G04 ================== begin FILE IDENTIFICATION RECORD ==================*
G04 Layout Name:  D:/<user>/Wistron_project/16317-1/gbr/16317-1.brd*
G04 Film Name:    TSILK*
G04 File Format:  Gerber RS274X*
G04 File Origin:  Cadence Allegro 16.5-S056*
G04 Origin Date:  Fri Jun 09 15:52:58 2017*
G04 *
G04 Layer:  VIA CLASS/FILMMASKTOP*
G04 Layer:  REF DES/ASSEMBLY_TOP*
G04 Layer:  PACKAGE GEOMETRY/SILKSCREEN_TOP*
G04 Layer:  DRAWING FORMAT/LAYER_PCB_STORY*
G04 Layer:  DRAWING FORMAT/LAYER_SILK_T*
G04 Layer:  BOARD GEOMETRY/SILKSCREEN_TOP*
G04 *
G04 Offset:    (0.00 0.00)*
G04 Mirror:    No*
G04 Mode:      Positive*
G04 Rotation:  0*
G04 FullContactRelief:  No*
G04 UndefLineWidth:     6.00*
G04 ================== end FILE IDENTIFICATION RECORD ====================*
%FSLAX35Y35*MOIN*%
%IR0*IPPOS*OFA0.00000B0.00000*MIA0B0*SFA1.00000B1.00000*%
%ADD10C,.026*%
%ADD11C,.01*%
%ADD12C,.02*%
%ADD13C,.03*%
%ADD14C,.012*%
%ADD15C,.013*%
%ADD16C,.015*%
%ADD17C,.025*%
%ADD18C,.018*%
%ADD19C,.019*%
%ADD20C,.002*%
%ADD21C,.006*%
%ADD22C,.008*%
%ADD24C,.123*%
%ADD23C,.15*%
G75*
%LPD*%
G75*
G36*
G01X90200Y97900D02*
Y109100D01*
X72800D01*
Y97900D01*
X90200D01*
G37*
G36*
G01X49800Y127100D02*
Y115900D01*
X67200D01*
Y127100D01*
X49800D01*
G37*
G36*
G01X90200Y550400D02*
Y561600D01*
X72800D01*
Y550400D01*
X90200D01*
G37*
G36*
G01X49800Y579600D02*
Y568400D01*
X67200D01*
Y579600D01*
X49800D01*
G37*
G36*
G01X90200Y1003400D02*
Y1014600D01*
X72800D01*
Y1003400D01*
X90200D01*
G37*
G36*
G01X49800Y1032600D02*
Y1021400D01*
X67200D01*
Y1032600D01*
X49800D01*
G37*
G36*
G01X123742Y51343D02*
X126242Y48843D01*
Y53843D01*
X123742Y51343D01*
G37*
G36*
G01X172300Y101600D02*
Y90400D01*
X189700D01*
Y101600D01*
X172300D01*
G37*
G36*
G01X138211Y28796D02*
Y36796D01*
X129111D01*
Y28796D01*
X138211D01*
G37*
G36*
G01X123742Y504099D02*
X126242Y501599D01*
Y506599D01*
X123742Y504099D01*
G37*
G36*
G01X173800Y579600D02*
Y568400D01*
X191200D01*
Y579600D01*
X173800D01*
G37*
G36*
G01X123742Y956855D02*
X126242Y954355D01*
Y959355D01*
X123742Y956855D01*
G37*
G36*
G01X174300Y1032600D02*
Y1021400D01*
X191700D01*
Y1032600D01*
X174300D01*
G37*
G36*
G01X192974Y1426400D02*
Y1415200D01*
X210374D01*
Y1426400D01*
X192974D01*
G37*
G36*
G01X113239Y1491160D02*
X116109D01*
Y1486040D01*
X113239D01*
Y1491160D01*
G37*
G36*
G01X247954Y51343D02*
X250454Y48843D01*
Y53843D01*
X247954Y51343D01*
G37*
G36*
G01X214200Y97900D02*
Y109100D01*
X196800D01*
Y97900D01*
X214200D01*
G37*
G36*
G01X247954Y504099D02*
X250454Y501599D01*
Y506599D01*
X247954Y504099D01*
G37*
G36*
G01X214200Y550400D02*
Y561600D01*
X196800D01*
Y550400D01*
X214200D01*
G37*
G36*
G01X247954Y956855D02*
X250454Y954355D01*
Y959355D01*
X247954Y956855D01*
G37*
G36*
G01X214700Y1003400D02*
Y1014600D01*
X197300D01*
Y1003400D01*
X214700D01*
G37*
G36*
G01X289535Y1329472D02*
G02X287535I-1000J0D01*
G01Y1331472D01*
G02X289535I1000J0D01*
G01Y1329472D01*
G37*
G36*
G01Y1319472D02*
G02X287535I-1000J0D01*
G01Y1321472D01*
G02X289535I1000J0D01*
G01Y1319472D01*
G37*
G36*
G01X235535Y1305772D02*
Y1320447D01*
X239035D01*
G03X254035I7500J25D01*
G01X260385D01*
G03X272685I6150J25D01*
G01X286435D01*
Y1316672D01*
X487855D01*
Y1354272D01*
X410835D01*
Y1360572D01*
X368635D01*
Y1354272D01*
X286435D01*
Y1320497D01*
X272685D01*
G03X260385I-6150J-25D01*
G01X254035D01*
G03X239035I-7500J-25D01*
G01X235535D01*
Y1335172D01*
X245535D01*
Y1365172D01*
X532535D01*
Y1335172D01*
X542535D01*
Y1305772D01*
X235535D01*
G37*
G36*
G01X289535Y1349472D02*
G02X287535I-1000J0D01*
G01Y1351472D01*
G02X289535I1000J0D01*
G01Y1349472D01*
G37*
G36*
G01Y1339472D02*
G02X287535I-1000J0D01*
G01Y1341472D01*
G02X289535I1000J0D01*
G01Y1339472D01*
G37*
G36*
G01X372167Y51343D02*
X374667Y48843D01*
Y53843D01*
X372167Y51343D01*
G37*
G36*
G01X338700Y97900D02*
Y109100D01*
X321300D01*
Y97900D01*
X338700D01*
G37*
G36*
G01X298300Y127100D02*
Y115900D01*
X315700D01*
Y127100D01*
X298300D01*
G37*
G36*
G01X372167Y504099D02*
X374667Y501599D01*
Y506599D01*
X372167Y504099D01*
G37*
G36*
G01X338700Y550400D02*
Y561600D01*
X321300D01*
Y550400D01*
X338700D01*
G37*
G36*
G01X298300Y579600D02*
Y568400D01*
X315700D01*
Y579600D01*
X298300D01*
G37*
G36*
G01X372167Y956855D02*
X374667Y954355D01*
Y959355D01*
X372167Y956855D01*
G37*
G36*
G01X338700Y1003400D02*
Y1014600D01*
X321300D01*
Y1003400D01*
X338700D01*
G37*
G36*
G01X298300Y1032600D02*
Y1021400D01*
X315700D01*
Y1032600D01*
X298300D01*
G37*
G36*
G01X424300Y62200D02*
Y51000D01*
X441700D01*
Y62200D01*
X424300D01*
G37*
G36*
G01X463100Y101500D02*
Y112700D01*
X445700D01*
Y101500D01*
X463100D01*
G37*
G36*
G01X462700Y550400D02*
Y561600D01*
X445300D01*
Y550400D01*
X462700D01*
G37*
G36*
G01X422300Y579600D02*
Y568400D01*
X439700D01*
Y579600D01*
X422300D01*
G37*
G36*
G01X462700Y1003400D02*
Y1014600D01*
X445300D01*
Y1003400D01*
X462700D01*
G37*
G36*
G01X422300Y1032600D02*
Y1021400D01*
X439700D01*
Y1032600D01*
X422300D01*
G37*
G36*
G01X496379Y51343D02*
X498879Y48843D01*
Y53843D01*
X496379Y51343D01*
G37*
G36*
G01X587200Y97900D02*
Y109100D01*
X569800D01*
Y97900D01*
X587200D01*
G37*
G36*
G01X546800Y127100D02*
Y115900D01*
X564200D01*
Y127100D01*
X546800D01*
G37*
G36*
G01X496379Y504099D02*
X498879Y501599D01*
Y506599D01*
X496379Y504099D01*
G37*
G36*
G01X587200Y550400D02*
Y561600D01*
X569800D01*
Y550400D01*
X587200D01*
G37*
G36*
G01X546800Y579600D02*
Y568400D01*
X564200D01*
Y579600D01*
X546800D01*
G37*
G36*
G01X496379Y956855D02*
X498879Y954355D01*
Y959355D01*
X496379Y956855D01*
G37*
G36*
G01X587200Y1003400D02*
Y1014600D01*
X569800D01*
Y1003400D01*
X587200D01*
G37*
G36*
G01X546800Y1032600D02*
Y1021400D01*
X564200D01*
Y1032600D01*
X546800D01*
G37*
G36*
G01X519235Y1422531D02*
Y1433731D01*
X501835D01*
Y1422531D01*
X519235D01*
G37*
G36*
G01X620592Y51343D02*
X623092Y48843D01*
Y53843D01*
X620592Y51343D01*
G37*
G36*
G01X669300Y101600D02*
Y90400D01*
X686700D01*
Y101600D01*
X669300D01*
G37*
G36*
G01X620592Y504099D02*
X623092Y501599D01*
Y506599D01*
X620592Y504099D01*
G37*
G36*
G01X670800Y579600D02*
Y568400D01*
X688200D01*
Y579600D01*
X670800D01*
G37*
G36*
G01X620592Y956855D02*
X623092Y954355D01*
Y959355D01*
X620592Y956855D01*
G37*
G36*
G01X670800Y1032600D02*
Y1021400D01*
X688200D01*
Y1032600D01*
X670800D01*
G37*
G36*
G01X662218Y1319042D02*
X664526Y1321350D01*
X659910D01*
X662218Y1319042D01*
G37*
G36*
G01X625182Y1386658D02*
X622874Y1384350D01*
X627490D01*
X625182Y1386658D01*
G37*
G36*
G01X744805Y51343D02*
X747305Y48843D01*
Y53843D01*
X744805Y51343D01*
G37*
G36*
G01X711200Y97900D02*
Y109100D01*
X693800D01*
Y97900D01*
X711200D01*
G37*
G36*
G01X744805Y504099D02*
X747305Y501599D01*
Y506599D01*
X744805Y504099D01*
G37*
G36*
G01X711200Y550400D02*
Y561600D01*
X693800D01*
Y550400D01*
X711200D01*
G37*
G36*
G01X744805Y956855D02*
X747305Y954355D01*
Y959355D01*
X744805Y956855D01*
G37*
G36*
G01X711200Y1003400D02*
Y1014600D01*
X693800D01*
Y1003400D01*
X711200D01*
G37*
G36*
G01X681150Y1439650D02*
X676150Y1444650D01*
Y1439650D01*
X681150D01*
G37*
G36*
G01X739197Y1477094D02*
X742067D01*
Y1471974D01*
X739197D01*
Y1477094D01*
G37*
G36*
G01X862916Y249192D02*
G02X861316I-800J0D01*
G01Y250792D01*
G02X862916I800J0D01*
G01Y249192D01*
G37*
G36*
G01X855830D02*
G02X854230I-800J0D01*
G01Y250792D01*
G02X855830I800J0D01*
G01Y249192D01*
G37*
G36*
G01X848744D02*
G02X847144I-800J0D01*
G01Y250792D01*
G02X848744I800J0D01*
G01Y249192D01*
G37*
G36*
G01X841658D02*
G02X840058I-800J0D01*
G01Y250792D01*
G02X841658I800J0D01*
G01Y249192D01*
G37*
G36*
G01X828172D02*
G02X826572I-800J0D01*
G01Y250792D01*
G02X828172I800J0D01*
G01Y249192D01*
G37*
G36*
G01X834572D02*
G02X832972I-800J0D01*
G01Y250792D01*
G02X834572I800J0D01*
G01Y249192D01*
G37*
G36*
G01X913772Y248031D02*
Y251637D01*
X914111D01*
Y317654D01*
X889572D01*
Y323392D01*
X848872D01*
Y317654D01*
X823072D01*
Y324992D01*
X917172D01*
Y248031D01*
X913772D01*
G37*
G36*
G01X841190Y648810D02*
Y679570D01*
X855790D01*
Y648810D01*
X841190D01*
G37*
G36*
G01X851600Y774380D02*
Y743620D01*
X837000D01*
Y774380D01*
X851600D01*
G37*
G36*
G01X856800Y886380D02*
Y855620D01*
X842200D01*
Y886380D01*
X856800D01*
G37*
G36*
G01X842700Y808620D02*
Y839380D01*
X857300D01*
Y808620D01*
X842700D01*
G37*
G36*
G01X828850Y944130D02*
X798090D01*
Y958730D01*
X828850D01*
Y944130D01*
G37*
G36*
G01X815631Y1303285D02*
Y1306685D01*
X813931Y1304985D01*
X815631Y1303285D01*
G37*
G36*
G01X816101Y1345791D02*
Y1349191D01*
X814401Y1347491D01*
X816101Y1345791D01*
G37*
G36*
G01X815880Y1383459D02*
Y1386859D01*
X814180Y1385159D01*
X815880Y1383459D01*
G37*
G36*
G01X912518Y249192D02*
G02X910918I-800J0D01*
G01Y250792D01*
G02X912518I800J0D01*
G01Y249192D01*
G37*
G36*
G01X905432D02*
G02X903832I-800J0D01*
G01Y250792D01*
G02X905432I800J0D01*
G01Y249192D01*
G37*
G36*
G01X898346D02*
G02X896746I-800J0D01*
G01Y250792D01*
G02X898346I800J0D01*
G01Y249192D01*
G37*
G36*
G01X891260D02*
G02X889660I-800J0D01*
G01Y250792D01*
G02X891260I800J0D01*
G01Y249192D01*
G37*
G36*
G01X877088D02*
G02X875488I-800J0D01*
G01Y250792D01*
G02X877088I800J0D01*
G01Y249192D01*
G37*
G36*
G01X870002D02*
G02X868402I-800J0D01*
G01Y250792D01*
G02X870002I800J0D01*
G01Y249192D01*
G37*
G36*
G01X929200Y768420D02*
Y799180D01*
X943800D01*
Y768420D01*
X929200D01*
G37*
G36*
G01X918920Y884164D02*
X888160D01*
Y898764D01*
X918920D01*
Y884164D01*
G37*
G36*
G01X945570Y879130D02*
Y865130D01*
X964570D01*
Y879130D01*
X945570D01*
G37*
G36*
G01X902200Y1194680D02*
Y1220320D01*
X916800D01*
Y1194680D01*
X902200D01*
G37*
G36*
G01X945782Y1328458D02*
X943474Y1326150D01*
X948090D01*
X945782Y1328458D01*
G37*
G36*
G01X967307Y268218D02*
G02X969307I1000J0D01*
G01Y267218D01*
G02X967307I-1000J0D01*
G01Y268218D01*
G37*
G36*
G01Y262312D02*
G02X969307I1000J0D01*
G01Y261312D01*
G02X967307I-1000J0D01*
G01Y262312D01*
G37*
G36*
G01Y284950D02*
G02X969307I1000J0D01*
G01Y283950D01*
G02X967307I-1000J0D01*
G01Y284950D01*
G37*
G36*
G01Y279044D02*
G02X969307I1000J0D01*
G01Y278044D01*
G02X967307I-1000J0D01*
G01Y279044D01*
G37*
G36*
G01Y256406D02*
G02X969307I1000J0D01*
G01Y255406D01*
G02X967307I-1000J0D01*
G01Y256406D01*
G37*
G36*
G01X1051907Y325006D02*
Y248032D01*
X964907D01*
Y325006D01*
X987307D01*
Y316393D01*
X966307D01*
Y252506D01*
X1046707D01*
Y316393D01*
X1031307D01*
Y325006D01*
X1051907D01*
G37*
G36*
G01X967307Y290856D02*
G02X969307I1000J0D01*
G01Y289856D01*
G02X967307I-1000J0D01*
G01Y290856D01*
G37*
G36*
G01Y313494D02*
G02X969307I1000J0D01*
G01Y312494D01*
G02X967307I-1000J0D01*
G01Y313494D01*
G37*
G36*
G01Y307588D02*
G02X969307I1000J0D01*
G01Y306588D01*
G02X967307I-1000J0D01*
G01Y307588D01*
G37*
G36*
G01Y301682D02*
G02X969307I1000J0D01*
G01Y300682D01*
G02X967307I-1000J0D01*
G01Y301682D01*
G37*
G36*
G01X974421Y554271D02*
Y545271D01*
X966421D01*
Y554271D01*
X974421D01*
G37*
G36*
G01X972063Y528157D02*
Y519157D01*
X964063D01*
Y528157D01*
X972063D01*
G37*
G36*
G01X990320Y849450D02*
Y860650D01*
X972920D01*
Y849450D01*
X990320D01*
G37*
G36*
G01X1002200Y874230D02*
Y860230D01*
X1021200D01*
Y874230D01*
X1002200D01*
G37*
G36*
G01X968850Y1214350D02*
X963850Y1219350D01*
X968850D01*
Y1214350D01*
G37*
G36*
G01X1034118Y1310689D02*
Y1314089D01*
X1032418Y1312389D01*
X1034118Y1310689D01*
G37*
G36*
G01X988593Y1427549D02*
X983593Y1432549D01*
Y1427549D01*
X988593D01*
G37*
G36*
G01X1034118Y1366289D02*
Y1369689D01*
X1032418Y1367989D01*
X1034118Y1366289D01*
G37*
G36*
G01Y1338489D02*
Y1341889D01*
X1032418Y1340189D01*
X1034118Y1338489D01*
G37*
G36*
G01X1051505Y1480789D02*
X1053505D01*
Y1482789D01*
X1051505D01*
Y1480789D01*
G37*
G36*
G01X1084389Y518757D02*
G02Y521357I0J1300D01*
G01X1087389D01*
G02Y518757I0J-1300D01*
G01X1084389D01*
G37*
G36*
G01Y525844D02*
G02Y528444I0J1300D01*
G01X1087389D01*
G02Y525844I0J-1300D01*
G01X1084389D01*
G37*
G36*
G01Y532930D02*
G02Y535530I0J1300D01*
G01X1087389D01*
G02Y532930I0J-1300D01*
G01X1084389D01*
G37*
G36*
G01Y540017D02*
G02Y542617I0J1300D01*
G01X1087389D01*
G02Y540017I0J-1300D01*
G01X1084389D01*
G37*
G36*
G01Y547103D02*
G02Y549703I0J1300D01*
G01X1087389D01*
G02Y547103I0J-1300D01*
G01X1084389D01*
G37*
G36*
G01Y554190D02*
G02Y556790I0J1300D01*
G01X1087389D01*
G02Y554190I0J-1300D01*
G01X1084389D01*
G37*
G36*
G01Y561276D02*
G02Y563876I0J1300D01*
G01X1087389D01*
G02Y561276I0J-1300D01*
G01X1084389D01*
G37*
G36*
G01Y568363D02*
G02Y570963I0J1300D01*
G01X1087389D01*
G02Y568363I0J-1300D01*
G01X1084389D01*
G37*
G36*
G01X1082015Y577163D02*
X1133245D01*
Y572163D01*
X1082215D01*
Y517557D01*
X1141615D01*
Y559863D01*
X1136109D01*
Y572163D01*
X1133255D01*
Y577163D01*
X1143515D01*
Y569463D01*
X1141215D01*
Y565263D01*
X1143515D01*
Y510263D01*
X1082015D01*
Y577163D01*
G37*
G36*
G01X1092215Y685742D02*
G02Y687742I0J1000D01*
G01X1093215D01*
G02Y685742I0J-1000D01*
G01X1092215D01*
G37*
G36*
G01X1097215D02*
G02Y687742I0J1000D01*
G01X1098215D01*
G02Y685742I0J-1000D01*
G01X1097215D01*
G37*
G36*
G01X1102215D02*
G02Y687742I0J1000D01*
G01X1103215D01*
G02Y685742I0J-1000D01*
G01X1102215D01*
G37*
G36*
G01X1107215D02*
G02Y687742I0J1000D01*
G01X1108215D01*
G02Y685742I0J-1000D01*
G01X1107215D01*
G37*
G36*
G01X1112215D02*
G02Y687742I0J1000D01*
G01X1113215D01*
G02Y685742I0J-1000D01*
G01X1112215D01*
G37*
G36*
G01X1117215D02*
G02Y687742I0J1000D01*
G01X1118215D01*
G02Y685742I0J-1000D01*
G01X1117215D01*
G37*
G36*
G01X1122215D02*
G02Y687742I0J1000D01*
G01X1123215D01*
G02Y685742I0J-1000D01*
G01X1122215D01*
G37*
G36*
G01X1127215D02*
G02Y687742I0J1000D01*
G01X1128215D01*
G02Y685742I0J-1000D01*
G01X1127215D01*
G37*
G36*
G01X1132215D02*
G02Y687742I0J1000D01*
G01X1133215D01*
G02Y685742I0J-1000D01*
G01X1132215D01*
G37*
G36*
G01X1082015Y947392D02*
X1143515D01*
Y938242D01*
X1140715D01*
Y934242D01*
X1143515D01*
Y837242D01*
X1136109D01*
Y942242D01*
X1088589D01*
Y684742D01*
X1136109D01*
Y794242D01*
X1143515D01*
Y682292D01*
X1082015D01*
Y947392D01*
G37*
G36*
G01X1095426Y1119240D02*
G02Y1120840I0J800D01*
G01X1096226D01*
G02Y1119240I0J-800D01*
G01X1095426D01*
G37*
G36*
G01Y1131838D02*
G02Y1133438I0J800D01*
G01X1096226D01*
G02Y1131838I0J-800D01*
G01X1095426D01*
G37*
G36*
G01X1093726Y1138338D02*
X1129730D01*
Y1136038D01*
X1094326D01*
Y1116640D01*
X1129730D01*
Y1114338D01*
X1093726D01*
Y1138338D01*
G37*
G36*
G01X1111950Y1308100D02*
Y1291300D01*
X1098000D01*
Y1308100D01*
X1111950D01*
G37*
G36*
G01X1112762Y1381923D02*
X1117762Y1376923D01*
X1112762D01*
Y1381923D01*
G37*
G36*
G01X1112300Y1348915D02*
X1113700Y1350315D01*
X1110900D01*
X1112300Y1348915D01*
G37*
G36*
G01X1197112Y1401293D02*
Y1375653D01*
X1182512D01*
Y1401293D01*
X1197112D01*
G37*
G36*
G01X1294411Y51343D02*
X1296911Y48843D01*
Y53843D01*
X1294411Y51343D01*
G37*
G36*
G01X1315700Y86400D02*
Y97600D01*
X1298300D01*
Y86400D01*
X1315700D01*
G37*
G36*
G01X1316800Y135600D02*
Y124400D01*
X1334200D01*
Y135600D01*
X1316800D01*
G37*
G36*
G01X1294411Y504099D02*
X1296911Y501599D01*
Y506599D01*
X1294411Y504099D01*
G37*
G36*
G01X1324100Y555700D02*
X1312900D01*
Y538300D01*
X1324100D01*
Y555700D01*
G37*
G36*
G01X1317300Y588600D02*
Y577400D01*
X1334700D01*
Y588600D01*
X1317300D01*
G37*
G36*
G01X1294411Y956855D02*
X1296911Y954355D01*
Y959355D01*
X1294411Y956855D01*
G37*
G36*
G01X1324100Y1008200D02*
X1312900D01*
Y990800D01*
X1324100D01*
Y1008200D01*
G37*
G36*
G01X1317300Y1041100D02*
Y1029900D01*
X1334700D01*
Y1041100D01*
X1317300D01*
G37*
G36*
G01X1331900Y1426300D02*
Y1415100D01*
X1349300D01*
Y1426300D01*
X1331900D01*
G37*
G36*
G01X1259539Y1495960D02*
X1262409D01*
Y1490840D01*
X1259539D01*
Y1495960D01*
G37*
G36*
G01X1418624Y51343D02*
X1421124Y48843D01*
Y53843D01*
X1418624Y51343D01*
G37*
G36*
G01Y504099D02*
X1421124Y501599D01*
Y506599D01*
X1418624Y504099D01*
G37*
G36*
G01Y956855D02*
X1421124Y954355D01*
Y959355D01*
X1418624Y956855D01*
G37*
G36*
G01X1448100Y102700D02*
X1436900D01*
Y85300D01*
X1448100D01*
Y102700D01*
G37*
G36*
G01X1441300Y135600D02*
Y124400D01*
X1458700D01*
Y135600D01*
X1441300D01*
G37*
G36*
G01X1448100Y555700D02*
X1436900D01*
Y538300D01*
X1448100D01*
Y555700D01*
G37*
G36*
G01X1441300Y588600D02*
Y577400D01*
X1458700D01*
Y588600D01*
X1441300D01*
G37*
G36*
G01X1448100Y1008200D02*
X1436900D01*
Y990800D01*
X1448100D01*
Y1008200D01*
G37*
G36*
G01X1441300Y1041100D02*
Y1029900D01*
X1458700D01*
Y1041100D01*
X1441300D01*
G37*
G36*
G01X1518627Y1291714D02*
X1518688Y1291227D01*
X1518748Y1291167D01*
X1518809Y1290437D01*
X1518870Y1290376D01*
X1518931Y1289585D01*
X1518992Y1289524D01*
X1519053Y1288794D01*
X1519113Y1288734D01*
X1519174Y1288004D01*
X1519235Y1287943D01*
X1519296Y1287213D01*
X1519357Y1287152D01*
X1519417Y1286422D01*
X1519478Y1286362D01*
X1519539Y1285571D01*
X1519600Y1285510D01*
X1519661Y1284780D01*
X1519722Y1284720D01*
X1519782Y1283990D01*
X1519843Y1283929D01*
X1519904Y1283199D01*
X1519965Y1283138D01*
X1520026Y1282409D01*
X1520087Y1282348D01*
X1520147Y1281618D01*
X1520208Y1281557D01*
X1520269Y1280767D01*
X1520330Y1280706D01*
X1520391Y1279976D01*
X1520452Y1279915D01*
X1520512Y1279489D01*
X1524952D01*
X1525135Y1279732D01*
X1525256Y1280037D01*
X1525439Y1280280D01*
X1525560Y1280584D01*
X1525743Y1280827D01*
X1525804Y1281009D01*
X1525986Y1281253D01*
X1526107Y1281557D01*
X1526290Y1281800D01*
X1526412Y1282104D01*
X1526594Y1282348D01*
X1526716Y1282652D01*
X1526898Y1282895D01*
X1526959Y1283078D01*
X1527141Y1283321D01*
X1527263Y1283625D01*
X1527446Y1283868D01*
X1527567Y1284172D01*
X1527750Y1284415D01*
X1527871Y1284720D01*
X1528054Y1284963D01*
X1528176Y1285267D01*
X1528358Y1285510D01*
X1528419Y1285693D01*
X1528601Y1285936D01*
X1528723Y1286240D01*
X1528905Y1286483D01*
X1529027Y1286787D01*
X1529209Y1287031D01*
Y1287092D01*
X1529331Y1287213D01*
X1529392Y1287152D01*
X1529453Y1286057D01*
X1529513Y1285997D01*
X1529574Y1284902D01*
X1529635Y1284841D01*
X1529696Y1283746D01*
X1529757Y1283686D01*
X1529818Y1282530D01*
X1529878Y1282469D01*
X1529939Y1281374D01*
X1530000Y1281314D01*
X1530061Y1280219D01*
X1530122Y1280158D01*
X1530182Y1279489D01*
X1534622D01*
X1534744Y1279793D01*
X1534926Y1280037D01*
X1534987Y1280219D01*
X1535170Y1280462D01*
X1535230Y1280645D01*
X1535413Y1280888D01*
X1535474Y1281070D01*
X1535656Y1281314D01*
X1535778Y1281618D01*
X1535960Y1281861D01*
X1536021Y1282044D01*
X1536204Y1282287D01*
X1536265Y1282469D01*
X1536447Y1282713D01*
X1536507Y1282895D01*
X1536690Y1283138D01*
X1536751Y1283321D01*
X1536933Y1283564D01*
X1536994Y1283746D01*
X1537177Y1283990D01*
X1537237Y1284172D01*
X1537420Y1284415D01*
X1537481Y1284598D01*
X1537663Y1284841D01*
X1537724Y1285024D01*
X1537907Y1285267D01*
X1538028Y1285571D01*
X1538211Y1285814D01*
X1538271Y1285997D01*
X1538454Y1286240D01*
X1538515Y1286422D01*
X1538697Y1286666D01*
X1538758Y1286848D01*
X1538941Y1287092D01*
X1539001Y1287274D01*
X1539184Y1287517D01*
X1539244Y1287700D01*
X1539427Y1287943D01*
X1539488Y1288126D01*
X1539670Y1288369D01*
X1539731Y1288551D01*
X1539913Y1288794D01*
X1539974Y1288977D01*
X1540157Y1289220D01*
X1540278Y1289524D01*
X1540461Y1289768D01*
X1540522Y1289950D01*
X1540704Y1290193D01*
X1540765Y1290376D01*
X1540948Y1290619D01*
X1541008Y1290802D01*
X1541191Y1291045D01*
X1541252Y1291227D01*
X1541434Y1291470D01*
X1541495Y1291653D01*
X1541677Y1291896D01*
X1541738Y1292079D01*
X1541920Y1292322D01*
Y1292383D01*
X1541981Y1292444D01*
X1536872D01*
X1536812Y1292200D01*
X1536569Y1291775D01*
X1536507Y1291531D01*
X1536325Y1291227D01*
X1536265Y1290984D01*
X1536143Y1290802D01*
X1536082Y1290558D01*
X1535900Y1290254D01*
X1535839Y1290011D01*
X1535656Y1289707D01*
X1535595Y1289463D01*
X1535474Y1289281D01*
X1535413Y1289038D01*
X1535230Y1288734D01*
X1535170Y1288491D01*
X1534987Y1288186D01*
X1534926Y1287943D01*
X1534805Y1287761D01*
X1534744Y1287517D01*
X1534561Y1287213D01*
X1534501Y1286970D01*
X1534318Y1286666D01*
X1534257Y1286422D01*
X1534136Y1286240D01*
X1534075Y1285997D01*
X1533893Y1285693D01*
X1533831Y1285450D01*
X1533649Y1285145D01*
X1533588Y1284902D01*
X1533467Y1284720D01*
X1533406Y1284476D01*
X1533284Y1284355D01*
X1533224Y1284415D01*
X1533163Y1285632D01*
X1533102Y1285693D01*
X1533041Y1286970D01*
X1532980Y1287031D01*
X1532919Y1288308D01*
X1532859Y1288369D01*
X1532798Y1289707D01*
X1532737Y1289768D01*
X1532676Y1291045D01*
X1532615Y1291106D01*
X1532554Y1292383D01*
X1532494Y1292444D01*
X1527993D01*
X1527811Y1292018D01*
X1527628Y1291775D01*
X1527446Y1291349D01*
X1527263Y1291106D01*
X1527081Y1290680D01*
X1526898Y1290437D01*
X1526716Y1290011D01*
X1526533Y1289768D01*
X1526412Y1289463D01*
X1526229Y1289220D01*
X1526047Y1288794D01*
X1525864Y1288551D01*
X1525682Y1288126D01*
X1525499Y1287882D01*
X1525378Y1287578D01*
X1525195Y1287335D01*
X1525013Y1286909D01*
X1524830Y1286666D01*
X1524648Y1286240D01*
X1524465Y1285997D01*
X1524283Y1285571D01*
X1524100Y1285328D01*
X1523979Y1285024D01*
X1523796Y1284780D01*
X1523614Y1284355D01*
X1523493Y1284233D01*
X1523431Y1284294D01*
X1523371Y1286240D01*
X1523310Y1286301D01*
X1523249Y1288308D01*
X1523188Y1288369D01*
X1523128Y1290376D01*
X1523067Y1290437D01*
X1523006Y1292444D01*
X1518505D01*
X1518627Y1291714D01*
G37*
G36*
G01X1503008Y1419311D02*
Y1395689D01*
X1628992D01*
Y1419311D01*
X1503008D01*
G37*
G36*
G01X1542836Y51343D02*
X1545336Y48843D01*
Y53843D01*
X1542836Y51343D01*
G37*
G36*
G01X1565200Y86400D02*
Y97600D01*
X1547800D01*
Y86400D01*
X1565200D01*
G37*
G36*
G01X1574800Y124800D02*
X1586000D01*
Y142200D01*
X1574800D01*
Y124800D01*
G37*
G36*
G01X1542836Y504099D02*
X1545336Y501599D01*
Y506599D01*
X1542836Y504099D01*
G37*
G36*
G01X1572600Y555700D02*
X1561400D01*
Y538300D01*
X1572600D01*
Y555700D01*
G37*
G36*
G01X1565800Y588600D02*
Y577400D01*
X1583200D01*
Y588600D01*
X1565800D01*
G37*
G36*
G01X1542836Y956855D02*
X1545336Y954355D01*
Y959355D01*
X1542836Y956855D01*
G37*
G36*
G01X1572600Y1008200D02*
X1561400D01*
Y990800D01*
X1572600D01*
Y1008200D01*
G37*
G36*
G01X1565800Y1041100D02*
Y1029900D01*
X1583200D01*
Y1041100D01*
X1565800D01*
G37*
G36*
G01X1620985Y1294937D02*
X1621107Y1294694D01*
X1620560D01*
X1620499Y1294755D01*
X1620317Y1295180D01*
X1620134Y1295424D01*
Y1295545D01*
X1619952Y1295606D01*
X1619526Y1295667D01*
Y1294694D01*
X1619100D01*
Y1296490D01*
X1619526D01*
Y1296032D01*
X1619830D01*
X1620438Y1296093D01*
X1620499Y1296275D01*
X1620438Y1296640D01*
X1620256D01*
X1620195Y1296701D01*
X1619526D01*
Y1296491D01*
X1619100D01*
Y1297066D01*
X1620256D01*
X1620620Y1297005D01*
X1620864Y1296822D01*
X1620925Y1296580D01*
X1620985Y1296519D01*
X1620925Y1296154D01*
X1620681Y1295850D01*
X1620438Y1295789D01*
X1620377Y1295728D01*
X1620499Y1295606D01*
X1620560D01*
X1620620Y1295545D01*
X1620742Y1295363D01*
X1620803Y1295180D01*
X1620985Y1294937D01*
G37*
G36*
G01X1621472Y1294207D02*
X1621168Y1293964D01*
X1620925Y1293903D01*
X1620742Y1293781D01*
X1619708Y1293721D01*
X1619648Y1293781D01*
X1619283Y1293843D01*
X1618918Y1294025D01*
X1618674Y1294207D01*
X1618249Y1294694D01*
X1618006Y1295180D01*
X1617944Y1296093D01*
X1617945Y1296099D01*
X1618330D01*
X1618309Y1295910D01*
X1618370Y1295302D01*
X1618492Y1295059D01*
X1618735Y1294755D01*
Y1294694D01*
X1619161Y1294329D01*
X1619404Y1294207D01*
X1619830Y1294146D01*
X1619891Y1294086D01*
X1620620Y1294146D01*
X1620681Y1294207D01*
X1620925Y1294268D01*
X1621290Y1294572D01*
X1621715Y1295059D01*
X1621776Y1295302D01*
X1621837Y1295363D01*
X1621898Y1295789D01*
X1621837Y1296397D01*
X1621776Y1296458D01*
X1621715Y1296701D01*
X1621411Y1297066D01*
Y1297187D01*
X1621290D01*
X1620925Y1297492D01*
X1620803D01*
X1620742Y1297552D01*
X1620377Y1297613D01*
X1620317Y1297674D01*
X1619587Y1297613D01*
X1619526Y1297552D01*
X1619283Y1297492D01*
X1619039Y1297309D01*
X1618978D01*
X1618553Y1296822D01*
X1618370Y1296458D01*
X1618330Y1296100D01*
X1617945D01*
X1618006Y1296580D01*
X1618249Y1297066D01*
X1618431Y1297309D01*
X1618918Y1297735D01*
X1619283Y1297917D01*
X1619648Y1297978D01*
X1619708Y1298039D01*
X1620499D01*
X1620560Y1297978D01*
X1620925Y1297917D01*
X1621168Y1297796D01*
X1621472Y1297552D01*
X1621533D01*
X1621959Y1297066D01*
X1622080Y1296822D01*
X1622141Y1296580D01*
X1622202Y1296519D01*
X1622263Y1295424D01*
X1622202Y1295363D01*
X1622141Y1295059D01*
X1621959Y1294694D01*
X1621533Y1294207D01*
X1621472D01*
G37*
G36*
G01X1613687Y1292687D02*
X1612957Y1292626D01*
X1612896Y1292565D01*
X1612471Y1292504D01*
X1612410Y1292444D01*
X1612106Y1292383D01*
X1611924Y1292261D01*
X1611680Y1292200D01*
X1611072Y1291896D01*
X1610768Y1291653D01*
X1610707D01*
X1610342Y1291349D01*
X1610281D01*
X1609369Y1290437D01*
X1609308Y1290497D01*
X1609369Y1290923D01*
X1609430Y1290984D01*
X1609491Y1291470D01*
X1609552Y1291531D01*
X1609612Y1292018D01*
X1609673Y1292079D01*
X1609734Y1292383D01*
Y1292444D01*
X1605112D01*
X1605051Y1292383D01*
X1604990Y1291896D01*
X1604929Y1291835D01*
X1604869Y1291288D01*
X1604807Y1291227D01*
X1604747Y1290741D01*
X1604686Y1290680D01*
X1604625Y1290193D01*
X1604564Y1290133D01*
X1604504Y1289585D01*
X1604443Y1289524D01*
X1604382Y1289038D01*
X1604321Y1288977D01*
X1604260Y1288491D01*
X1604199Y1288430D01*
X1604139Y1287943D01*
X1604078Y1287882D01*
X1604017Y1287335D01*
X1603956Y1287274D01*
X1603895Y1286787D01*
X1603835Y1286727D01*
X1603774Y1286240D01*
X1603713Y1286179D01*
X1603652Y1285632D01*
X1603591Y1285571D01*
X1603530Y1285085D01*
X1603470Y1285024D01*
X1603409Y1284537D01*
X1603348Y1284476D01*
X1603287Y1283929D01*
X1603226Y1283868D01*
X1603165Y1283381D01*
X1603105Y1283321D01*
X1603044Y1282834D01*
X1602983Y1282773D01*
X1602922Y1282287D01*
X1602861Y1282226D01*
X1602800Y1281679D01*
X1602740Y1281618D01*
X1602679Y1281131D01*
X1602618Y1281070D01*
X1602557Y1280584D01*
X1602496Y1280523D01*
X1602436Y1279976D01*
X1602375Y1279915D01*
X1602314Y1279489D01*
X1607301D01*
X1607362Y1279854D01*
X1607423Y1279915D01*
X1607483Y1280462D01*
X1607544Y1280523D01*
X1607605Y1281009D01*
X1607666Y1281070D01*
X1607727Y1281557D01*
X1607788Y1281618D01*
X1607848Y1282104D01*
X1607909Y1282165D01*
X1607970Y1282652D01*
X1608031Y1282713D01*
X1608092Y1283260D01*
X1608153Y1283321D01*
X1608213Y1283807D01*
X1608274Y1283868D01*
X1608335Y1284355D01*
X1608396Y1284415D01*
X1608457Y1284902D01*
X1608518Y1284963D01*
X1608578Y1285450D01*
X1608639Y1285510D01*
X1608700Y1285936D01*
X1608761Y1285997D01*
X1608822Y1286301D01*
X1608883Y1286362D01*
X1608943Y1286605D01*
X1609004Y1286666D01*
X1609065Y1286909D01*
X1609126Y1286970D01*
X1609187Y1287213D01*
X1609369Y1287456D01*
X1609430Y1287639D01*
X1609673Y1287943D01*
Y1288004D01*
X1610099Y1288491D01*
X1610160D01*
X1610585Y1288855D01*
X1610950Y1289038D01*
X1611437Y1289098D01*
X1611498Y1289159D01*
X1612106Y1289098D01*
X1612349Y1288916D01*
X1612471D01*
Y1288794D01*
X1612593Y1288673D01*
X1612653Y1288308D01*
X1612714Y1288247D01*
X1612653Y1287517D01*
X1612593Y1287456D01*
X1612531Y1286848D01*
X1612471Y1286787D01*
X1612410Y1286240D01*
X1612349Y1286179D01*
X1612288Y1285693D01*
X1612228Y1285632D01*
X1612167Y1285085D01*
X1612106Y1285024D01*
X1612045Y1284537D01*
X1611984Y1284476D01*
X1611924Y1283990D01*
X1611863Y1283929D01*
X1611802Y1283381D01*
X1611741Y1283321D01*
X1611680Y1282834D01*
X1611619Y1282773D01*
X1611559Y1282226D01*
X1611498Y1282165D01*
X1611437Y1281679D01*
X1611376Y1281618D01*
X1611315Y1281131D01*
X1611254Y1281070D01*
X1611194Y1280523D01*
X1611133Y1280462D01*
X1611072Y1279976D01*
X1611011Y1279915D01*
X1610950Y1279489D01*
X1615937D01*
X1615998Y1279976D01*
X1616059Y1280037D01*
X1616120Y1280523D01*
X1616181Y1280584D01*
X1616242Y1281131D01*
X1616302Y1281192D01*
X1616363Y1281679D01*
X1616424Y1281739D01*
X1616485Y1282287D01*
X1616546Y1282348D01*
X1616607Y1282834D01*
X1616667Y1282895D01*
X1616728Y1283381D01*
X1616789Y1283443D01*
X1616850Y1283990D01*
X1616911Y1284050D01*
X1616971Y1284537D01*
X1617032Y1284598D01*
X1617093Y1285145D01*
X1617154Y1285206D01*
X1617215Y1285693D01*
X1617276Y1285754D01*
X1617336Y1286301D01*
X1617397Y1286362D01*
X1617458Y1286848D01*
X1617519Y1286909D01*
X1617580Y1287456D01*
X1617641Y1287517D01*
X1617701Y1288126D01*
X1617762Y1288186D01*
X1617823Y1288916D01*
X1617884Y1288977D01*
X1617823Y1290558D01*
X1617762Y1290619D01*
X1617701Y1290862D01*
X1617641Y1290923D01*
Y1291045D01*
X1617458Y1291288D01*
Y1291349D01*
X1617032Y1291835D01*
X1616546Y1292261D01*
X1616059Y1292504D01*
X1615755Y1292565D01*
X1615694Y1292626D01*
X1615086Y1292687D01*
X1615025Y1292748D01*
X1613748D01*
X1613687Y1292687D01*
G37*
G36*
G01X1598239D02*
X1597509Y1292626D01*
X1597448Y1292565D01*
X1597083Y1292504D01*
X1597023Y1292444D01*
X1596719Y1292383D01*
X1596658Y1292322D01*
X1596415Y1292261D01*
X1596354Y1292200D01*
X1596111Y1292139D01*
X1595867Y1292018D01*
X1595624Y1291835D01*
X1595563D01*
X1595259Y1291592D01*
X1595198D01*
X1594712Y1291167D01*
X1594651D01*
X1593982Y1290497D01*
X1593921Y1290558D01*
X1593982Y1291045D01*
X1594043Y1291106D01*
X1594104Y1291592D01*
X1594164Y1291653D01*
X1594225Y1292139D01*
X1594286Y1292200D01*
Y1292444D01*
X1589664D01*
X1589603Y1292018D01*
X1589542Y1291957D01*
X1589481Y1291410D01*
X1589420Y1291349D01*
X1589359Y1290862D01*
X1589299Y1290802D01*
X1589238Y1290315D01*
X1589177Y1290254D01*
X1589116Y1289707D01*
X1589056Y1289646D01*
X1588994Y1289159D01*
X1588934Y1289098D01*
X1588873Y1288612D01*
X1588812Y1288551D01*
X1588751Y1288065D01*
X1588691Y1288004D01*
X1588630Y1287456D01*
X1588569Y1287396D01*
X1588508Y1286909D01*
X1588447Y1286848D01*
X1588387Y1286362D01*
X1588326Y1286301D01*
X1588265Y1285754D01*
X1588204Y1285693D01*
X1588143Y1285206D01*
X1588082Y1285145D01*
X1588022Y1284659D01*
X1587961Y1284598D01*
X1587900Y1284050D01*
X1587839Y1283990D01*
X1587778Y1283503D01*
X1587717Y1283443D01*
X1587657Y1282956D01*
X1587596Y1282895D01*
X1587535Y1282409D01*
X1587474Y1282348D01*
X1587413Y1281800D01*
X1587352Y1281739D01*
X1587292Y1281253D01*
X1587231Y1281192D01*
X1587170Y1280706D01*
X1587109Y1280645D01*
X1587048Y1280097D01*
X1586987Y1280037D01*
X1586927Y1279550D01*
X1586866Y1279489D01*
X1591914D01*
X1591975Y1280037D01*
X1592035Y1280097D01*
X1592096Y1280584D01*
X1592157Y1280645D01*
X1592218Y1281131D01*
X1592279Y1281192D01*
X1592340Y1281679D01*
X1592400Y1281739D01*
X1592461Y1282226D01*
X1592522Y1282287D01*
X1592583Y1282834D01*
X1592644Y1282895D01*
X1592705Y1283381D01*
X1592765Y1283443D01*
X1592826Y1283929D01*
X1592887Y1283990D01*
X1592948Y1284476D01*
X1593009Y1284537D01*
X1593070Y1285024D01*
X1593130Y1285085D01*
X1593191Y1285571D01*
X1593252Y1285632D01*
X1593313Y1285997D01*
X1593374Y1286057D01*
X1593434Y1286362D01*
X1593495Y1286422D01*
X1593556Y1286727D01*
X1593982Y1287578D01*
X1594225Y1287882D01*
Y1287943D01*
X1594772Y1288551D01*
X1595076Y1288794D01*
X1595563Y1289038D01*
X1596050Y1289098D01*
X1596111Y1289159D01*
X1596719Y1289098D01*
X1597083Y1288794D01*
X1597205Y1288612D01*
X1597266Y1288126D01*
X1597205Y1287335D01*
X1597144Y1287274D01*
X1597083Y1286727D01*
X1597023Y1286666D01*
X1596962Y1286119D01*
X1596901Y1286057D01*
X1596840Y1285510D01*
X1596780Y1285450D01*
X1596719Y1284963D01*
X1596658Y1284902D01*
X1596597Y1284355D01*
X1596536Y1284294D01*
X1596475Y1283807D01*
X1596415Y1283746D01*
X1596354Y1283260D01*
X1596293Y1283199D01*
X1596232Y1282652D01*
X1596171Y1282591D01*
X1596111Y1282104D01*
X1596050Y1282044D01*
X1595989Y1281496D01*
X1595928Y1281435D01*
X1595867Y1280949D01*
X1595806Y1280888D01*
X1595746Y1280402D01*
X1595685Y1280341D01*
X1595624Y1279793D01*
X1595563Y1279732D01*
Y1279489D01*
X1600489D01*
X1600550Y1279793D01*
X1600611Y1279854D01*
X1600672Y1280402D01*
X1600733Y1280462D01*
X1600794Y1280949D01*
X1600854Y1281009D01*
X1600915Y1281557D01*
X1600976Y1281618D01*
X1601037Y1282104D01*
X1601098Y1282165D01*
X1601158Y1282652D01*
X1601219Y1282713D01*
X1601280Y1283260D01*
X1601341Y1283321D01*
X1601402Y1283807D01*
X1601463Y1283868D01*
X1601523Y1284415D01*
X1601584Y1284476D01*
X1601645Y1284963D01*
X1601706Y1285024D01*
X1601767Y1285510D01*
X1601828Y1285571D01*
X1601888Y1286119D01*
X1601949Y1286179D01*
X1602010Y1286666D01*
X1602071Y1286727D01*
X1602131Y1287274D01*
X1602193Y1287335D01*
X1602253Y1287943D01*
X1602314Y1288004D01*
X1602375Y1288673D01*
X1602436Y1288734D01*
X1602496Y1289707D01*
X1602436Y1290437D01*
X1602375Y1290497D01*
X1602314Y1290802D01*
X1602253Y1290862D01*
X1602193Y1291106D01*
X1602010Y1291349D01*
Y1291410D01*
X1601584Y1291896D01*
X1601158Y1292261D01*
X1600794Y1292444D01*
X1600550Y1292504D01*
X1600489Y1292565D01*
X1600064Y1292626D01*
X1600003Y1292687D01*
X1599030Y1292748D01*
X1598300D01*
X1598239Y1292687D01*
G37*
G36*
G01X1583521Y1292200D02*
X1583339Y1291957D01*
X1583278Y1291775D01*
X1583095Y1291531D01*
X1583034Y1291349D01*
X1582852Y1291106D01*
X1582791Y1290923D01*
X1582609Y1290680D01*
X1582487Y1290376D01*
X1582304Y1290133D01*
X1582244Y1289950D01*
X1582061Y1289707D01*
X1582000Y1289524D01*
X1581818Y1289281D01*
X1581757Y1289098D01*
X1581575Y1288855D01*
X1581453Y1288551D01*
X1581270Y1288308D01*
X1581210Y1288126D01*
X1581027Y1287882D01*
X1580967Y1287700D01*
X1580784Y1287456D01*
X1580723Y1287274D01*
X1580541Y1287031D01*
X1580480Y1286848D01*
X1580298Y1286605D01*
X1580176Y1286301D01*
X1579993Y1286057D01*
X1579933Y1285875D01*
X1579750Y1285632D01*
X1579689Y1285450D01*
X1579507Y1285206D01*
Y1285145D01*
X1579385Y1285024D01*
X1579324Y1285085D01*
X1579263Y1286057D01*
X1579203Y1286119D01*
X1579142Y1287274D01*
X1579081Y1287335D01*
X1579020Y1288551D01*
X1578959Y1288612D01*
X1578899Y1289768D01*
X1578838Y1289828D01*
X1578777Y1291045D01*
X1578716Y1291106D01*
X1578656Y1292261D01*
X1578594Y1292322D01*
Y1292444D01*
X1573729D01*
X1573790Y1292383D01*
X1573851Y1291775D01*
X1573911Y1291714D01*
X1573972Y1291106D01*
X1574033Y1291045D01*
X1574094Y1290497D01*
X1574155Y1290437D01*
X1574216Y1289828D01*
X1574276Y1289768D01*
X1574337Y1289159D01*
X1574398Y1289098D01*
X1574459Y1288551D01*
X1574520Y1288491D01*
X1574580Y1287882D01*
X1574641Y1287821D01*
X1574702Y1287213D01*
X1574763Y1287152D01*
X1574824Y1286605D01*
X1574885Y1286544D01*
X1574945Y1285936D01*
X1575006Y1285875D01*
X1575067Y1285267D01*
X1575128Y1285206D01*
X1575189Y1284659D01*
X1575250Y1284598D01*
X1575310Y1283990D01*
X1575371Y1283929D01*
X1575432Y1283321D01*
X1575493Y1283260D01*
X1575554Y1282713D01*
X1575615Y1282652D01*
X1575675Y1282044D01*
X1575736Y1281983D01*
X1575797Y1281374D01*
X1575857Y1281314D01*
X1575919Y1280767D01*
X1575979Y1280706D01*
X1576040Y1280097D01*
X1576101Y1280037D01*
X1576162Y1279428D01*
X1576222Y1279367D01*
X1576101Y1279124D01*
X1575919Y1278881D01*
X1575797Y1278577D01*
X1575615Y1278333D01*
X1575554Y1278151D01*
X1575371Y1277908D01*
X1575310Y1277726D01*
X1575128Y1277482D01*
X1575067Y1277300D01*
X1574885Y1277056D01*
X1574763Y1276752D01*
X1574580Y1276509D01*
X1574520Y1276326D01*
X1574337Y1276083D01*
X1574276Y1275901D01*
X1574094Y1275657D01*
X1574033Y1275475D01*
X1573851Y1275232D01*
X1573729Y1274928D01*
X1573546Y1274684D01*
X1573486Y1274502D01*
X1573303Y1274259D01*
X1573243Y1274076D01*
X1573060Y1273833D01*
X1572999Y1273650D01*
X1572817Y1273407D01*
X1572695Y1273103D01*
X1572574Y1272981D01*
X1577682D01*
X1577743Y1273164D01*
X1577926Y1273407D01*
X1577986Y1273590D01*
X1578169Y1273833D01*
X1578230Y1274015D01*
X1578412Y1274259D01*
X1578534Y1274563D01*
X1578716Y1274806D01*
X1578777Y1274989D01*
X1578959Y1275232D01*
X1579020Y1275414D01*
X1579203Y1275657D01*
X1579263Y1275840D01*
X1579446Y1276083D01*
X1579568Y1276387D01*
X1579750Y1276631D01*
X1579811Y1276813D01*
X1579993Y1277056D01*
X1580054Y1277239D01*
X1580237Y1277482D01*
X1580298Y1277665D01*
X1580480Y1277908D01*
X1580541Y1278090D01*
X1580723Y1278333D01*
X1580845Y1278638D01*
X1581027Y1278881D01*
X1581088Y1279063D01*
X1581270Y1279307D01*
X1581331Y1279489D01*
X1581514Y1279732D01*
X1581575Y1279915D01*
X1581757Y1280158D01*
X1581879Y1280462D01*
X1582061Y1280706D01*
X1582122Y1280888D01*
X1582304Y1281131D01*
X1582365Y1281314D01*
X1582548Y1281557D01*
X1582609Y1281739D01*
X1582791Y1281983D01*
X1582913Y1282287D01*
X1583095Y1282530D01*
X1583156Y1282713D01*
X1583339Y1282956D01*
X1583399Y1283138D01*
X1583582Y1283381D01*
X1583643Y1283564D01*
X1583825Y1283807D01*
X1583886Y1283990D01*
X1584068Y1284233D01*
X1584190Y1284537D01*
X1584372Y1284780D01*
X1584433Y1284963D01*
X1584616Y1285206D01*
X1584676Y1285389D01*
X1584859Y1285632D01*
X1584920Y1285814D01*
X1585102Y1286057D01*
X1585224Y1286362D01*
X1585406Y1286605D01*
X1585467Y1286787D01*
X1585650Y1287031D01*
X1585710Y1287213D01*
X1585893Y1287456D01*
X1585954Y1287639D01*
X1586136Y1287882D01*
X1586258Y1288186D01*
X1586440Y1288430D01*
X1586501Y1288612D01*
X1586683Y1288855D01*
X1586744Y1289038D01*
X1586927Y1289281D01*
X1586987Y1289463D01*
X1587170Y1289707D01*
X1587292Y1290011D01*
X1587474Y1290254D01*
X1587535Y1290437D01*
X1587717Y1290680D01*
X1587778Y1290862D01*
X1587961Y1291106D01*
X1588022Y1291288D01*
X1588204Y1291531D01*
X1588265Y1291714D01*
X1588447Y1291957D01*
X1588569Y1292261D01*
X1588691Y1292383D01*
Y1292504D01*
X1583643D01*
X1583521Y1292200D01*
G37*
G36*
G01X1549341Y1291896D02*
X1549401Y1291835D01*
X1549462Y1291045D01*
X1549523Y1290984D01*
X1549584Y1290254D01*
X1549644Y1290193D01*
X1549706Y1289463D01*
X1549766Y1289403D01*
X1549827Y1288673D01*
X1549888Y1288612D01*
X1549949Y1287882D01*
X1550009Y1287821D01*
X1550070Y1287092D01*
X1550131Y1287031D01*
X1550192Y1286240D01*
X1550253Y1286179D01*
X1550314Y1285450D01*
X1550374Y1285389D01*
X1550435Y1284659D01*
X1550496Y1284598D01*
X1550557Y1283868D01*
X1550618Y1283807D01*
X1550678Y1283078D01*
X1550739Y1283017D01*
X1550800Y1282287D01*
X1550861Y1282226D01*
X1550922Y1281435D01*
X1550983Y1281374D01*
X1551043Y1280645D01*
X1551104Y1280584D01*
X1551165Y1279854D01*
X1551226Y1279793D01*
Y1279489D01*
X1555726D01*
X1555848Y1279732D01*
X1556031Y1279976D01*
X1556152Y1280280D01*
X1556335Y1280523D01*
X1556456Y1280827D01*
X1556639Y1281070D01*
X1556761Y1281374D01*
X1556943Y1281618D01*
X1557065Y1281922D01*
X1557247Y1282165D01*
X1557369Y1282469D01*
X1557551Y1282713D01*
X1557612Y1282895D01*
X1557794Y1283138D01*
X1557916Y1283443D01*
X1558098Y1283686D01*
X1558220Y1283990D01*
X1558403Y1284233D01*
X1558524Y1284537D01*
X1558707Y1284780D01*
X1558828Y1285085D01*
X1559011Y1285328D01*
X1559132Y1285632D01*
X1559315Y1285875D01*
X1559376Y1286057D01*
X1559558Y1286301D01*
X1559680Y1286605D01*
X1559862Y1286848D01*
X1560045Y1287213D01*
X1560106Y1287152D01*
X1560166Y1286666D01*
X1560227Y1285936D01*
X1560288Y1285571D01*
X1560349Y1284720D01*
X1560409Y1284659D01*
X1560470Y1283564D01*
X1560531Y1283503D01*
X1560592Y1282409D01*
X1560653Y1282348D01*
X1560714Y1281192D01*
X1560774Y1281131D01*
X1560835Y1280037D01*
X1560896Y1279976D01*
Y1279489D01*
X1565336D01*
X1565457Y1279732D01*
X1565640Y1279976D01*
X1565701Y1280158D01*
X1565883Y1280402D01*
X1565944Y1280584D01*
X1566127Y1280827D01*
X1566187Y1281009D01*
X1566370Y1281253D01*
X1566431Y1281435D01*
X1566613Y1281679D01*
X1566674Y1281861D01*
X1566856Y1282104D01*
X1566917Y1282287D01*
X1567100Y1282530D01*
X1567161Y1282713D01*
X1567343Y1282956D01*
X1567404Y1283138D01*
X1567586Y1283381D01*
X1567708Y1283686D01*
X1567891Y1283929D01*
X1567951Y1284111D01*
X1568133Y1284355D01*
X1568194Y1284537D01*
X1568377Y1284780D01*
X1568438Y1284963D01*
X1568620Y1285206D01*
X1568681Y1285389D01*
X1568863Y1285632D01*
X1568924Y1285814D01*
X1569107Y1286057D01*
X1569168Y1286240D01*
X1569350Y1286483D01*
X1569411Y1286666D01*
X1569593Y1286909D01*
X1569654Y1287092D01*
X1569837Y1287335D01*
X1569897Y1287517D01*
X1570080Y1287761D01*
X1570202Y1288065D01*
X1570384Y1288308D01*
X1570445Y1288491D01*
X1570627Y1288734D01*
X1570688Y1288916D01*
X1570870Y1289159D01*
X1570931Y1289342D01*
X1571114Y1289585D01*
X1571174Y1289768D01*
X1571357Y1290011D01*
X1571418Y1290193D01*
X1571600Y1290437D01*
X1571661Y1290619D01*
X1571844Y1290862D01*
X1571904Y1291045D01*
X1572087Y1291288D01*
X1572148Y1291470D01*
X1572330Y1291714D01*
X1572452Y1292018D01*
X1572634Y1292261D01*
X1572695Y1292383D01*
Y1292444D01*
X1567647D01*
X1567404Y1291957D01*
X1567343Y1291714D01*
X1567161Y1291410D01*
X1567100Y1291167D01*
X1566978Y1290984D01*
X1566917Y1290741D01*
X1566735Y1290437D01*
X1566674Y1290193D01*
X1566491Y1289889D01*
X1566431Y1289646D01*
X1566309Y1289463D01*
X1566248Y1289220D01*
X1566066Y1288916D01*
X1566005Y1288673D01*
X1565822Y1288369D01*
X1565762Y1288126D01*
X1565640Y1287943D01*
X1565579Y1287700D01*
X1565397Y1287396D01*
X1565336Y1287152D01*
X1565154Y1286848D01*
X1565093Y1286605D01*
X1564971Y1286422D01*
X1564910Y1286179D01*
X1564728Y1285875D01*
X1564667Y1285632D01*
X1564485Y1285328D01*
X1564424Y1285085D01*
X1564302Y1284902D01*
X1564241Y1284659D01*
X1564059Y1284355D01*
X1563998Y1284415D01*
X1563937Y1285389D01*
X1563876Y1285754D01*
X1563815Y1286727D01*
X1563755Y1287092D01*
X1563694Y1288065D01*
X1563633Y1288430D01*
X1563572Y1289403D01*
X1563511Y1289768D01*
X1563450Y1290741D01*
X1563390Y1291106D01*
X1563329Y1292079D01*
X1563268Y1292444D01*
X1558767D01*
Y1292383D01*
X1558585Y1292139D01*
X1558403Y1291714D01*
X1558220Y1291470D01*
X1558038Y1291045D01*
X1557855Y1290802D01*
X1557673Y1290376D01*
X1557490Y1290133D01*
X1557369Y1289828D01*
X1557186Y1289585D01*
X1557004Y1289159D01*
X1556821Y1288916D01*
X1556639Y1288491D01*
X1556456Y1288247D01*
X1556274Y1287821D01*
X1556091Y1287578D01*
X1555970Y1287274D01*
X1555787Y1287031D01*
X1555605Y1286605D01*
X1555422Y1286362D01*
X1555240Y1285936D01*
X1555057Y1285693D01*
X1554875Y1285267D01*
X1554693Y1285024D01*
X1554571Y1284720D01*
X1554389Y1284476D01*
X1554267Y1284233D01*
X1554206Y1284294D01*
X1554145Y1285632D01*
X1554084Y1286362D01*
X1554024Y1287700D01*
X1553963Y1288430D01*
X1553902Y1289768D01*
X1553841Y1290619D01*
X1553780Y1291835D01*
X1553720Y1292444D01*
X1549280D01*
X1549341Y1291896D01*
G37*
G36*
G01X1546421Y1298891D02*
X1545935Y1298830D01*
X1545752Y1298708D01*
X1545509Y1298647D01*
X1545266Y1298526D01*
X1544961Y1298282D01*
X1544901D01*
X1544232Y1297552D01*
Y1297492D01*
X1544049Y1297248D01*
X1543928Y1297005D01*
X1543867Y1296701D01*
X1543806Y1296640D01*
X1543745Y1296032D01*
X1543806Y1295241D01*
X1543867Y1295180D01*
X1543928Y1294937D01*
X1544110Y1294694D01*
Y1294633D01*
X1544657Y1294146D01*
X1544718D01*
X1544840Y1294025D01*
X1545083Y1293964D01*
X1545144Y1293903D01*
X1545631Y1293843D01*
X1545691Y1293781D01*
X1546665Y1293843D01*
X1546725Y1293903D01*
X1547030Y1293964D01*
X1547090Y1294025D01*
X1547333Y1294086D01*
X1547577Y1294207D01*
X1547942Y1294511D01*
X1548002D01*
X1548672Y1295241D01*
X1548732Y1295424D01*
X1548915Y1295667D01*
X1548976Y1295910D01*
X1549037Y1295971D01*
X1549097Y1296458D01*
X1549158Y1296519D01*
X1549097Y1297431D01*
X1549037Y1297492D01*
X1548976Y1297735D01*
X1548854Y1297978D01*
X1548428Y1298465D01*
X1548185Y1298647D01*
X1547820Y1298830D01*
X1547394Y1298891D01*
X1547333Y1298951D01*
X1546482D01*
X1546421Y1298891D01*
G37*
G36*
G01X1542894Y1292079D02*
X1542833Y1292018D01*
X1542772Y1291531D01*
X1542711Y1291470D01*
X1542650Y1290984D01*
X1542590Y1290923D01*
X1542529Y1290376D01*
X1542468Y1290315D01*
X1542407Y1289828D01*
X1542346Y1289768D01*
X1542285Y1289281D01*
X1542225Y1289220D01*
X1542164Y1288673D01*
X1542103Y1288612D01*
X1542042Y1288126D01*
X1541981Y1288065D01*
X1541920Y1287578D01*
X1541860Y1287517D01*
X1541799Y1286970D01*
X1541738Y1286909D01*
X1541677Y1286422D01*
X1541617Y1286362D01*
X1541556Y1285875D01*
X1541495Y1285814D01*
X1541434Y1285267D01*
X1541373Y1285206D01*
X1541312Y1284720D01*
X1541252Y1284659D01*
X1541191Y1284172D01*
X1541130Y1284111D01*
X1541069Y1283564D01*
X1541008Y1283503D01*
X1540948Y1283017D01*
X1540887Y1282956D01*
X1540826Y1282469D01*
X1540765Y1282409D01*
X1540704Y1281861D01*
X1540643Y1281800D01*
X1540583Y1281314D01*
X1540522Y1281253D01*
X1540461Y1280767D01*
X1540400Y1280706D01*
X1540339Y1280158D01*
X1540278Y1280097D01*
X1540218Y1279611D01*
X1540157Y1279550D01*
Y1279489D01*
X1545509D01*
X1545570Y1279854D01*
X1545631Y1279915D01*
X1545691Y1280402D01*
X1545752Y1280462D01*
X1545813Y1281009D01*
X1545874Y1281070D01*
X1545935Y1281557D01*
X1545995Y1281618D01*
X1546056Y1282104D01*
X1546117Y1282165D01*
X1546178Y1282713D01*
X1546239Y1282773D01*
X1546300Y1283260D01*
X1546360Y1283321D01*
X1546421Y1283807D01*
X1546482Y1283868D01*
X1546543Y1284415D01*
X1546604Y1284476D01*
X1546665Y1284963D01*
X1546725Y1285024D01*
X1546786Y1285510D01*
X1546847Y1285571D01*
X1546908Y1286119D01*
X1546969Y1286179D01*
X1547030Y1286666D01*
X1547090Y1286727D01*
X1547151Y1287213D01*
X1547212Y1287274D01*
X1547273Y1287761D01*
X1547333Y1287821D01*
X1547394Y1288369D01*
X1547455Y1288430D01*
X1547516Y1288916D01*
X1547577Y1288977D01*
X1547637Y1289463D01*
X1547698Y1289524D01*
X1547759Y1290072D01*
X1547820Y1290133D01*
X1547881Y1290619D01*
X1547942Y1290680D01*
X1548002Y1291167D01*
X1548063Y1291227D01*
X1548124Y1291775D01*
X1548185Y1291835D01*
X1548246Y1292322D01*
X1548307Y1292383D01*
Y1292444D01*
X1542954D01*
X1542894Y1292079D01*
G37*
G36*
G01X1667049Y51343D02*
X1669549Y48843D01*
Y53843D01*
X1667049Y51343D01*
G37*
G36*
G01X1696600Y102700D02*
X1685400D01*
Y85300D01*
X1696600D01*
Y102700D01*
G37*
G36*
G01X1689800Y135600D02*
Y124400D01*
X1707200D01*
Y135600D01*
X1689800D01*
G37*
G36*
G01X1667049Y504099D02*
X1669549Y501599D01*
Y506599D01*
X1667049Y504099D01*
G37*
G36*
G01X1696600Y555700D02*
X1685400D01*
Y538300D01*
X1696600D01*
Y555700D01*
G37*
G36*
G01X1689800Y588600D02*
Y577400D01*
X1707200D01*
Y588600D01*
X1689800D01*
G37*
G36*
G01X1667049Y956855D02*
X1669549Y954355D01*
Y959355D01*
X1667049Y956855D01*
G37*
G36*
G01X1696600Y1008200D02*
X1685400D01*
Y990800D01*
X1696600D01*
Y1008200D01*
G37*
G36*
G01X1689800Y1041100D02*
Y1029900D01*
X1707200D01*
Y1041100D01*
X1689800D01*
G37*
G36*
G01X1663434Y1246875D02*
G02I-11811J0D01*
G37*
G36*
G01X1693480Y1246918D02*
Y1241918D01*
X1713480D01*
Y1246918D01*
X1693480D01*
G37*
G36*
G01X1655409Y1300497D02*
Y1302297D01*
X1659909D01*
Y1300497D01*
X1655409D01*
G37*
G36*
G01X1646409Y1295997D02*
Y1297797D01*
X1650009D01*
Y1295997D01*
X1646409D01*
G37*
G36*
G01X1655409D02*
Y1297797D01*
X1658109D01*
Y1295997D01*
X1655409D01*
G37*
G36*
G01X1650009Y1291497D02*
Y1302297D01*
X1651809D01*
Y1291497D01*
X1650009D01*
G37*
G36*
G01X1653609D02*
Y1302297D01*
X1655409D01*
Y1291497D01*
X1653609D01*
G37*
G36*
G01X1644609D02*
Y1302297D01*
X1646409D01*
Y1291497D01*
X1644609D01*
G37*
G36*
G01X1720126Y1426200D02*
Y1415000D01*
X1737526D01*
Y1426200D01*
X1720126D01*
G37*
G36*
G01X1791261Y51343D02*
X1793761Y48843D01*
Y53843D01*
X1791261Y51343D01*
G37*
G36*
G01X1805731Y27496D02*
Y35496D01*
X1796631D01*
Y27496D01*
X1805731D01*
G37*
G36*
G01X1812500Y95500D02*
Y106700D01*
X1795100D01*
Y95500D01*
X1812500D01*
G37*
G36*
G01X1813300Y135600D02*
Y124400D01*
X1830700D01*
Y135600D01*
X1813300D01*
G37*
G36*
G01X1791261Y504099D02*
X1793761Y501599D01*
Y506599D01*
X1791261Y504099D01*
G37*
G36*
G01X1820600Y555700D02*
X1809400D01*
Y538300D01*
X1820600D01*
Y555700D01*
G37*
G36*
G01X1813800Y588600D02*
Y577400D01*
X1831200D01*
Y588600D01*
X1813800D01*
G37*
G36*
G01X1791261Y956855D02*
X1793761Y954355D01*
Y959355D01*
X1791261Y956855D01*
G37*
G36*
G01X1820600Y1008200D02*
X1809400D01*
Y990800D01*
X1820600D01*
Y1008200D01*
G37*
G36*
G01X1813800Y1041100D02*
Y1029900D01*
X1831200D01*
Y1041100D01*
X1813800D01*
G37*
G36*
G01X1818686Y1482135D02*
Y1479265D01*
X1813566D01*
Y1482135D01*
X1818686D01*
G37*
G36*
G01X1839800Y101100D02*
Y89900D01*
X1857200D01*
Y101100D01*
X1839800D01*
G37*
G36*
G01X1881700Y97400D02*
Y108600D01*
X1864300D01*
Y97400D01*
X1881700D01*
G37*
G36*
G01Y550400D02*
Y561600D01*
X1864300D01*
Y550400D01*
X1881700D01*
G37*
G36*
G01X1841300Y579600D02*
Y568400D01*
X1858700D01*
Y579600D01*
X1841300D01*
G37*
G36*
G01X1881700Y1003400D02*
Y1014600D01*
X1864300D01*
Y1003400D01*
X1881700D01*
G37*
G36*
G01X1841300Y1032600D02*
Y1021400D01*
X1858700D01*
Y1032600D01*
X1841300D01*
G37*
G36*
G01X1915474Y51343D02*
X1917974Y48843D01*
Y53843D01*
X1915474Y51343D01*
G37*
G36*
G01Y504099D02*
X1917974Y501599D01*
Y506599D01*
X1915474Y504099D01*
G37*
G36*
G01Y956855D02*
X1917974Y954355D01*
Y959355D01*
X1915474Y956855D01*
G37*
%LPC*%
G75*
G36*
G01X1651623Y1236245D02*
X1653698Y1236450D01*
X1655693Y1237055D01*
X1657528Y1238035D01*
X1658597Y1238915D01*
X1656157Y1241355D01*
X1655727D01*
X1655629Y1241363D01*
X1654928Y1241575D01*
X1654603Y1241750D01*
Y1241355D01*
X1653003D01*
Y1244510D01*
X1650286Y1247227D01*
X1649878Y1246895D01*
X1649242Y1246554D01*
X1648586Y1246355D01*
X1646028D01*
Y1241355D01*
X1644458D01*
Y1253055D01*
X1643663Y1253849D01*
X1642783Y1252780D01*
X1641803Y1250945D01*
X1641198Y1248950D01*
X1640993Y1246875D01*
X1641198Y1244800D01*
X1641803Y1242805D01*
X1642783Y1240970D01*
X1644108Y1239360D01*
X1645718Y1238035D01*
X1647553Y1237055D01*
X1649548Y1236450D01*
X1651623Y1236245D01*
G37*
G36*
G01X1659582Y1239900D02*
X1660463Y1240970D01*
X1661443Y1242805D01*
X1662048Y1244800D01*
X1662253Y1246875D01*
X1662048Y1248950D01*
X1661443Y1250945D01*
X1660463Y1252780D01*
X1659138Y1254390D01*
X1657528Y1255715D01*
X1655693Y1256695D01*
X1653698Y1257300D01*
X1651623Y1257505D01*
X1649548Y1257300D01*
X1647553Y1256695D01*
X1645718Y1255715D01*
X1644647Y1254833D01*
X1645889Y1253590D01*
X1648278D01*
X1648552Y1253555D01*
X1649243Y1253345D01*
X1649878Y1253005D01*
X1650438Y1252550D01*
X1650893Y1251990D01*
X1651233Y1251355D01*
X1651443Y1250665D01*
X1651513Y1249950D01*
X1651443Y1249235D01*
X1651233Y1248545D01*
X1651129Y1248352D01*
X1653003Y1246478D01*
Y1253395D01*
X1654603D01*
Y1249340D01*
X1654928Y1249515D01*
X1655623Y1249725D01*
X1656348Y1249795D01*
X1657073Y1249725D01*
X1657768Y1249515D01*
X1658408Y1249170D01*
X1658968Y1248710D01*
X1659428Y1248150D01*
X1659773Y1247510D01*
X1659982Y1246817D01*
X1660053Y1246090D01*
Y1245000D01*
X1659983Y1244275D01*
X1659773Y1243580D01*
X1659428Y1242940D01*
X1658968Y1242380D01*
X1658408Y1241920D01*
X1657858Y1241624D01*
X1659582Y1239900D01*
G37*
G36*
G01X1656658Y1242824D02*
X1656778Y1242835D01*
X1657194Y1242965D01*
X1657576Y1243167D01*
X1657912Y1243444D01*
X1658185Y1243778D01*
X1658386Y1244159D01*
X1658514Y1244573D01*
X1658553Y1245000D01*
Y1246090D01*
X1658515Y1246520D01*
X1658383Y1246935D01*
X1658183Y1247315D01*
X1657908Y1247650D01*
X1657573Y1247926D01*
X1657191Y1248126D01*
X1656776Y1248255D01*
X1656349Y1248295D01*
X1655919Y1248255D01*
X1655503Y1248125D01*
X1655123Y1247925D01*
X1654788Y1247650D01*
X1654603Y1247425D01*
Y1244878D01*
X1656658Y1242824D01*
G37*
G36*
G01X1646028Y1247930D02*
X1648638D01*
X1648668Y1247940D01*
X1649048Y1248140D01*
X1649230Y1248283D01*
X1646028Y1251485D01*
Y1247930D01*
G37*
G36*
G01X1649969Y1249511D02*
X1649973Y1249525D01*
X1650013Y1249950D01*
X1649973Y1250375D01*
X1649848Y1250780D01*
X1649648Y1251160D01*
X1649378Y1251490D01*
X1649048Y1251760D01*
X1648668Y1251960D01*
X1648583Y1251990D01*
X1647489D01*
X1649969Y1249511D01*
G37*
G54D24*
X511535Y1320472D03*
G54D23*
X531535D03*
%LPD*%
G75*
G54D10*
X85000Y885500D03*
X89000D03*
Y881500D03*
X85000D03*
X89000Y877500D03*
X85000D03*
X89000Y889500D03*
X85000D03*
X89000Y893500D03*
X85000D03*
X81166Y892754D03*
Y888754D03*
X178993Y455018D03*
Y451018D03*
X182827Y447764D03*
Y455764D03*
X186827D03*
X182827Y451764D03*
X186827D03*
X182827Y439764D03*
Y443764D03*
X1001687Y1111499D03*
X1721762Y458436D03*
Y454436D03*
X1725596Y447182D03*
X1729596Y443182D03*
X1725596D03*
X1729596Y455182D03*
X1725596D03*
X1729596Y459182D03*
X1725596D03*
Y451182D03*
X1729596Y447182D03*
Y451182D03*
X1796166Y892754D03*
Y888754D03*
X1804000Y885500D03*
Y881500D03*
X1800000Y885500D03*
Y893500D03*
X1804000D03*
X1800000Y889500D03*
X1804000D03*
X1800000Y877500D03*
X1804000D03*
X1800000Y881500D03*
G54D20*
G01X1696650Y1252008D02*
X1695990D01*
G01X1696090Y1252098D02*
X1696750D01*
G01X1696840Y1252208D02*
X1696190D01*
G01X1696290Y1252298D02*
X1696940D01*
G01X1697040Y1252408D02*
X1696380D01*
G01X1696480Y1252508D02*
X1697130D01*
G01X1697230Y1252598D02*
X1696580D01*
G01X1696670Y1252708D02*
X1697330D01*
G01X1697420Y1252798D02*
X1696770D01*
G01X1696860Y1252908D02*
X1697520D01*
G01X1697620Y1253008D02*
X1696960D01*
G01X1697060Y1253098D02*
X1697710D01*
G01X1697810Y1253208D02*
X1697165D01*
G01X1697160D02*
X1697210D01*
G01X1697250Y1253298D02*
X1697290D01*
G01X1697250D02*
X1697900D01*
G01X1698000Y1253408D02*
X1697350D01*
G01X1697450Y1253508D02*
X1698100D01*
G01X1698200Y1253598D02*
X1697540D01*
G01X1697640Y1253708D02*
X1698290D01*
G01X1698390Y1253798D02*
X1697730D01*
G01X1697830Y1253908D02*
X1698490D01*
G01X1698580Y1254008D02*
X1697930D01*
G01X1698030Y1254098D02*
X1698680D01*
G01X1698770Y1254208D02*
X1698120D01*
G01X1698220Y1254298D02*
X1698870D01*
G01X1698970Y1254408D02*
X1698310D01*
G01X1698410Y1254508D02*
X1699070D01*
G01X1699160Y1254598D02*
X1698510D01*
G01X1698600Y1254708D02*
X1699260D01*
G01X1699450Y1254908D02*
X1698800D01*
G01X1698990Y1255098D02*
X1699640D01*
G01X1694350Y1269518D02*
X1694380Y1269538D01*
G01X1694350Y1268978D02*
Y1269518D01*
G01X1694360Y1268958D02*
X1694350Y1268978D01*
G01X1694410Y1268848D02*
X1694360Y1268958D01*
G01X1694420Y1268838D02*
X1694410Y1268848D01*
G01X1699600Y1263248D02*
X1694420Y1268838D01*
G01X1694350Y1269508D02*
X1694410D01*
G01X1694350Y1269408D02*
X1694500D01*
G01X1694590Y1269298D02*
X1694350D01*
G01Y1269208D02*
X1694690D01*
G01X1694780Y1269098D02*
X1694350D01*
G01Y1269008D02*
X1694870D01*
G01X1694970Y1268908D02*
X1694380D01*
G01X1694450Y1268798D02*
X1695060D01*
G01X1695150Y1268708D02*
X1694540D01*
G01X1694630Y1268598D02*
X1695240D01*
G01X1695340Y1268508D02*
X1694730D01*
G01X1694820Y1268408D02*
X1695430D01*
G01X1695520Y1268298D02*
X1694910D01*
G01X1695000Y1268208D02*
X1695620D01*
G01X1695710Y1268098D02*
X1695100D01*
G01X1695190Y1268008D02*
X1695800D01*
G01X1695900Y1267908D02*
X1695280D01*
G01X1695380Y1267798D02*
X1695990D01*
G01X1696080Y1267708D02*
X1695470D01*
G01X1695560Y1267598D02*
X1696180D01*
G01X1696270Y1267508D02*
X1695660D01*
G01X1695750Y1267408D02*
X1696360D01*
G01X1696460Y1267298D02*
X1695840D01*
G01X1695930Y1267208D02*
X1696550D01*
G01X1696640Y1267098D02*
X1696030D01*
G01X1696120Y1267008D02*
X1696730D01*
G01X1696830Y1266908D02*
X1696210D01*
G01X1696310Y1266798D02*
X1696920D01*
G01X1697010Y1266708D02*
X1696400D01*
G01X1696490Y1266598D02*
X1697100D01*
G01X1697200Y1266508D02*
X1696590D01*
G01X1696680Y1266408D02*
X1697290D01*
G01X1697380Y1266298D02*
X1696770D01*
G01X1696860Y1266208D02*
X1697480D01*
G01X1697570Y1266098D02*
X1696960D01*
G01X1697050Y1266008D02*
X1697660D01*
G01X1697760Y1265908D02*
X1697140D01*
G01X1697230Y1265798D02*
X1697850D01*
G01X1697940Y1265708D02*
X1697330D01*
G01X1697420Y1265598D02*
X1698040D01*
G01X1698130Y1265508D02*
X1697510D01*
G01X1697600Y1265408D02*
X1698220D01*
G01X1698320Y1265298D02*
X1697700D01*
G01X1697790Y1265208D02*
X1698410D01*
G01X1698500Y1265098D02*
X1697880D01*
G01X1697970Y1265008D02*
X1698600D01*
G01X1698690Y1264908D02*
X1698070D01*
G01X1698160Y1264798D02*
X1698780D01*
G01X1698870Y1264708D02*
X1698250D01*
G01X1698350Y1264598D02*
X1698970D01*
G01X1699060Y1264508D02*
X1698440D01*
G01X1698530Y1264408D02*
X1699150D01*
G01X1699250Y1264298D02*
X1698630D01*
G01X1698810Y1264098D02*
X1700050D01*
G01X1700060Y1263908D02*
X1699000D01*
G01X1698750Y1266198D02*
X1699260D01*
G01X1698710Y1266158D02*
X1698750Y1266198D01*
G01X1698710Y1265698D02*
Y1266158D01*
G01X1698750Y1265658D02*
X1698710Y1265698D01*
G01Y1266098D02*
X1708960D01*
G01X1708890Y1265908D02*
X1698710D01*
G01Y1265708D02*
X1708730D01*
G01X1701360Y1267008D02*
X1699930D01*
G01X1699350Y1266268D02*
X1699260Y1266198D01*
G01X1699370Y1266318D02*
X1699350Y1266268D01*
G01X1699370Y1266328D02*
Y1266318D01*
G01X1699490Y1266578D02*
X1699370Y1266328D01*
G01X1699510Y1266588D02*
X1699490Y1266578D01*
G01X1699940Y1267008D02*
X1699510Y1266588D01*
G01X1699270Y1266208D02*
X1700000D01*
G01X1700110Y1266538D02*
X1700220Y1266608D01*
G01X1699940Y1266368D02*
X1700110Y1266538D01*
G01X1699920Y1266258D02*
X1699940Y1266368D01*
G01X1700010Y1266198D02*
X1699920Y1266258D01*
G01X1700080Y1266508D02*
X1699460D01*
G01X1699410Y1266408D02*
X1699980D01*
G01X1699930Y1266298D02*
X1699360D01*
G01X1699620Y1266708D02*
X1701300D01*
G01Y1266908D02*
X1699830D01*
G01X1700180Y1263308D02*
X1703410Y1259828D01*
G01X1700170Y1263308D02*
X1700180D01*
G01X1700130Y1263358D02*
X1700170Y1263308D01*
G01X1700100Y1263418D02*
X1700130Y1263358D01*
G01X1699920Y1265548D02*
X1700100Y1263418D01*
G01X1700020Y1265658D02*
X1699920Y1265548D01*
G01X1700440Y1259508D02*
X1699970D01*
G01X1699960Y1259708D02*
X1700420D01*
G01X1700400Y1259908D02*
X1699940D01*
G01X1699920Y1260098D02*
X1700390D01*
G01X1700370Y1260298D02*
X1699900D01*
G01X1699880Y1260508D02*
X1700350D01*
G01X1700340Y1260708D02*
X1699870D01*
G01X1699850Y1260908D02*
X1700320D01*
G01X1700300Y1261098D02*
X1699830D01*
G01X1699820Y1261298D02*
X1700290D01*
G01X1700270Y1261508D02*
X1699800D01*
G01X1699780Y1261708D02*
X1700250D01*
G01X1700230Y1261908D02*
X1699770D01*
G01X1699750Y1262098D02*
X1700220D01*
G01X1700200Y1262298D02*
X1699730D01*
G01X1699720Y1262408D02*
X1700230D01*
G01X1700730Y1262708D02*
X1699700D01*
G01X1699680Y1262908D02*
X1700550D01*
G01X1699620Y1263218D02*
X1699600Y1263248D01*
G01X1699660Y1263118D02*
X1699620Y1263218D01*
G01X1699660Y1263108D02*
Y1263118D01*
G01Y1263098D02*
Y1263108D01*
G01X1700360Y1263098D02*
X1699660D01*
G01X1699560Y1263298D02*
X1700180D01*
G01X1700110Y1263408D02*
X1699460D01*
G01X1699370Y1263508D02*
X1700100D01*
G01X1700090Y1263598D02*
X1699280D01*
G01X1699180Y1263708D02*
X1700080D01*
G01X1700070Y1263798D02*
X1699090D01*
G01X1698900Y1264008D02*
X1700050D01*
G01X1700040Y1264208D02*
X1699560D01*
G01X1699350Y1265658D02*
X1698750D01*
G01X1699450Y1265568D02*
X1699350Y1265658D01*
G01X1699570Y1264218D02*
X1699450Y1265568D01*
G01X1699410Y1265598D02*
X1699970D01*
G01X1699920Y1265508D02*
X1699460D01*
G01X1699470Y1265408D02*
X1699940D01*
G01Y1265298D02*
X1699470D01*
G01X1699480Y1265208D02*
X1699950D01*
G01X1699960Y1265098D02*
X1699490D01*
G01X1699500Y1265008D02*
X1699970D01*
G01X1699980Y1264908D02*
X1699510D01*
G01X1699520Y1264798D02*
X1699990D01*
G01Y1264708D02*
X1699530D01*
G01Y1264598D02*
X1700000D01*
G01X1700010Y1264508D02*
X1699550D01*
G01Y1264408D02*
X1700020D01*
G01X1700030Y1264298D02*
X1699560D01*
G01X1699400Y1264148D02*
X1694380Y1269538D01*
G01X1699510Y1264118D02*
X1699400Y1264148D01*
G01X1699570Y1264218D02*
X1699510Y1264118D01*
G01X1698720Y1264208D02*
X1699340D01*
G01X1699660Y1263098D02*
X1700100Y1257948D01*
G01X1700110Y1257908D02*
X1700580D01*
G01X1700590Y1257708D02*
X1700120D01*
G01X1700140Y1257508D02*
X1700610D01*
G01X1700630Y1257298D02*
X1700160D01*
G01X1700180Y1257098D02*
X1700650D01*
G01X1700690Y1257008D02*
X1700190D01*
G01X1700200Y1256358D02*
X1700100Y1256248D01*
G01X1700230Y1256428D02*
X1700200Y1256358D01*
G01X1700050Y1256208D02*
X1700740D01*
G01Y1256008D02*
X1699860D01*
G01X1699670Y1255798D02*
X1700760D01*
G01X1700120Y1255598D02*
X1699470D01*
G01X1699380Y1255508D02*
X1700030D01*
G01X1699930Y1255408D02*
X1699280D01*
G01X1699180Y1255298D02*
X1699840D01*
G01X1699740Y1255208D02*
X1699090D01*
G01X1698900Y1255008D02*
X1699550D01*
G01X1699350Y1254798D02*
X1698700D01*
G01X1700080Y1258208D02*
X1700550D01*
G01X1700530Y1258408D02*
X1700070D01*
G01X1700050Y1258598D02*
X1700520D01*
G01X1700500Y1258798D02*
X1700030D01*
G01X1700010Y1259008D02*
X1700480D01*
G01X1700470Y1259208D02*
X1700000D01*
G01X1699990Y1259298D02*
X1700460D01*
G01X1700450Y1259408D02*
X1699980D01*
G01X1699960Y1259598D02*
X1700430D01*
G01X1700420Y1259798D02*
X1699950D01*
G01X1699930Y1260008D02*
X1700400D01*
G01X1700380Y1260208D02*
X1699910D01*
G01X1699900Y1260408D02*
X1700360D01*
G01X1700340Y1260598D02*
X1699880D01*
G01X1699860Y1260798D02*
X1700330D01*
G01X1700310Y1261008D02*
X1699840D01*
G01X1699830Y1261208D02*
X1700290D01*
G01X1700280Y1261408D02*
X1699810D01*
G01X1699790Y1261598D02*
X1700260D01*
G01X1700240Y1261798D02*
X1699770D01*
G01X1699760Y1262008D02*
X1700220D01*
G01X1700210Y1262208D02*
X1699740D01*
G01X1700370Y1262428D02*
X1703100Y1259488D01*
G01X1700250Y1262448D02*
X1700370Y1262428D01*
G01X1700200Y1262348D02*
X1700250Y1262448D01*
G01X1700470Y1259098D02*
X1700010D01*
G01X1700020Y1258908D02*
X1700490D01*
G01X1700510Y1258708D02*
X1700040D01*
G01X1700060Y1258508D02*
X1700530D01*
G01X1700540Y1258298D02*
X1700070D01*
G01X1700090Y1258098D02*
X1700560D01*
G01X1700570Y1258008D02*
X1700100D01*
G01X1700230Y1256488D02*
Y1256428D01*
G01X1700100Y1257948D02*
X1700230Y1256488D01*
G01X1700220Y1256408D02*
X1700900D01*
G01X1700750Y1256228D02*
X1700730Y1256158D01*
G01X1700800Y1256308D02*
X1700750Y1256228D01*
G01X1700730Y1256098D02*
X1699960D01*
G01X1699770Y1255908D02*
X1700750D01*
G01X1700770Y1255598D02*
X1700270D01*
G01X1700240Y1255638D02*
X1700140Y1255618D01*
G01X1700510Y1253198D02*
X1700620D01*
G01X1700510Y1253208D02*
Y1253198D01*
G01X1700310Y1255558D02*
X1700510Y1253208D01*
G01X1700240Y1255638D02*
X1700310Y1255558D01*
G01X1700610Y1253298D02*
X1700500D01*
G01X1700505D02*
X1706100D01*
G01X1706165Y1253208D02*
X1700510D01*
G01X1700750Y1252158D02*
X1701640D01*
G01X1700710Y1252198D02*
X1700750Y1252158D01*
G01X1700710Y1252878D02*
Y1252198D01*
G01X1700680Y1252948D02*
X1700710Y1252878D01*
G01X1700530Y1253108D02*
X1700680Y1252948D01*
G01X1700520Y1253128D02*
X1700530Y1253108D01*
G01X1700510Y1253188D02*
X1700520Y1253128D01*
G01X1701680Y1252208D02*
X1700710D01*
G01Y1252408D02*
X1701680D01*
G01Y1252598D02*
X1700710D01*
G01Y1252798D02*
X1701680D01*
G01X1700960Y1253508D02*
X1700490D01*
G01X1700470Y1253598D02*
X1700940D01*
G01X1700930Y1253798D02*
X1700460D01*
G01X1700440Y1254008D02*
X1700910D01*
G01X1700890Y1254208D02*
X1700420D01*
G01X1700410Y1254408D02*
X1700880D01*
G01X1700860Y1254598D02*
X1700390D01*
G01X1700370Y1254798D02*
X1700840D01*
G01X1700830Y1255008D02*
X1700360D01*
G01X1700340Y1255208D02*
X1700810D01*
G01X1700790Y1255408D02*
X1700330D01*
G01X1700220Y1256598D02*
X1701090D01*
G01X1701280Y1256798D02*
X1700200D01*
G01X1700170Y1257208D02*
X1700640D01*
G01X1700650Y1257058D02*
X1700200Y1262348D01*
G01X1700390Y1262408D02*
X1701010D01*
G01X1701200Y1262208D02*
X1700580D01*
G01X1700760Y1262008D02*
X1701380D01*
G01X1700640Y1262798D02*
X1699690D01*
G01X1699670Y1263008D02*
X1700460D01*
G01X1700270Y1263208D02*
X1699630D01*
G01X1700330Y1266618D02*
X1700220Y1266608D01*
G01X1700380Y1266528D02*
X1700330Y1266618D01*
G01X1700380Y1266298D02*
Y1266528D01*
G01X1700280Y1266198D02*
X1700380Y1266298D01*
G01X1700010Y1266198D02*
X1700280D01*
G01X1700210Y1266598D02*
X1699520D01*
G01X1700390Y1267588D02*
X1700420Y1267608D01*
G01X1700380Y1267558D02*
X1700390Y1267588D01*
G01X1700380Y1267358D02*
Y1267558D01*
G01X1700370Y1267318D02*
X1700380Y1267358D01*
G01X1700350Y1267268D02*
X1700370Y1267318D01*
G01X1700300Y1267208D02*
X1700350Y1267268D01*
G01X1700210Y1267168D02*
X1700300Y1267208D01*
G01X1699940Y1267008D02*
X1700210Y1267168D01*
G01X1700420Y1267598D02*
X1701250D01*
G01X1700380Y1267408D02*
X1703270D01*
G01X1703260Y1267208D02*
X1700280D01*
G01X1700330Y1266598D02*
X1701300D01*
G01Y1266408D02*
X1700380D01*
G01X1700290Y1266208D02*
X1701400D01*
G01X1700590Y1257798D02*
X1700120D01*
G01X1700130Y1257598D02*
X1700600D01*
G01X1700620Y1257408D02*
X1700150D01*
G01X1700720Y1256968D02*
X1700820Y1256998D01*
G01X1700650Y1257058D02*
X1700720Y1256968D01*
G01X1700630Y1253008D02*
X1706410D01*
G01X1700950Y1253578D02*
X1700730Y1256158D01*
G01X1700950Y1253508D02*
Y1253578D01*
G01X1701050Y1253418D02*
X1700950Y1253508D01*
G01X1705150Y1253418D02*
X1701050D01*
G01X1700800Y1256298D02*
X1700150D01*
G01X1700230Y1256508D02*
X1700990D01*
G01X1700810Y1256308D02*
X1700800D01*
G01X1700810Y1256318D02*
Y1256308D01*
G01Y1256318D02*
X1703400Y1259008D01*
G01X1703210Y1258798D02*
X1702570D01*
G01X1702370Y1258598D02*
X1703020D01*
G01X1702830Y1258408D02*
X1702180D01*
G01X1701990Y1258208D02*
X1702630D01*
G01X1702540Y1258098D02*
X1701890D01*
G01X1701940Y1258158D02*
X1700820Y1256998D01*
G01X1700830Y1257008D02*
X1701470D01*
G01X1701380Y1256908D02*
X1700200D01*
G01X1700210Y1256708D02*
X1701190D01*
G01X1700930Y1257098D02*
X1701570D01*
G01X1701670Y1257208D02*
X1701030D01*
G01X1701120Y1257298D02*
X1701770D01*
G01X1701860Y1257408D02*
X1701220D01*
G01X1701310Y1257508D02*
X1701960D01*
G01X1702050Y1257598D02*
X1701410D01*
G01X1701510Y1257708D02*
X1702150D01*
G01X1702250Y1257798D02*
X1701600D01*
G01X1701700Y1257908D02*
X1702340D01*
G01X1702440Y1258008D02*
X1701790D01*
G01X1702620Y1260008D02*
X1703250D01*
G01X1703060Y1260208D02*
X1702440D01*
G01X1702250Y1260408D02*
X1702870D01*
G01X1702690Y1260598D02*
X1702060D01*
G01X1701970Y1260708D02*
X1702590D01*
G01X1702500Y1260798D02*
X1701880D01*
G01X1701790Y1260908D02*
X1702410D01*
G01X1702310Y1261008D02*
X1701690D01*
G01X1701600Y1261098D02*
X1702220D01*
G01X1702130Y1261208D02*
X1701510D01*
G01X1701410Y1261298D02*
X1702040D01*
G01X1701940Y1261408D02*
X1701320D01*
G01X1701230Y1261508D02*
X1701850D01*
G01X1701760Y1261598D02*
X1701130D01*
G01X1701040Y1261708D02*
X1701660D01*
G01X1701570Y1261798D02*
X1700950D01*
G01X1700860Y1261908D02*
X1701480D01*
G01X1701290Y1262098D02*
X1700670D01*
G01X1700480Y1262298D02*
X1701100D01*
G01X1700920Y1262508D02*
X1699720D01*
G01X1699710Y1262598D02*
X1700830D01*
G01X1702680Y1261878D02*
X1702720Y1261838D01*
G01X1701300Y1266298D02*
X1700380D01*
G01X1701400Y1266198D02*
X1701300Y1266298D01*
G01X1700380Y1266508D02*
X1701300D01*
G01X1702630Y1267208D02*
X1702740Y1267098D01*
G01X1702360Y1267178D02*
X1702630Y1267208D01*
G01X1702080Y1267148D02*
X1702360Y1267178D01*
G01X1701960Y1267138D02*
X1702080Y1267148D01*
G01X1701860Y1267118D02*
X1701960Y1267138D01*
G01X1701610Y1267078D02*
X1701860Y1267118D01*
G01X1701600Y1267078D02*
X1701610D01*
G01X1701510Y1267058D02*
X1701600Y1267078D01*
G01X1701500Y1267058D02*
X1701510D01*
G01X1701380Y1267038D02*
X1701500Y1267058D01*
G01X1701300Y1266938D02*
X1701380Y1267038D01*
G01X1701300Y1266298D02*
Y1266938D01*
G01X1701240Y1267608D02*
X1700420D01*
G01X1701260Y1267598D02*
X1701240Y1267608D01*
G01X1701290Y1267588D02*
X1701260Y1267598D01*
G01X1701320Y1267568D02*
X1701290Y1267588D01*
G01X1701400Y1267548D02*
X1701320Y1267568D01*
G01X1701420Y1267558D02*
X1701400Y1267548D01*
G01X1701660Y1267598D02*
X1701420Y1267558D01*
G01X1702160Y1267668D02*
X1701660Y1267598D01*
G01X1702280Y1267678D02*
X1702160Y1267668D01*
G01X1702340Y1267678D02*
X1702280D01*
G01X1702500Y1267698D02*
X1702340Y1267678D01*
G01X1702640Y1267708D02*
X1702500Y1267698D01*
G01X1700100Y1267098D02*
X1701750D01*
G01X1701300Y1266798D02*
X1699730D01*
G01X1701400Y1266198D02*
X1707240D01*
G01X1705310Y1267708D02*
X1702620D01*
G01X1702640D02*
X1702740Y1267808D01*
G01X1700770Y1255708D02*
X1699570D01*
G01X1700310Y1255508D02*
X1700780D01*
G01X1700800Y1255298D02*
X1700330D01*
G01X1700350Y1255098D02*
X1700820D01*
G01X1700830Y1254908D02*
X1700360D01*
G01X1700380Y1254708D02*
X1700850D01*
G01X1700870Y1254508D02*
X1700400D01*
G01X1700420Y1254298D02*
X1700880D01*
G01X1700900Y1254098D02*
X1700440D01*
G01X1700450Y1253908D02*
X1700920D01*
G01X1700940Y1253708D02*
X1700470D01*
G01X1700700Y1252908D02*
X1701750D01*
G01X1701680Y1252198D02*
X1701640Y1252158D01*
G01X1701680Y1252838D02*
Y1252198D01*
G01X1701780Y1252938D02*
X1701680Y1252838D01*
G01Y1252298D02*
X1700710D01*
G01Y1252508D02*
X1701680D01*
G01Y1252708D02*
X1700710D01*
G01X1705250Y1253888D02*
Y1253898D01*
G01X1705240Y1253818D02*
X1705250Y1253888D01*
G01X1705240Y1253558D02*
Y1253818D01*
G01X1705250Y1253538D02*
X1705240Y1253558D01*
G01X1705150Y1253418D02*
X1705250Y1253538D01*
G01Y1253908D02*
X1706020D01*
G01X1705980Y1253708D02*
X1705240D01*
G01X1705220Y1253508D02*
X1706020D01*
G01X1703860Y1259338D02*
Y1259478D01*
G01X1706560Y1256438D02*
X1703860Y1259338D01*
G01X1703880Y1259508D02*
X1703090D01*
G01X1703100Y1259348D02*
X1701940Y1258158D01*
G01X1703100Y1259488D02*
Y1259348D01*
G01X1702090Y1258298D02*
X1702730D01*
G01X1702920Y1258508D02*
X1702280D01*
G01X1702470Y1258708D02*
X1703120D01*
G01X1703310Y1258908D02*
X1702660D01*
G01X1703550Y1259008D02*
X1705230Y1257188D01*
G01X1703400Y1259008D02*
X1703550D01*
G01X1702760D02*
X1703400D01*
G01X1705220Y1257208D02*
X1705850D01*
G01X1705660Y1257408D02*
X1705030D01*
G01X1704850Y1257598D02*
X1705480D01*
G01X1705290Y1257798D02*
X1704660D01*
G01X1704570Y1257908D02*
X1705200D01*
G01X1705100Y1258008D02*
X1704470D01*
G01X1704380Y1258098D02*
X1705010D01*
G01X1704920Y1258208D02*
X1704290D01*
G01X1704200Y1258298D02*
X1704830D01*
G01X1704730Y1258408D02*
X1704100D01*
G01X1704010Y1258508D02*
X1704640D01*
G01X1704550Y1258598D02*
X1703920D01*
G01X1703830Y1258708D02*
X1704460D01*
G01X1704360Y1258798D02*
X1703730D01*
G01X1703640Y1258908D02*
X1704270D01*
G01X1704180Y1259008D02*
X1703530D01*
G01X1703900Y1259298D02*
X1703050D01*
G01X1703100Y1259408D02*
X1703860D01*
G01X1703980Y1259598D02*
X1702990D01*
G01X1702900Y1259708D02*
X1704080D01*
G01X1704180Y1259798D02*
X1702810D01*
G01X1702720Y1259908D02*
X1703340D01*
G01X1703550Y1259828D02*
X1704980Y1261298D01*
G01X1703410Y1259828D02*
X1703550D01*
G01X1704880Y1261208D02*
X1705520D01*
G01X1705330Y1261008D02*
X1704690D01*
G01X1704600Y1260908D02*
X1705230D01*
G01X1705140Y1260798D02*
X1704500D01*
G01X1704400Y1260708D02*
X1705040D01*
G01X1704950Y1260598D02*
X1704310D01*
G01X1704210Y1260508D02*
X1704850D01*
G01X1704750Y1260408D02*
X1704110D01*
G01X1704020Y1260298D02*
X1704660D01*
G01X1704560Y1260208D02*
X1703920D01*
G01X1703830Y1260098D02*
X1704460D01*
G01X1704370Y1260008D02*
X1703730D01*
G01X1703630Y1259908D02*
X1704270D01*
G01X1703990Y1259208D02*
X1702960D01*
G01X1702860Y1259098D02*
X1704080D01*
G01X1703150Y1260098D02*
X1702530D01*
G01X1702340Y1260298D02*
X1702970D01*
G01X1702780Y1260508D02*
X1702160D01*
G01X1702770Y1261838D02*
X1705260D01*
G01X1702720D02*
X1702770D01*
G01X1705270Y1261598D02*
X1705910D01*
G01X1705720Y1261408D02*
X1705080D01*
G01X1706200Y1261908D02*
X1702680D01*
G01X1702720Y1262868D02*
X1702770D01*
G01X1702680Y1262828D02*
X1702720Y1262868D01*
G01X1702680Y1261878D02*
Y1262828D01*
G01Y1262708D02*
X1705940D01*
G01X1705970Y1262508D02*
X1702680D01*
G01Y1262298D02*
X1706590D01*
G01X1706390Y1262098D02*
X1702680D01*
G01X1702740Y1266758D02*
Y1267098D01*
G01X1702780Y1266708D02*
X1702740Y1266758D01*
G01X1702730Y1267098D02*
X1705360D01*
G01X1705230Y1266708D02*
X1702780D01*
G01X1705280Y1266758D02*
X1705230Y1266708D01*
G01X1705280Y1267038D02*
Y1266758D01*
G01X1702740Y1266798D02*
X1705280D01*
G01Y1266908D02*
X1702740D01*
G01Y1267008D02*
X1705280D01*
G01X1704830Y1267318D02*
Y1267278D01*
G01X1704730Y1267418D02*
X1704830Y1267318D01*
G01X1703290Y1267418D02*
X1704730D01*
G01X1703190Y1267318D02*
X1703290Y1267418D01*
G01X1703190Y1267278D02*
Y1267318D01*
G01X1703290Y1267168D02*
X1703190Y1267278D01*
G01X1704730Y1267168D02*
X1703290D01*
G01X1704830Y1267278D02*
X1704730Y1267168D01*
G01X1704830Y1267298D02*
X1706800D01*
G01X1706510Y1267408D02*
X1704740D01*
G01X1702740Y1267838D02*
Y1267808D01*
G01X1702780Y1267878D02*
X1702740Y1267838D01*
G01X1705230Y1267878D02*
X1702780D01*
G01X1705280Y1267838D02*
X1705230Y1267878D01*
G01X1705280Y1267738D02*
Y1267838D01*
G01X1702730Y1267798D02*
X1705280D01*
G01X1703190Y1267298D02*
X1700360D01*
G01X1700380Y1267508D02*
X1706140D01*
G01X1705360Y1267638D02*
X1705280Y1267738D01*
G01X1705410Y1267638D02*
X1705360D01*
G01X1705970Y1267548D02*
X1705410Y1267638D01*
G01X1706150Y1267508D02*
X1705970Y1267548D01*
G01X1705590Y1267598D02*
X1701720D01*
G01X1705790Y1267068D02*
X1706200Y1266978D01*
G01X1705500Y1267118D02*
X1705790Y1267068D01*
G01X1705470Y1267118D02*
X1705500D01*
G01X1705390Y1267138D02*
X1705470Y1267118D01*
G01X1705280Y1267038D02*
X1705390Y1267138D01*
G01X1705580Y1267098D02*
X1707170D01*
G01X1705890Y1262868D02*
X1702770D01*
G01X1702680Y1262798D02*
X1705940D01*
G01X1705930Y1262828D02*
X1705890Y1262868D01*
G01X1706110Y1262478D02*
X1706310Y1262678D01*
G01X1706000Y1262448D02*
X1706110Y1262478D01*
G01X1705940Y1262548D02*
X1706000Y1262448D01*
G01X1705940Y1262728D02*
Y1262548D01*
G01Y1262738D02*
Y1262728D01*
G01X1705930Y1262828D02*
X1705940Y1262738D01*
G01X1706140Y1262508D02*
X1706780D01*
G01X1705940Y1262598D02*
X1702680D01*
G01X1704790Y1261098D02*
X1705430D01*
G01X1705350Y1261778D02*
X1705260Y1261838D01*
G01X1705330Y1261668D02*
X1705350Y1261778D01*
G01X1704980Y1261298D02*
X1705330Y1261668D01*
G01X1705620Y1261298D02*
X1704980D01*
G01X1705310Y1261798D02*
X1706100D01*
G01X1706010Y1261708D02*
X1705340D01*
G01X1705180Y1261508D02*
X1705810D01*
G01X1705380Y1257708D02*
X1704750D01*
G01X1704940Y1257508D02*
X1705570D01*
G01X1705750Y1257298D02*
X1705120D01*
G01X1705310Y1257098D02*
X1705940D01*
G01X1706030Y1257008D02*
X1705400D01*
G01X1705490Y1256908D02*
X1706130D01*
G01X1706220Y1256798D02*
X1705590D01*
G01X1705680Y1256708D02*
X1706310D01*
G01X1706500Y1256508D02*
X1705870D01*
G01X1706050Y1256298D02*
X1707190D01*
G01X1707180Y1256208D02*
X1706150D01*
G01X1705290Y1254078D02*
X1705250Y1253898D01*
G01X1705290Y1254088D02*
Y1254078D01*
G01X1705400Y1254398D02*
X1705290Y1254088D01*
G01X1705410Y1254408D02*
X1705400Y1254398D01*
G01X1705620Y1254718D02*
X1705410Y1254408D01*
G01X1705630Y1254728D02*
X1705620Y1254718D01*
G01X1705870Y1254948D02*
X1705630Y1254728D01*
G01X1705880Y1254948D02*
X1705870D01*
G01X1706000Y1255028D02*
X1705880Y1254948D01*
G01X1706010Y1255038D02*
X1706000Y1255028D01*
G01X1706070Y1255068D02*
X1706010Y1255038D01*
G01X1706230Y1255138D02*
X1706070Y1255068D01*
G01X1705240Y1253798D02*
X1706000D01*
G01X1706040Y1253408D02*
X1700490D01*
G01X1706030Y1253428D02*
X1706040Y1253408D01*
G01X1705980Y1253688D02*
X1706030Y1253428D01*
G01X1705980Y1253698D02*
Y1253688D01*
G01Y1253718D02*
Y1253698D01*
G01X1700530Y1253098D02*
X1706270D01*
G01X1706190Y1253168D02*
X1706130Y1253258D01*
G01X1706200Y1253158D02*
X1706190Y1253168D01*
G01X1706210Y1253148D02*
X1706200Y1253158D01*
G01X1706050Y1253398D02*
X1706040Y1253408D01*
G01X1706130Y1253268D02*
X1706050Y1253398D01*
G01X1706000Y1253598D02*
X1705240D01*
G01X1705270Y1254008D02*
X1706040D01*
G01X1706030Y1253978D02*
X1705980Y1253718D01*
G01X1706040Y1253998D02*
X1706030Y1253978D01*
G01X1706260Y1253728D02*
X1706270Y1253748D01*
G01X1706210Y1254258D02*
X1706430Y1254418D01*
G01X1706200Y1254248D02*
X1706210Y1254258D01*
G01X1706190Y1254228D02*
X1706200Y1254248D01*
G01X1706050Y1254018D02*
X1706190Y1254228D01*
G01X1706040Y1253998D02*
X1706050Y1254018D01*
G01X1706270Y1254298D02*
X1705370D01*
G01X1705330Y1254208D02*
X1706170D01*
G01X1706100Y1254098D02*
X1705290D01*
G01X1705470Y1254508D02*
X1706730D01*
G01X1706140Y1255098D02*
X1707810D01*
G01X1707900Y1255008D02*
X1705960D01*
G01X1705720Y1254798D02*
X1708090D01*
G01X1708270Y1254598D02*
X1705550D01*
G01X1706130Y1253208D02*
X1706170D01*
G01X1706210Y1253148D02*
X1706430Y1252988D01*
G01X1706000Y1252408D02*
X1707550D01*
G01X1707710Y1252508D02*
X1705820D01*
G01X1705380Y1252938D02*
X1701780D01*
G01X1705460Y1252908D02*
X1705380Y1252938D01*
G01X1705470Y1252898D02*
X1705460Y1252908D01*
G01X1705470Y1252888D02*
Y1252898D01*
G01X1705510Y1252818D02*
X1705470Y1252888D01*
G01X1705520Y1252818D02*
X1705510D01*
G01X1705530Y1252808D02*
X1705520Y1252818D01*
G01X1705600Y1252708D02*
X1705530Y1252808D01*
G01X1705610Y1252698D02*
X1705600Y1252708D01*
G01X1705840Y1252478D02*
X1705610Y1252698D01*
G01Y1252708D02*
X1707950D01*
G01X1705860Y1252468D02*
X1705840Y1252478D01*
G01X1706660Y1252168D02*
X1707000Y1252178D01*
G01X1706650Y1252168D02*
X1706660D01*
G01X1706640D02*
X1706650D01*
G01X1706480Y1252188D02*
X1706640Y1252168D01*
G01X1706460Y1252188D02*
X1706480D01*
G01X1705860Y1252468D02*
X1706460Y1252188D01*
G01X1707110Y1252208D02*
X1706440D01*
G01Y1252978D02*
X1706430Y1252988D01*
G01X1706460Y1252978D02*
X1706440D01*
G01X1706630Y1252918D02*
X1706460Y1252978D01*
G01X1706850Y1252908D02*
X1706870D01*
G01X1706720D02*
X1706850D01*
G01X1706650Y1252918D02*
X1706720Y1252908D01*
G01X1706630Y1252918D02*
X1706650D01*
G01X1706290Y1253538D02*
X1706260Y1253728D01*
G01X1706300Y1253508D02*
X1706290Y1253538D01*
G01X1706470Y1253288D02*
X1706300Y1253508D01*
G01X1706490Y1253278D02*
X1706470Y1253288D01*
G01X1706660Y1253198D02*
X1706490Y1253278D01*
G01X1706670Y1253198D02*
X1706660D01*
G01X1706710Y1253188D02*
X1706670Y1253198D01*
G01X1706770Y1253188D02*
X1706710D01*
G01X1706790D02*
X1706770D01*
G01X1706820Y1254218D02*
X1706830D01*
G01X1706730D02*
X1706820D01*
G01X1706710Y1254208D02*
X1706730Y1254218D01*
G01X1706400Y1254048D02*
X1706710Y1254208D01*
G01X1706380Y1254028D02*
X1706400Y1254048D01*
G01X1706270Y1253748D02*
X1706380Y1254028D01*
G01X1706440Y1254428D02*
X1706430Y1254418D01*
G01X1706460Y1254428D02*
X1706440D01*
G01X1706630Y1254488D02*
X1706460Y1254428D01*
G01X1706650Y1254488D02*
X1706630D01*
G01X1706720Y1254498D02*
X1706650Y1254488D01*
G01X1706740Y1254508D02*
X1706720Y1254498D01*
G01X1706800Y1254508D02*
X1706740D01*
G01X1706830Y1254498D02*
X1706800Y1254508D01*
G01X1706410Y1254408D02*
X1705410D01*
G01X1706320Y1253888D02*
X1707260D01*
G01X1707280Y1253688D02*
X1706270D01*
G01X1706320Y1253488D02*
X1707230D01*
G01X1707050Y1253288D02*
X1706480D01*
G01X1706790Y1253188D02*
X1706920Y1253208D01*
G01X1707120Y1254078D02*
X1706470D01*
G01X1706870Y1254498D02*
X1707070Y1254448D01*
G01X1706830Y1254498D02*
X1706870D01*
G01X1706320Y1255168D02*
X1706230Y1255138D01*
G01X1706330Y1255178D02*
X1706320Y1255168D01*
G01X1706470Y1255208D02*
X1706330Y1255178D01*
G01X1706550Y1255228D02*
X1706470Y1255208D01*
G01X1706330Y1256008D02*
X1705230Y1257188D01*
G01X1706590Y1255728D02*
X1706330Y1256008D01*
G01X1706620Y1255678D02*
X1706590Y1255728D01*
G01X1706650Y1255528D02*
X1706620Y1255678D01*
G01X1706660Y1255508D02*
X1706650Y1255528D01*
G01X1706660Y1255488D02*
Y1255508D01*
G01X1706640Y1255318D02*
X1706660Y1255488D01*
G01X1706640Y1255308D02*
Y1255318D01*
G01X1706550Y1255228D02*
X1706640Y1255308D01*
G01X1705770Y1256598D02*
X1706410D01*
G01X1706730Y1256498D02*
X1707240Y1262728D01*
G01X1706670Y1256418D02*
X1706730Y1256498D01*
G01X1706560Y1256438D02*
X1706670Y1256418D01*
G01X1706330Y1262708D02*
X1706310Y1262678D01*
G01X1706970Y1262708D02*
X1706330D01*
G01D02*
X1707140Y1263548D01*
G01X1706720Y1263098D02*
X1708980D01*
G01Y1262908D02*
X1706530D01*
G01X1706230Y1262598D02*
X1706870D01*
G01X1706680Y1262408D02*
X1702680D01*
G01Y1262208D02*
X1706490D01*
G01X1706290Y1262008D02*
X1702680D01*
G01X1706900Y1258508D02*
X1707360D01*
G01X1707350Y1258298D02*
X1706880D01*
G01X1706860Y1258098D02*
X1707330D01*
G01X1707320Y1257908D02*
X1706850D01*
G01X1706830Y1257708D02*
X1707300D01*
G01X1707290Y1257508D02*
X1706820D01*
G01X1706800Y1257298D02*
X1707270D01*
G01X1707250Y1257098D02*
X1706790D01*
G01X1706770Y1256908D02*
X1707230D01*
G01X1707220Y1256708D02*
X1706750D01*
G01X1706730Y1256508D02*
X1707200D01*
G01X1707160Y1256008D02*
X1706330D01*
G01X1706520Y1255798D02*
X1707160D01*
G01X1707340Y1255598D02*
X1706640D01*
G01X1706650Y1255408D02*
X1707530D01*
G01X1706480Y1266898D02*
X1706200Y1266978D01*
G01X1706490Y1266888D02*
X1706480Y1266898D01*
G01X1706600Y1266858D02*
X1706490Y1266888D01*
G01X1706600Y1266848D02*
Y1266858D01*
G01X1706710Y1266808D02*
X1706600Y1266848D01*
G01X1706720Y1266798D02*
X1706710Y1266808D01*
G01X1707580Y1266798D02*
X1706720D01*
G01X1706440Y1266908D02*
X1707470D01*
G01X1706270Y1267468D02*
X1706150Y1267508D01*
G01X1706380Y1267448D02*
X1706270Y1267468D01*
G01X1706620Y1267368D02*
X1706380Y1267448D01*
G01X1706730Y1267328D02*
X1706620Y1267368D01*
G01X1706790Y1267308D02*
X1706730Y1267328D01*
G01X1706080Y1267008D02*
X1707330D01*
G01X1707010Y1267208D02*
X1704760D01*
G01X1707330Y1266248D02*
X1707240Y1266198D01*
G01X1707320Y1266348D02*
X1707330Y1266248D01*
G01X1707250Y1266458D02*
X1707320Y1266348D01*
G01X1707230Y1266478D02*
X1707250Y1266458D01*
G01X1706930Y1266698D02*
X1707230Y1266478D01*
G01X1706920Y1266708D02*
X1706930Y1266698D01*
G01X1706910Y1266708D02*
X1706920D01*
G01X1706720Y1266798D02*
X1706910Y1266708D01*
G01X1707250Y1266208D02*
X1708970D01*
G01X1708950Y1266408D02*
X1707290D01*
G01X1707060Y1266598D02*
X1708870D01*
G01X1708980Y1264598D02*
X1707200D01*
G01X1707170Y1263578D02*
X1707140Y1263548D01*
G01X1707200Y1263638D02*
X1707170Y1263578D01*
G01X1707200Y1264658D02*
Y1263638D01*
G01X1707100Y1263508D02*
X1707770D01*
G01X1707940Y1263708D02*
X1707200D01*
G01Y1263908D02*
X1708130D01*
G01X1708320Y1264098D02*
X1707200D01*
G01Y1264208D02*
X1708980D01*
G01Y1264408D02*
X1707200D01*
G01X1707310Y1264738D02*
X1707410Y1264838D01*
G01X1707240Y1264738D02*
X1707310D01*
G01X1707200Y1264698D02*
X1707240Y1264738D01*
G01X1707200Y1264658D02*
Y1264698D01*
G01X1706910Y1263298D02*
X1708980D01*
G01X1707700Y1262598D02*
X1707230D01*
G01X1707070Y1262808D02*
X1703860Y1259478D01*
G01X1707180Y1262828D02*
X1707070Y1262808D01*
G01X1707240Y1262728D02*
X1707180Y1262828D01*
G01X1706960Y1259298D02*
X1707430D01*
G01X1707440Y1259408D02*
X1706970D01*
G01X1706990Y1259598D02*
X1707460D01*
G01X1707470Y1259798D02*
X1707010D01*
G01X1707020Y1260008D02*
X1707490D01*
G01X1707500Y1260208D02*
X1707040D01*
G01X1707050Y1260408D02*
X1707520D01*
G01X1707540Y1260598D02*
X1707070D01*
G01X1707090Y1260798D02*
X1707550D01*
G01X1707570Y1261008D02*
X1707100D01*
G01X1707120Y1261208D02*
X1707590D01*
G01X1707600Y1261408D02*
X1707140D01*
G01X1707150Y1261598D02*
X1707620D01*
G01X1707630Y1261798D02*
X1707170D01*
G01X1707180Y1262008D02*
X1707650D01*
G01X1707670Y1262208D02*
X1707200D01*
G01X1707220Y1262408D02*
X1707680D01*
G01X1707070Y1262798D02*
X1706430D01*
G01X1706950Y1259098D02*
X1707420D01*
G01X1707400Y1258908D02*
X1706930D01*
G01X1706920Y1258708D02*
X1707380D01*
G01X1707370Y1258598D02*
X1706910D01*
G01X1706890Y1258408D02*
X1707360D01*
G01X1707340Y1258208D02*
X1706870D01*
G01X1706860Y1258008D02*
X1707330D01*
G01X1707310Y1257798D02*
X1706840D01*
G01X1706830Y1257598D02*
X1707290D01*
G01X1707280Y1257408D02*
X1706810D01*
G01X1706790Y1257208D02*
X1707260D01*
G01X1707240Y1257008D02*
X1706780D01*
G01X1706760Y1256798D02*
X1707230D01*
G01X1707210Y1256598D02*
X1706740D01*
G01X1707200Y1256408D02*
X1705960D01*
G01X1706240Y1256098D02*
X1707170D01*
G01X1707160Y1255908D02*
X1706430D01*
G01X1706600Y1255708D02*
X1707240D01*
G01X1707180Y1255768D02*
X1708140Y1254748D01*
G01X1708460Y1254408D02*
X1707130D01*
G01X1707110Y1254428D02*
X1707070Y1254448D01*
G01X1707110Y1254428D02*
X1707420Y1254168D01*
G01X1707190Y1253988D02*
X1706360D01*
G01X1706280Y1253788D02*
X1707270D01*
G01X1707080Y1254118D02*
X1706830Y1254218D01*
G01X1707100Y1254108D02*
X1707080Y1254118D01*
G01X1707250Y1253908D02*
X1707100Y1254108D01*
G01X1707260Y1253878D02*
X1707250Y1253908D01*
G01X1706920Y1254188D02*
X1706650D01*
G01X1706940Y1253208D02*
X1706920D01*
G01X1707160Y1253348D02*
X1706940Y1253208D01*
G01X1707170Y1253368D02*
X1707160Y1253348D01*
G01X1707280Y1253598D02*
X1707170Y1253368D01*
G01X1707290Y1253618D02*
X1707280Y1253598D01*
G01X1707260Y1253878D02*
X1707290Y1253618D01*
G01X1707130Y1253008D02*
X1708150D01*
G01X1707010Y1252178D02*
X1707000D01*
G01X1707300Y1252248D02*
X1707010Y1252178D01*
G01X1707310Y1252258D02*
X1707300Y1252248D01*
G01X1707820Y1252568D02*
X1707310Y1252258D01*
G01X1707070Y1252958D02*
X1707110Y1252978D01*
G01X1706870Y1252908D02*
X1707070Y1252958D01*
G01X1707180Y1253388D02*
X1706400D01*
G01X1706280Y1253578D02*
X1707280D01*
G01X1707170Y1255788D02*
X1707150Y1255858D01*
G01X1707180Y1255778D02*
X1707170Y1255788D01*
G01X1707180Y1255768D02*
Y1255778D01*
G01X1706940Y1267248D02*
X1706790Y1267308D01*
G01X1706950Y1267238D02*
X1706940Y1267248D01*
G01X1708200Y1266958D02*
X1708260Y1266968D01*
G01X1708190Y1266958D02*
X1708200D01*
G01X1708080Y1266928D02*
X1708190Y1266958D01*
G01X1708070Y1266928D02*
X1708080D01*
G01X1707940Y1266878D02*
X1708070Y1266928D01*
G01X1707940Y1266868D02*
Y1266878D01*
G01X1707880Y1266838D02*
X1707940Y1266868D01*
G01X1707860Y1266818D02*
X1707880Y1266838D01*
G01X1707800Y1266768D02*
X1707860Y1266818D01*
G01X1707780Y1266748D02*
X1707800Y1266768D01*
G01X1707640Y1266748D02*
X1707780D01*
G01X1707460Y1266918D02*
X1707640Y1266748D01*
G01X1707450Y1266928D02*
X1707460Y1266918D01*
G01X1706950Y1267238D02*
X1707450Y1266928D01*
G01X1708010Y1266908D02*
X1708530D01*
G01X1708580Y1265598D02*
X1707420D01*
G01X1707470Y1265548D02*
X1707410Y1264838D01*
G01X1707380Y1264798D02*
X1707930D01*
G01X1708220Y1265528D02*
X1708250Y1265518D01*
G01X1708140Y1265538D02*
X1708220Y1265528D01*
G01X1708070Y1265558D02*
X1708140Y1265538D01*
G01X1708060Y1265558D02*
X1708070D01*
G01X1707930Y1265468D02*
X1708060Y1265558D01*
G01X1707880Y1264858D02*
X1707930Y1265468D01*
G01X1707980Y1264748D02*
X1707880Y1264858D01*
G01X1707980Y1265508D02*
X1707470D01*
G01X1707370Y1265658D02*
X1700020D01*
G01X1707470Y1265548D02*
X1707370Y1265658D01*
G01X1707010Y1263408D02*
X1707830D01*
G01X1707800Y1263558D02*
X1708350Y1264138D01*
G01X1707770Y1263508D02*
X1707800Y1263558D01*
G01X1707770Y1263468D02*
Y1263508D01*
G01X1707870Y1263358D02*
X1707770Y1263468D01*
G01X1708230Y1264008D02*
X1707200D01*
G01Y1263798D02*
X1708030D01*
G01X1707840Y1263598D02*
X1707180D01*
G01X1707200Y1262798D02*
X1707730D01*
G01X1707720Y1262788D02*
X1707150Y1255858D01*
G01X1707430Y1255508D02*
X1706660D01*
G01X1706630Y1255298D02*
X1707620D01*
G01X1707710Y1255208D02*
X1706440D01*
G01X1705830Y1254908D02*
X1707990D01*
G01X1708180Y1254708D02*
X1705610D01*
G01X1705460Y1252908D02*
X1708090D01*
G01X1707910Y1252658D02*
X1707820Y1252568D01*
G01X1707970Y1252728D02*
X1707910Y1252658D01*
G01X1708100Y1252918D02*
X1707970Y1252728D01*
G01X1707860Y1252598D02*
X1705710D01*
G01X1705530Y1252798D02*
X1708020D01*
G01X1708220Y1253168D02*
X1708280Y1253338D01*
G01X1708180Y1253068D02*
X1708220Y1253168D01*
G01X1708180Y1253058D02*
Y1253068D01*
G01X1708110Y1252928D02*
X1708180Y1253058D01*
G01X1708100Y1252918D02*
X1708110Y1252928D01*
G01X1708270Y1253298D02*
X1707455D01*
G01X1707460D02*
X1707520D01*
G01X1707420Y1253238D02*
X1707110Y1252978D01*
G01X1707450Y1253288D02*
X1707420Y1253238D01*
G01X1707250Y1253098D02*
X1708200D01*
G01X1708230Y1253208D02*
X1707440D01*
G01X1708200D02*
X1708230D01*
G01X1707450Y1254118D02*
X1707420Y1254168D01*
G01X1707570Y1253728D02*
X1707450Y1254118D01*
G01X1707570Y1253668D02*
Y1253728D01*
G01X1707450Y1253288D02*
X1707570Y1253668D01*
G01X1707380Y1254208D02*
X1708640D01*
G01X1708830Y1254008D02*
X1707490D01*
G01X1707550Y1253798D02*
X1709010D01*
G01X1708310Y1253598D02*
X1707550D01*
G01X1707490Y1253408D02*
X1708290D01*
G01X1707380Y1252298D02*
X1706220D01*
G01X1706920Y1258798D02*
X1707390D01*
G01X1707410Y1259008D02*
X1706940D01*
G01X1706960Y1259208D02*
X1707420D01*
G01X1707450Y1259508D02*
X1706980D01*
G01X1706990Y1259708D02*
X1707460D01*
G01X1707480Y1259908D02*
X1707010D01*
G01X1707030Y1260098D02*
X1707490D01*
G01X1707510Y1260298D02*
X1707050D01*
G01X1707060Y1260508D02*
X1707530D01*
G01X1707550Y1260708D02*
X1707080D01*
G01X1707090Y1260908D02*
X1707560D01*
G01X1707580Y1261098D02*
X1707110D01*
G01X1707130Y1261298D02*
X1707590D01*
G01X1707610Y1261508D02*
X1707140D01*
G01X1707160Y1261708D02*
X1707620D01*
G01X1707640Y1261908D02*
X1707180D01*
G01X1707190Y1262098D02*
X1707660D01*
G01X1707680Y1262298D02*
X1707210D01*
G01X1707220Y1262508D02*
X1707690D01*
G01X1707710Y1262708D02*
X1707240D01*
G01X1707720Y1262788D02*
X1707810Y1262878D01*
G01X1708140Y1264738D02*
X1708260D01*
G01X1707980Y1264748D02*
X1708140Y1264738D01*
G01X1707890Y1264908D02*
X1707420D01*
G01X1707430Y1265008D02*
X1707900D01*
G01Y1265098D02*
X1707440D01*
G01Y1265208D02*
X1707910D01*
G01X1707920Y1265298D02*
X1707450D01*
G01X1707460Y1265408D02*
X1707930D01*
G01X1708330Y1266968D02*
X1708260D01*
G01X1708340Y1266958D02*
X1708330Y1266968D01*
G01X1708600Y1266888D02*
X1708340Y1266958D01*
G01X1708610Y1266878D02*
X1708600Y1266888D01*
G01X1708810Y1266708D02*
X1708610Y1266878D01*
G01X1708820Y1266698D02*
X1708810Y1266708D01*
G01X1708940Y1266468D02*
X1708820Y1266698D01*
G01X1708950Y1266448D02*
X1708940Y1266468D01*
G01X1708970Y1266168D02*
X1708950Y1266448D01*
G01X1708970Y1266158D02*
Y1266168D01*
G01X1708890Y1265898D02*
X1708970Y1266158D01*
G01X1708880Y1265888D02*
X1708890Y1265898D01*
G01X1708720Y1265688D02*
X1708880Y1265888D01*
G01X1708710Y1265668D02*
X1708720Y1265688D01*
G01X1708480Y1265548D02*
X1708710Y1265668D01*
G01X1708460Y1265548D02*
X1708480D01*
G01X1708340Y1265528D02*
X1708460Y1265548D01*
G01X1708330Y1265528D02*
X1708340D01*
G01X1708270Y1265518D02*
X1708330Y1265528D01*
G01X1708250Y1265518D02*
X1708270D01*
G01X1707840Y1266798D02*
X1708700D01*
G01X1708810Y1266708D02*
X1706920D01*
G01X1707200Y1266508D02*
X1708920D01*
G01X1708960Y1266298D02*
X1707330D01*
G01X1708820Y1265798D02*
X1698710D01*
G01Y1266008D02*
X1708920D01*
G01X1709230Y1265708D02*
X1709860D01*
G01X1709960Y1265798D02*
X1709330D01*
G01X1709420Y1265908D02*
X1710060D01*
G01X1710150Y1266008D02*
X1709520D01*
G01X1709620Y1266098D02*
X1710250D01*
G01X1710340Y1266208D02*
X1709720D01*
G01X1709810Y1266298D02*
X1710440D01*
G01X1710540Y1266408D02*
X1709910D01*
G01X1710010Y1266508D02*
X1710640D01*
G01X1710830Y1266708D02*
X1710200D01*
G01X1710390Y1266908D02*
X1711020D01*
G01X1709770Y1265598D02*
X1709140D01*
G01X1709040Y1265508D02*
X1709670D01*
G01X1709570Y1265408D02*
X1708940D01*
G01X1708840Y1265298D02*
X1709480D01*
G01X1709380Y1265208D02*
X1708750D01*
G01X1708650Y1265098D02*
X1709290D01*
G01X1709190Y1265008D02*
X1708560D01*
G01X1708460Y1264908D02*
X1709090D01*
G01X1708940Y1262878D02*
X1707810D01*
G01X1708980Y1262898D02*
X1708940Y1262878D01*
G01X1708980Y1262908D02*
Y1262898D01*
G01Y1264728D02*
Y1262908D01*
G01Y1264738D02*
Y1264728D01*
G01X1709010Y1264818D02*
X1708980Y1264738D01*
G01X1708460Y1264158D02*
X1708350Y1264138D01*
G01X1708520Y1264058D02*
X1708460Y1264158D01*
G01X1708520Y1263458D02*
Y1264058D01*
G01X1708420Y1263358D02*
X1708520Y1263458D01*
G01X1707870Y1263358D02*
X1708420D01*
G01X1708490Y1264098D02*
X1708980D01*
G01Y1264008D02*
X1708520D01*
G01Y1263908D02*
X1708980D01*
G01Y1263798D02*
X1708520D01*
G01Y1263708D02*
X1708980D01*
G01Y1263598D02*
X1708520D01*
G01Y1263508D02*
X1708980D01*
G01Y1263408D02*
X1708470D01*
G01X1708980Y1263208D02*
X1706810D01*
G01X1706620Y1263008D02*
X1708980D01*
G01Y1264298D02*
X1707200D01*
G01Y1264508D02*
X1708980D01*
G01Y1264708D02*
X1707200D01*
G01X1708260Y1264738D02*
X1708330Y1264768D01*
G01X1708360Y1264798D02*
X1709000D01*
G01X1708360Y1254508D02*
X1706810D01*
G01X1707250Y1254298D02*
X1708550D01*
G01X1708730Y1254098D02*
X1707460D01*
G01X1707510Y1253908D02*
X1708920D01*
G01X1709110Y1253708D02*
X1708420D01*
G01X1708280Y1253358D02*
Y1253338D01*
G01X1708320Y1253628D02*
X1708280Y1253358D01*
G01X1708380Y1253708D02*
X1708320Y1253628D01*
G01X1708300Y1253508D02*
X1707520D01*
G01X1708380Y1253708D02*
X1708490Y1253688D01*
G01X1707570Y1253708D02*
X1708380D01*
G01X1708570Y1253598D02*
X1709200D01*
G01X1709290Y1253508D02*
X1708660D01*
G01X1708750Y1253408D02*
X1709390D01*
G01X1709440Y1253298D02*
X1709480D01*
G01X1709490D02*
X1708850D01*
G01X1708940Y1253208D02*
X1709575D01*
G01X1709570D02*
X1709520D01*
G01X1709675Y1253098D02*
X1709030D01*
G01X1709120Y1253008D02*
X1709760D01*
G01X1709850Y1252908D02*
X1709215D01*
G01X1709315Y1252798D02*
X1709950D01*
G01X1710040Y1252708D02*
X1709400D01*
G01X1709505Y1252598D02*
X1710130D01*
G01X1710230Y1252508D02*
X1709590D01*
G01X1709680Y1252408D02*
X1710320D01*
G01X1710410Y1252298D02*
X1709770D01*
G01X1709860Y1252208D02*
X1710510D01*
G01X1710690Y1252008D02*
X1710050D01*
G01X1709960Y1252098D02*
X1710600D01*
G01X1710780Y1251908D02*
X1710140D01*
G01X1710240Y1251798D02*
X1710880D01*
G01X1710970Y1251708D02*
X1710330D01*
G01X1710420Y1251598D02*
X1711060D01*
G01X1711160Y1251508D02*
X1710510D01*
G01X1710610Y1251408D02*
X1711250D01*
G01X1711340Y1251298D02*
X1710700D01*
G01X1710790Y1251208D02*
X1711440D01*
G01X1711530Y1251098D02*
X1710890D01*
G01X1710980Y1251008D02*
X1711620D01*
G01X1711810Y1250798D02*
X1711170D01*
G01X1711350Y1250598D02*
X1711960D01*
G01X1711950Y1250658D02*
X1708140Y1254748D01*
G01X1711620Y1250318D02*
X1711640Y1250298D01*
G01X1708490Y1253688D02*
X1711620Y1250318D01*
G01X1711540Y1250408D02*
X1711760D01*
G01X1694680Y1250638D02*
X1700100Y1256248D01*
G01X1694650Y1250608D02*
X1694680Y1250638D01*
G01X1694660Y1250588D02*
X1694650Y1250608D01*
G01X1694970Y1250318D02*
X1694660Y1250588D01*
G01X1695000Y1250308D02*
X1694970Y1250318D01*
G01X1695020D02*
X1695000Y1250308D01*
G01X1700140Y1255618D02*
X1695020Y1250318D01*
G01X1695100Y1250408D02*
X1694870D01*
G01X1694750Y1250508D02*
X1695200D01*
G01X1695300Y1250598D02*
X1694650D01*
G01X1694740Y1250708D02*
X1695400D01*
G01X1695490Y1250798D02*
X1694840D01*
G01X1694930Y1250908D02*
X1695590D01*
G01X1695680Y1251008D02*
X1695030D01*
G01X1695120Y1251098D02*
X1695780D01*
G01X1695880Y1251208D02*
X1695220D01*
G01X1695320Y1251298D02*
X1695970D01*
G01X1696070Y1251408D02*
X1695420D01*
G01X1695510Y1251508D02*
X1696170D01*
G01X1696260Y1251598D02*
X1695610D01*
G01X1695710Y1251708D02*
X1696360D01*
G01X1696460Y1251798D02*
X1695800D01*
G01X1695900Y1251908D02*
X1696550D01*
G01X1708330Y1264768D02*
X1712910Y1269508D01*
G01X1712940Y1268898D02*
X1709010Y1264818D01*
G01X1710100Y1266598D02*
X1710730D01*
G01X1710920Y1266798D02*
X1710290D01*
G01X1710490Y1267008D02*
X1711120D01*
G01X1711220Y1267098D02*
X1710590D01*
G01X1710680Y1267208D02*
X1711310D01*
G01X1711410Y1267298D02*
X1710780D01*
G01X1710880Y1267408D02*
X1711500D01*
G01X1711600Y1267508D02*
X1710970D01*
G01X1711160Y1267708D02*
X1711790D01*
G01X1711990Y1267908D02*
X1711360D01*
G01X1711550Y1268098D02*
X1712180D01*
G01X1712080Y1268008D02*
X1711460D01*
G01X1711650Y1268208D02*
X1712270D01*
G01X1712370Y1268298D02*
X1711740D01*
G01X1711840Y1268408D02*
X1712470D01*
G01X1712570Y1268508D02*
X1711940D01*
G01X1712030Y1268598D02*
X1712660D01*
G01X1712760Y1268708D02*
X1712130D01*
G01X1712230Y1268798D02*
X1712850D01*
G01X1712960Y1269008D02*
X1712420D01*
G01X1712950Y1268928D02*
X1712960Y1269008D01*
G01X1712940Y1268898D02*
X1712950Y1268928D01*
G01X1712330Y1268908D02*
X1712940D01*
G01X1712960Y1269498D02*
X1712910Y1269508D01*
G01X1712960Y1269008D02*
Y1269498D01*
G01X1712900Y1269508D02*
X1712940D01*
G01X1712960Y1269408D02*
X1712810D01*
G01X1712710Y1269298D02*
X1712960D01*
G01Y1269208D02*
X1712610D01*
G01X1712520Y1269098D02*
X1712960D01*
G01X1711890Y1267798D02*
X1711260D01*
G01X1711070Y1267598D02*
X1711700D01*
G01X1711720Y1250908D02*
X1711070D01*
G01X1711260Y1250708D02*
X1711900D01*
G01X1711670Y1250318D02*
X1711640Y1250298D01*
G01X1711960Y1250608D02*
X1711670Y1250318D01*
G01X1711970Y1250628D02*
X1711960Y1250608D01*
G01Y1250638D02*
X1711970Y1250628D01*
G01X1711950Y1250658D02*
X1711960Y1250638D01*
G01X1711440Y1250508D02*
X1711860D01*
G54D11*
G01X964481Y0D02*
G03X954008I-5236J0D01*
G01X932986D02*
G03X922513I-5236J0D01*
G01X1058966D02*
G03X1048494I-5236J0D01*
G01X1027471D02*
G03X1016999I-5236J0D01*
G01X995976D02*
G03X985504I-5236J0D01*
G01X1090461D02*
G03X1079989I-5236J0D01*
G54D21*
G01X489037Y-206331D02*
X489911Y-205456D01*
X490566Y-203998D01*
X491003Y-201955D01*
X490566Y-200206D01*
X489693Y-199039D01*
X488164Y-198164D01*
X482269D01*
Y-215664D01*
X489474D01*
X491003Y-214498D01*
X491876Y-212747D01*
X492313Y-210706D01*
X491876Y-208664D01*
X490566Y-206914D01*
X489037Y-206331D01*
X482269D01*
G01X501734Y-215664D02*
Y-203998D01*
G01Y-206331D02*
X502826Y-205164D01*
X503918Y-204289D01*
X505446Y-203998D01*
X506537Y-204289D01*
X507848Y-205164D01*
G01X517706Y-220914D02*
X519016Y-221497D01*
X520763Y-220914D01*
X521854Y-219748D01*
X522728Y-218289D01*
X524037Y-213623D01*
X526876Y-203998D01*
G01X519889D02*
X524037Y-213623D01*
G01X543284Y-205456D02*
X541756Y-204289D01*
X540446Y-203998D01*
X538699Y-204581D01*
X537389Y-205747D01*
X536516Y-207789D01*
X536297Y-209831D01*
X536516Y-211873D01*
X537389Y-213623D01*
X538699Y-215081D01*
X540446Y-215664D01*
X541974Y-215081D01*
X543284Y-213914D01*
G01X554016Y-207789D02*
X561003D01*
X560348Y-205747D01*
X559256Y-204581D01*
X557728Y-203998D01*
X556199Y-204289D01*
X554889Y-205164D01*
X554016Y-207206D01*
X553579Y-208956D01*
Y-210706D01*
X554016Y-212456D01*
X555108Y-214206D01*
X556418Y-215372D01*
X557946Y-215664D01*
X559474Y-215081D01*
X561003Y-213331D01*
G01X597094Y-199623D02*
X595784Y-198747D01*
X594256Y-198164D01*
X592509D01*
X590544Y-199039D01*
X589016Y-200497D01*
X587924Y-202248D01*
X587051Y-205164D01*
X586832Y-207789D01*
X587269Y-210414D01*
X587924Y-212164D01*
X589234Y-213914D01*
X590763Y-215081D01*
X592291Y-215664D01*
X593819D01*
X595348Y-215081D01*
X596658Y-214206D01*
X597750Y-213040D01*
G01X613721Y-215664D02*
Y-203998D01*
G01Y-206039D02*
X612848Y-204873D01*
X611537Y-204289D01*
X610009Y-203998D01*
X608481Y-204581D01*
X607171Y-205747D01*
X606297Y-207497D01*
X605861Y-209831D01*
X606297Y-212164D01*
X607171Y-213914D01*
X608481Y-215081D01*
X610009Y-215664D01*
X611537Y-215372D01*
X612848Y-214498D01*
X613721Y-213331D01*
G01X623579Y-215664D02*
Y-203998D01*
G01Y-206914D02*
X624453Y-205456D01*
X625763Y-204289D01*
X627509Y-203998D01*
X629037Y-204289D01*
X630348Y-205456D01*
X631003Y-207497D01*
Y-215664D01*
G01X640206Y-220914D02*
X641516Y-221497D01*
X643263Y-220914D01*
X644354Y-219748D01*
X645228Y-218289D01*
X646537Y-213623D01*
X649376Y-203998D01*
G01X642389D02*
X646537Y-213623D01*
G01X662291Y-215664D02*
X660981Y-215372D01*
X659671Y-214206D01*
X658797Y-212164D01*
X658361Y-209831D01*
X658797Y-207497D01*
X659671Y-205456D01*
X660981Y-204289D01*
X662291Y-203998D01*
X663601Y-204289D01*
X664911Y-205456D01*
X665784Y-207497D01*
X666003Y-209831D01*
X665784Y-212164D01*
X664911Y-214206D01*
X663601Y-215372D01*
X662291Y-215664D01*
G01X676079D02*
Y-203998D01*
G01Y-206914D02*
X676953Y-205456D01*
X678263Y-204289D01*
X680009Y-203998D01*
X681537Y-204289D01*
X682848Y-205456D01*
X683503Y-207497D01*
Y-215664D01*
G01X710424D02*
Y-198164D01*
X715883D01*
X717629Y-199039D01*
X718721Y-200206D01*
X719158Y-202539D01*
X718721Y-204873D01*
X717411Y-206331D01*
X715883Y-207206D01*
X710424D01*
G01X715883D02*
X719158Y-215664D01*
G01X732291Y-216247D02*
X731854Y-215956D01*
Y-215372D01*
X732291Y-215081D01*
X732728Y-215372D01*
Y-215956D01*
X732291Y-216247D01*
G01X744988Y-215664D02*
Y-198164D01*
X749354D01*
X751101Y-199039D01*
X752411Y-200206D01*
X753503Y-201955D01*
X754376Y-203998D01*
X754594Y-206914D01*
X754376Y-209831D01*
X753503Y-211873D01*
X752411Y-213623D01*
X751101Y-214789D01*
X749354Y-215664D01*
X744988D01*
G01X762924D02*
Y-198164D01*
X768164D01*
X769911Y-199039D01*
X771221Y-201081D01*
X771658Y-203414D01*
X771221Y-205747D01*
X770129Y-207497D01*
X768164Y-208373D01*
X762924D01*
G01X786537Y-206331D02*
X787411Y-205456D01*
X788066Y-203998D01*
X788503Y-201955D01*
X788066Y-200206D01*
X787193Y-199039D01*
X785664Y-198164D01*
X779769D01*
Y-215664D01*
X786974D01*
X788503Y-214498D01*
X789376Y-212747D01*
X789813Y-210706D01*
X789376Y-208664D01*
X788066Y-206914D01*
X786537Y-206331D01*
X779769D01*
G01X595364Y-170664D02*
Y-153164D01*
X601041Y-167747D01*
X606718Y-153164D01*
Y-170664D01*
G01X618541D02*
X617231Y-170372D01*
X615921Y-169206D01*
X615047Y-167164D01*
X614611Y-164831D01*
X615047Y-162497D01*
X615921Y-160456D01*
X617231Y-159289D01*
X618541Y-158998D01*
X619851Y-159289D01*
X621161Y-160456D01*
X622034Y-162497D01*
X622253Y-164831D01*
X622034Y-167164D01*
X621161Y-169206D01*
X619851Y-170372D01*
X618541Y-170664D01*
G01X639971Y-153164D02*
Y-170664D01*
G01Y-168040D02*
X639098Y-169498D01*
X637787Y-170372D01*
X636259Y-170664D01*
X634513Y-170081D01*
X633203Y-168623D01*
X632329Y-166873D01*
X632111Y-164831D01*
X632329Y-162789D01*
X633203Y-161039D01*
X634513Y-159581D01*
X636259Y-158998D01*
X637787Y-159289D01*
X638879Y-159873D01*
X639971Y-161039D01*
G01X650266Y-162789D02*
X657253D01*
X656598Y-160747D01*
X655506Y-159581D01*
X653978Y-158998D01*
X652449Y-159289D01*
X651139Y-160164D01*
X650266Y-162206D01*
X649829Y-163956D01*
Y-165706D01*
X650266Y-167456D01*
X651358Y-169206D01*
X652668Y-170372D01*
X654196Y-170664D01*
X655724Y-170081D01*
X657253Y-168331D01*
G01X671041Y-170664D02*
Y-153164D01*
G01X839441Y-215664D02*
Y-198164D01*
X836821Y-201664D01*
G01Y-215664D02*
X842061D01*
G01X852793Y-208373D02*
X854321Y-206331D01*
X855631Y-205164D01*
X857378Y-204581D01*
X858906Y-205164D01*
X859998Y-206331D01*
X860871Y-208081D01*
X861089Y-210122D01*
X860871Y-211873D01*
X859998Y-213623D01*
X858687Y-215081D01*
X857159Y-215664D01*
X855413Y-215081D01*
X853884Y-213331D01*
X853011Y-210706D01*
X852793Y-207789D01*
X853229Y-203998D01*
X853884Y-201955D01*
X854976Y-199914D01*
X856504Y-198456D01*
X858033Y-198164D01*
X859561Y-198747D01*
X860653Y-200206D01*
G01X869638Y-212164D02*
X870947Y-214206D01*
X872694Y-215372D01*
X874659Y-215664D01*
X876406Y-215372D01*
X878153Y-213914D01*
X879244Y-212164D01*
X879463Y-210414D01*
X879026Y-208373D01*
X877498Y-206914D01*
X875969Y-206331D01*
X874004D01*
G01X875969D02*
X877279Y-205456D01*
X878371Y-203998D01*
X878808Y-202248D01*
X878371Y-200497D01*
X877279Y-199039D01*
X875314Y-198164D01*
X873349Y-198456D01*
X871384Y-199623D01*
G01X891941Y-215664D02*
Y-198164D01*
X889321Y-201664D01*
G01Y-215664D02*
X894561D01*
G01X909004D02*
X909441Y-211873D01*
X910096Y-208664D01*
X910969Y-205747D01*
X912061Y-202539D01*
X913808Y-198164D01*
X905074D01*
G01X826324Y-170664D02*
Y-153164D01*
X831564D01*
X833311Y-154039D01*
X834621Y-156081D01*
X835058Y-158414D01*
X834621Y-160747D01*
X833529Y-162497D01*
X831564Y-163373D01*
X826324D01*
G01X852994Y-154623D02*
X851684Y-153747D01*
X850156Y-153164D01*
X848409D01*
X846444Y-154039D01*
X844916Y-155497D01*
X843824Y-157248D01*
X842951Y-160164D01*
X842732Y-162789D01*
X843169Y-165414D01*
X843824Y-167164D01*
X845134Y-168914D01*
X846663Y-170081D01*
X848191Y-170664D01*
X849719D01*
X851248Y-170081D01*
X852558Y-169206D01*
X853650Y-168040D01*
G01X867437Y-161331D02*
X868311Y-160456D01*
X868966Y-158998D01*
X869403Y-156955D01*
X868966Y-155206D01*
X868093Y-154039D01*
X866564Y-153164D01*
X860669D01*
Y-170664D01*
X867874D01*
X869403Y-169498D01*
X870276Y-167747D01*
X870713Y-165706D01*
X870276Y-163664D01*
X868966Y-161914D01*
X867437Y-161331D01*
X860669D01*
G01X876641Y-176497D02*
X889741D01*
G01X895669Y-170664D02*
Y-153164D01*
X905713Y-170664D01*
Y-153164D01*
G01X918191Y-170664D02*
X916444Y-170372D01*
X914916Y-169206D01*
X913606Y-167456D01*
X912732Y-165414D01*
X912296Y-163081D01*
Y-160747D01*
X912732Y-158414D01*
X913606Y-156372D01*
X914916Y-154623D01*
X916444Y-153456D01*
X918191Y-153164D01*
X919937Y-153456D01*
X921466Y-154623D01*
X922776Y-156372D01*
X923650Y-158414D01*
X924086Y-160747D01*
Y-163081D01*
X923650Y-165414D01*
X922776Y-167456D01*
X921466Y-169206D01*
X919937Y-170372D01*
X918191Y-170664D01*
G01X1000741Y-215664D02*
Y-198164D01*
X998121Y-201664D01*
G01Y-215664D02*
X1003361D01*
G01X969032Y-153164D02*
X974491Y-170664D01*
X979950Y-153164D01*
G01X996358Y-170664D02*
X987624D01*
Y-153164D01*
X996358D01*
G01X992864Y-161622D02*
X987624D01*
G01X1005124Y-170664D02*
Y-153164D01*
X1010583D01*
X1012329Y-154039D01*
X1013421Y-155206D01*
X1013858Y-157539D01*
X1013421Y-159873D01*
X1012111Y-161331D01*
X1010583Y-162206D01*
X1005124D01*
G01X1010583D02*
X1013858Y-170664D01*
G01X1026991Y-171247D02*
X1026554Y-170956D01*
Y-170372D01*
X1026991Y-170081D01*
X1027428Y-170372D01*
Y-170956D01*
X1026991Y-171247D01*
G01X1106941Y-198164D02*
Y-215664D01*
G01X1101919Y-198164D02*
X1111963D01*
G01X1119856Y-213331D02*
X1121603Y-214789D01*
X1123568Y-215664D01*
X1125314D01*
X1127061Y-214789D01*
X1128371Y-213331D01*
X1129026Y-211289D01*
X1128589Y-209248D01*
X1127498Y-207497D01*
X1125533Y-206331D01*
X1122913Y-205747D01*
X1121384Y-204581D01*
X1120729Y-202539D01*
X1121166Y-200497D01*
X1122258Y-199039D01*
X1123786Y-198164D01*
X1125314D01*
X1126843Y-198747D01*
X1128153Y-200206D01*
G01X1139321Y-198164D02*
X1144561D01*
G01X1141941D02*
Y-215664D01*
G01X1139321D02*
X1144561D01*
G01X1155074Y-198164D02*
Y-215664D01*
X1163808D01*
G01X1172138D02*
Y-198164D01*
G01X1180434D02*
X1172138Y-208956D01*
G01X1181744Y-215664D02*
X1175849Y-203998D01*
G01X1102574Y-153164D02*
Y-170664D01*
X1111308D01*
G01X1128371D02*
Y-158998D01*
G01Y-161039D02*
X1127498Y-159873D01*
X1126187Y-159289D01*
X1124659Y-158998D01*
X1123131Y-159581D01*
X1121821Y-160747D01*
X1120947Y-162497D01*
X1120511Y-164831D01*
X1120947Y-167164D01*
X1121821Y-168914D01*
X1123131Y-170081D01*
X1124659Y-170664D01*
X1126187Y-170372D01*
X1127498Y-169498D01*
X1128371Y-168331D01*
G01X1137356Y-175914D02*
X1138666Y-176497D01*
X1140413Y-175914D01*
X1141504Y-174748D01*
X1142378Y-173289D01*
X1143687Y-168623D01*
X1146526Y-158998D01*
G01X1139539D02*
X1143687Y-168623D01*
G01X1156166Y-162789D02*
X1163153D01*
X1162498Y-160747D01*
X1161406Y-159581D01*
X1159878Y-158998D01*
X1158349Y-159289D01*
X1157039Y-160164D01*
X1156166Y-162206D01*
X1155729Y-163956D01*
Y-165706D01*
X1156166Y-167456D01*
X1157258Y-169206D01*
X1158568Y-170372D01*
X1160096Y-170664D01*
X1161624Y-170081D01*
X1163153Y-168331D01*
G01X1173884Y-170664D02*
Y-158998D01*
G01Y-161331D02*
X1174976Y-160164D01*
X1176068Y-159289D01*
X1177596Y-158998D01*
X1178687Y-159289D01*
X1179998Y-160164D01*
G01X1244688Y-170664D02*
Y-153164D01*
X1249054D01*
X1250801Y-154039D01*
X1252111Y-155206D01*
X1253203Y-156955D01*
X1254076Y-158998D01*
X1254294Y-161914D01*
X1254076Y-164831D01*
X1253203Y-166873D01*
X1252111Y-168623D01*
X1250801Y-169789D01*
X1249054Y-170664D01*
X1244688D01*
G01X1263716Y-162789D02*
X1270703D01*
X1270048Y-160747D01*
X1268956Y-159581D01*
X1267428Y-158998D01*
X1265899Y-159289D01*
X1264589Y-160164D01*
X1263716Y-162206D01*
X1263279Y-163956D01*
Y-165706D01*
X1263716Y-167456D01*
X1264808Y-169206D01*
X1266118Y-170372D01*
X1267646Y-170664D01*
X1269174Y-170081D01*
X1270703Y-168331D01*
G01X1281216Y-168623D02*
X1282308Y-169789D01*
X1283836Y-170664D01*
X1285146D01*
X1286456Y-170081D01*
X1287329Y-169206D01*
X1287766Y-168040D01*
X1287548Y-166289D01*
X1286674Y-165414D01*
X1282744Y-163664D01*
X1281871Y-161622D01*
X1282308Y-160164D01*
X1283181Y-159289D01*
X1284491Y-158998D01*
X1285801Y-159289D01*
X1287111Y-160164D01*
G01X1301991Y-158998D02*
Y-170664D01*
G01Y-154331D02*
X1301554Y-154039D01*
Y-153456D01*
X1301991Y-153164D01*
X1302428Y-153456D01*
Y-154039D01*
X1301991Y-154331D01*
G01X1316434Y-175039D02*
X1317963Y-176206D01*
X1319709Y-176497D01*
X1321237Y-176206D01*
X1322548Y-174748D01*
X1323421Y-172706D01*
Y-158998D01*
G01Y-161331D02*
X1322548Y-160164D01*
X1321237Y-159289D01*
X1319709Y-158998D01*
X1317963Y-159581D01*
X1316871Y-160747D01*
X1315997Y-162789D01*
X1315561Y-164831D01*
X1315779Y-166581D01*
X1316653Y-168623D01*
X1317963Y-170081D01*
X1319709Y-170664D01*
X1321019Y-170372D01*
X1322548Y-169206D01*
X1323421Y-168040D01*
G01X1333279Y-170664D02*
Y-158998D01*
G01Y-161914D02*
X1334153Y-160456D01*
X1335463Y-159289D01*
X1337209Y-158998D01*
X1338737Y-159289D01*
X1340048Y-160456D01*
X1340703Y-162497D01*
Y-170664D01*
G01X1351216Y-162789D02*
X1358203D01*
X1357548Y-160747D01*
X1356456Y-159581D01*
X1354928Y-158998D01*
X1353399Y-159289D01*
X1352089Y-160164D01*
X1351216Y-162206D01*
X1350779Y-163956D01*
Y-165706D01*
X1351216Y-167456D01*
X1352308Y-169206D01*
X1353618Y-170372D01*
X1355146Y-170664D01*
X1356674Y-170081D01*
X1358203Y-168331D01*
G01X1368934Y-170664D02*
Y-158998D01*
G01Y-161331D02*
X1370026Y-160164D01*
X1371118Y-159289D01*
X1372646Y-158998D01*
X1373737Y-159289D01*
X1375048Y-160164D01*
G01X1266991Y-215664D02*
X1265244Y-215372D01*
X1263716Y-214206D01*
X1262406Y-212456D01*
X1261532Y-210414D01*
X1261096Y-208081D01*
Y-205747D01*
X1261532Y-203414D01*
X1262406Y-201372D01*
X1263716Y-199623D01*
X1265244Y-198456D01*
X1266991Y-198164D01*
X1268737Y-198456D01*
X1270266Y-199623D01*
X1271576Y-201372D01*
X1272450Y-203414D01*
X1272886Y-205747D01*
Y-208081D01*
X1272450Y-210414D01*
X1271576Y-212456D01*
X1270266Y-214206D01*
X1268737Y-215372D01*
X1266991Y-215664D01*
G01X1268737Y-210997D02*
X1271358Y-215664D01*
G01X1279688Y-198164D02*
Y-210706D01*
X1280561Y-213331D01*
X1282308Y-215081D01*
X1284491Y-215664D01*
X1286674Y-215081D01*
X1288421Y-213331D01*
X1289294Y-210706D01*
Y-198164D01*
G01X1299371D02*
X1304611D01*
G01X1301991D02*
Y-215664D01*
G01X1299371D02*
X1304611D01*
G01X1314469D02*
Y-198164D01*
X1324513Y-215664D01*
Y-198164D01*
G01X1341794Y-199623D02*
X1340484Y-198747D01*
X1338956Y-198164D01*
X1337209D01*
X1335244Y-199039D01*
X1333716Y-200497D01*
X1332624Y-202248D01*
X1331751Y-205164D01*
X1331532Y-207789D01*
X1331969Y-210414D01*
X1332624Y-212164D01*
X1333934Y-213914D01*
X1335463Y-215081D01*
X1336991Y-215664D01*
X1338519D01*
X1340048Y-215081D01*
X1341358Y-214206D01*
X1342450Y-213040D01*
G01X1354491Y-215664D02*
Y-207789D01*
X1350124Y-198164D01*
G01X1358858D02*
X1354491Y-207789D01*
G01X1415691Y-198164D02*
X1413944Y-198747D01*
X1412634Y-200206D01*
X1411761Y-201955D01*
X1411106Y-204289D01*
X1410888Y-206914D01*
X1411106Y-209539D01*
X1411761Y-211873D01*
X1412634Y-213623D01*
X1413944Y-215081D01*
X1415691Y-215664D01*
X1417437Y-215081D01*
X1418748Y-213623D01*
X1419621Y-211873D01*
X1420276Y-209539D01*
X1420494Y-206914D01*
X1420276Y-204289D01*
X1419621Y-201955D01*
X1418748Y-200206D01*
X1417437Y-198747D01*
X1415691Y-198164D01*
G01X1429043Y-208373D02*
X1430571Y-206331D01*
X1431881Y-205164D01*
X1433628Y-204581D01*
X1435156Y-205164D01*
X1436248Y-206331D01*
X1437121Y-208081D01*
X1437339Y-210122D01*
X1437121Y-211873D01*
X1436248Y-213623D01*
X1434937Y-215081D01*
X1433409Y-215664D01*
X1431663Y-215081D01*
X1430134Y-213331D01*
X1429261Y-210706D01*
X1429043Y-207789D01*
X1429479Y-203998D01*
X1430134Y-201955D01*
X1431226Y-199914D01*
X1432754Y-198456D01*
X1434283Y-198164D01*
X1435811Y-198747D01*
X1436903Y-200206D01*
G01X1446761Y-216247D02*
X1454621Y-198164D01*
G01X1468191D02*
X1466444Y-198747D01*
X1465134Y-200206D01*
X1464261Y-201955D01*
X1463606Y-204289D01*
X1463388Y-206914D01*
X1463606Y-209539D01*
X1464261Y-211873D01*
X1465134Y-213623D01*
X1466444Y-215081D01*
X1468191Y-215664D01*
X1469937Y-215081D01*
X1471248Y-213623D01*
X1472121Y-211873D01*
X1472776Y-209539D01*
X1472994Y-206914D01*
X1472776Y-204289D01*
X1472121Y-201955D01*
X1471248Y-200206D01*
X1469937Y-198747D01*
X1468191Y-198164D01*
G01X1481979Y-213623D02*
X1483508Y-215081D01*
X1485254Y-215664D01*
X1487001Y-215081D01*
X1488529Y-213331D01*
X1489621Y-210706D01*
X1490058Y-208081D01*
Y-204873D01*
X1489621Y-202248D01*
X1488529Y-199914D01*
X1487219Y-198747D01*
X1485691Y-198164D01*
X1483944Y-198747D01*
X1482634Y-199914D01*
X1481761Y-201664D01*
X1481324Y-203998D01*
X1481761Y-206039D01*
X1482853Y-208081D01*
X1484163Y-209248D01*
X1485691Y-209539D01*
X1487437Y-208956D01*
X1488748Y-207497D01*
X1490058Y-204873D01*
G01X1499261Y-216247D02*
X1507121Y-198164D01*
G01X1516543Y-201081D02*
X1517853Y-199331D01*
X1519381Y-198456D01*
X1521128Y-198164D01*
X1523311Y-198747D01*
X1524839Y-200206D01*
X1525276Y-201955D01*
X1525058Y-203706D01*
X1524184Y-205164D01*
X1519818Y-208081D01*
X1517853Y-210122D01*
X1516543Y-213040D01*
X1516106Y-215664D01*
X1525276D01*
G01X1538191Y-198164D02*
X1536444Y-198747D01*
X1535134Y-200206D01*
X1534261Y-201955D01*
X1533606Y-204289D01*
X1533388Y-206914D01*
X1533606Y-209539D01*
X1534261Y-211873D01*
X1535134Y-213623D01*
X1536444Y-215081D01*
X1538191Y-215664D01*
X1539937Y-215081D01*
X1541248Y-213623D01*
X1542121Y-211873D01*
X1542776Y-209539D01*
X1542994Y-206914D01*
X1542776Y-204289D01*
X1542121Y-201955D01*
X1541248Y-200206D01*
X1539937Y-198747D01*
X1538191Y-198164D01*
G01X1555691Y-215664D02*
Y-198164D01*
X1553071Y-201664D01*
G01Y-215664D02*
X1558311D01*
G01X1572754D02*
X1573191Y-211873D01*
X1573846Y-208664D01*
X1574719Y-205747D01*
X1575811Y-202539D01*
X1577558Y-198164D01*
X1568824D01*
G01X1463388Y-170664D02*
Y-153164D01*
X1467754D01*
X1469501Y-154039D01*
X1470811Y-155206D01*
X1471903Y-156955D01*
X1472776Y-158998D01*
X1472994Y-161914D01*
X1472776Y-164831D01*
X1471903Y-166873D01*
X1470811Y-168623D01*
X1469501Y-169789D01*
X1467754Y-170664D01*
X1463388D01*
G01X1489621D02*
Y-158998D01*
G01Y-161039D02*
X1488748Y-159873D01*
X1487437Y-159289D01*
X1485909Y-158998D01*
X1484381Y-159581D01*
X1483071Y-160747D01*
X1482197Y-162497D01*
X1481761Y-164831D01*
X1482197Y-167164D01*
X1483071Y-168914D01*
X1484381Y-170081D01*
X1485909Y-170664D01*
X1487437Y-170372D01*
X1488748Y-169498D01*
X1489621Y-168331D01*
G01X1503191Y-153164D02*
Y-170664D01*
G01X1500134Y-158998D02*
X1506248D01*
G01X1517416Y-162789D02*
X1524403D01*
X1523748Y-160747D01*
X1522656Y-159581D01*
X1521128Y-158998D01*
X1519599Y-159289D01*
X1518289Y-160164D01*
X1517416Y-162206D01*
X1516979Y-163956D01*
Y-165706D01*
X1517416Y-167456D01*
X1518508Y-169206D01*
X1519818Y-170372D01*
X1521346Y-170664D01*
X1522874Y-170081D01*
X1524403Y-168331D01*
G01X94124Y107319D02*
X99174D01*
Y206019D01*
X123824D01*
Y21619D01*
X99174D01*
Y80319D01*
X94124D01*
Y107319D01*
G01X50767Y91953D02*
X50517Y92078D01*
X50225Y92161D01*
X49892D01*
X49517Y92036D01*
X49225Y91828D01*
X49017Y91578D01*
X48850Y91161D01*
X48808Y90786D01*
X48892Y90411D01*
X49017Y90161D01*
X49267Y89911D01*
X49558Y89744D01*
X49850Y89661D01*
X50142D01*
X50433Y89744D01*
X50683Y89869D01*
X50892Y90036D01*
G01X52033Y90161D02*
X52283Y89869D01*
X52617Y89703D01*
X52992Y89661D01*
X53325Y89703D01*
X53658Y89911D01*
X53867Y90161D01*
X53908Y90411D01*
X53825Y90703D01*
X53533Y90911D01*
X53242Y90994D01*
X52867D01*
G01X53242D02*
X53492Y91119D01*
X53700Y91328D01*
X53783Y91578D01*
X53700Y91828D01*
X53492Y92036D01*
X53117Y92161D01*
X52742Y92119D01*
X52367Y91953D01*
G01X55133Y90036D02*
X55383Y89828D01*
X55675Y89703D01*
X56050Y89661D01*
X56425Y89744D01*
X56717Y89911D01*
X56925Y90203D01*
X56967Y90536D01*
X56883Y90869D01*
X56675Y91078D01*
X56383Y91244D01*
X56092Y91286D01*
X55800Y91244D01*
X55425Y91078D01*
X55550Y92161D01*
X56675D01*
G01X59150D02*
X58817Y92078D01*
X58567Y91869D01*
X58400Y91619D01*
X58275Y91286D01*
X58233Y90911D01*
X58275Y90536D01*
X58400Y90203D01*
X58567Y89953D01*
X58817Y89744D01*
X59150Y89661D01*
X59483Y89744D01*
X59733Y89953D01*
X59900Y90203D01*
X60025Y90536D01*
X60067Y90911D01*
X60025Y91286D01*
X59900Y91619D01*
X59733Y91869D01*
X59483Y92078D01*
X59150Y92161D01*
G01X49017Y85500D02*
Y88000D01*
X50058D01*
X50392Y87875D01*
X50600Y87708D01*
X50683Y87375D01*
X50600Y87042D01*
X50350Y86833D01*
X50058Y86708D01*
X49017D01*
G01X50058D02*
X50683Y85500D01*
G01X52158Y86542D02*
X52450Y86833D01*
X52700Y87000D01*
X53033Y87083D01*
X53325Y87000D01*
X53533Y86833D01*
X53700Y86583D01*
X53742Y86292D01*
X53700Y86042D01*
X53533Y85792D01*
X53283Y85583D01*
X52992Y85500D01*
X52658Y85583D01*
X52367Y85833D01*
X52200Y86208D01*
X52158Y86625D01*
X52242Y87167D01*
X52367Y87458D01*
X52575Y87750D01*
X52867Y87958D01*
X53158Y88000D01*
X53450Y87917D01*
X53658Y87708D01*
G01X55258Y87583D02*
X55508Y87833D01*
X55800Y87958D01*
X56133Y88000D01*
X56550Y87917D01*
X56842Y87708D01*
X56925Y87458D01*
X56883Y87208D01*
X56717Y87000D01*
X55883Y86583D01*
X55508Y86292D01*
X55258Y85875D01*
X55175Y85500D01*
X56925D01*
G01X58442Y85792D02*
X58733Y85583D01*
X59067Y85500D01*
X59400Y85583D01*
X59692Y85833D01*
X59900Y86208D01*
X59983Y86583D01*
Y87042D01*
X59900Y87417D01*
X59692Y87750D01*
X59442Y87917D01*
X59150Y88000D01*
X58817Y87917D01*
X58567Y87750D01*
X58400Y87500D01*
X58317Y87167D01*
X58400Y86875D01*
X58608Y86583D01*
X58858Y86417D01*
X59150Y86375D01*
X59483Y86458D01*
X59733Y86667D01*
X59983Y87042D01*
G01X62300Y93000D02*
Y89000D01*
X69700D01*
G01X83517Y52500D02*
Y55000D01*
X84558D01*
X84892Y54875D01*
X85100Y54708D01*
X85183Y54375D01*
X85100Y54042D01*
X84850Y53833D01*
X84558Y53708D01*
X83517D01*
G01X84558D02*
X85183Y52500D01*
G01X86658Y53542D02*
X86950Y53833D01*
X87200Y54000D01*
X87533Y54083D01*
X87825Y54000D01*
X88033Y53833D01*
X88200Y53583D01*
X88242Y53292D01*
X88200Y53042D01*
X88033Y52792D01*
X87783Y52583D01*
X87492Y52500D01*
X87158Y52583D01*
X86867Y52833D01*
X86700Y53208D01*
X86658Y53625D01*
X86742Y54167D01*
X86867Y54458D01*
X87075Y54750D01*
X87367Y54958D01*
X87658Y55000D01*
X87950Y54917D01*
X88158Y54708D01*
G01X89633Y53000D02*
X89883Y52708D01*
X90217Y52542D01*
X90592Y52500D01*
X90925Y52542D01*
X91258Y52750D01*
X91467Y53000D01*
X91508Y53250D01*
X91425Y53542D01*
X91133Y53750D01*
X90842Y53833D01*
X90467D01*
G01X90842D02*
X91092Y53958D01*
X91300Y54167D01*
X91383Y54417D01*
X91300Y54667D01*
X91092Y54875D01*
X90717Y55000D01*
X90342Y54958D01*
X89967Y54792D01*
G01X93650Y55000D02*
X93317Y54917D01*
X93067Y54708D01*
X92900Y54458D01*
X92775Y54125D01*
X92733Y53750D01*
X92775Y53375D01*
X92900Y53042D01*
X93067Y52792D01*
X93317Y52583D01*
X93650Y52500D01*
X93983Y52583D01*
X94233Y52792D01*
X94400Y53042D01*
X94525Y53375D01*
X94567Y53750D01*
X94525Y54125D01*
X94400Y54458D01*
X94233Y54708D01*
X93983Y54917D01*
X93650Y55000D01*
G01X94200Y70400D02*
Y74400D01*
X86800D01*
G01X83517Y48500D02*
Y51000D01*
X84558D01*
X84892Y50875D01*
X85100Y50708D01*
X85183Y50375D01*
X85100Y50042D01*
X84850Y49833D01*
X84558Y49708D01*
X83517D01*
G01X84558D02*
X85183Y48500D01*
G01X86658Y49542D02*
X86950Y49833D01*
X87200Y50000D01*
X87533Y50083D01*
X87825Y50000D01*
X88033Y49833D01*
X88200Y49583D01*
X88242Y49292D01*
X88200Y49042D01*
X88033Y48792D01*
X87783Y48583D01*
X87492Y48500D01*
X87158Y48583D01*
X86867Y48833D01*
X86700Y49208D01*
X86658Y49625D01*
X86742Y50167D01*
X86867Y50458D01*
X87075Y50750D01*
X87367Y50958D01*
X87658Y51000D01*
X87950Y50917D01*
X88158Y50708D01*
G01X89633Y49000D02*
X89883Y48708D01*
X90217Y48542D01*
X90592Y48500D01*
X90925Y48542D01*
X91258Y48750D01*
X91467Y49000D01*
X91508Y49250D01*
X91425Y49542D01*
X91133Y49750D01*
X90842Y49833D01*
X90467D01*
G01X90842D02*
X91092Y49958D01*
X91300Y50167D01*
X91383Y50417D01*
X91300Y50667D01*
X91092Y50875D01*
X90717Y51000D01*
X90342Y50958D01*
X89967Y50792D01*
G01X92733Y49000D02*
X92983Y48708D01*
X93317Y48542D01*
X93692Y48500D01*
X94025Y48542D01*
X94358Y48750D01*
X94567Y49000D01*
X94608Y49250D01*
X94525Y49542D01*
X94233Y49750D01*
X93942Y49833D01*
X93567D01*
G01X93942D02*
X94192Y49958D01*
X94400Y50167D01*
X94483Y50417D01*
X94400Y50667D01*
X94192Y50875D01*
X93817Y51000D01*
X93442Y50958D01*
X93067Y50792D01*
G01X91000Y60800D02*
Y64800D01*
X83600D01*
G01X83517Y56500D02*
Y59000D01*
X84558D01*
X84892Y58875D01*
X85100Y58708D01*
X85183Y58375D01*
X85100Y58042D01*
X84850Y57833D01*
X84558Y57708D01*
X83517D01*
G01X84558D02*
X85183Y56500D01*
G01X86658Y57542D02*
X86950Y57833D01*
X87200Y58000D01*
X87533Y58083D01*
X87825Y58000D01*
X88033Y57833D01*
X88200Y57583D01*
X88242Y57292D01*
X88200Y57042D01*
X88033Y56792D01*
X87783Y56583D01*
X87492Y56500D01*
X87158Y56583D01*
X86867Y56833D01*
X86700Y57208D01*
X86658Y57625D01*
X86742Y58167D01*
X86867Y58458D01*
X87075Y58750D01*
X87367Y58958D01*
X87658Y59000D01*
X87950Y58917D01*
X88158Y58708D01*
G01X89633Y57000D02*
X89883Y56708D01*
X90217Y56542D01*
X90592Y56500D01*
X90925Y56542D01*
X91258Y56750D01*
X91467Y57000D01*
X91508Y57250D01*
X91425Y57542D01*
X91133Y57750D01*
X90842Y57833D01*
X90467D01*
G01X90842D02*
X91092Y57958D01*
X91300Y58167D01*
X91383Y58417D01*
X91300Y58667D01*
X91092Y58875D01*
X90717Y59000D01*
X90342Y58958D01*
X89967Y58792D01*
G01X92733Y56875D02*
X92983Y56667D01*
X93275Y56542D01*
X93650Y56500D01*
X94025Y56583D01*
X94317Y56750D01*
X94525Y57042D01*
X94567Y57375D01*
X94483Y57708D01*
X94275Y57917D01*
X93983Y58083D01*
X93692Y58125D01*
X93400Y58083D01*
X93025Y57917D01*
X93150Y59000D01*
X94275D01*
G01X86800Y79000D02*
Y75000D01*
X94200D01*
G01X41517Y64500D02*
Y67000D01*
X42558D01*
X42892Y66875D01*
X43100Y66708D01*
X43183Y66375D01*
X43100Y66042D01*
X42850Y65833D01*
X42558Y65708D01*
X41517D01*
G01X42558D02*
X43183Y64500D01*
G01X44658Y65542D02*
X44950Y65833D01*
X45200Y66000D01*
X45533Y66083D01*
X45825Y66000D01*
X46033Y65833D01*
X46200Y65583D01*
X46242Y65292D01*
X46200Y65042D01*
X46033Y64792D01*
X45783Y64583D01*
X45492Y64500D01*
X45158Y64583D01*
X44867Y64833D01*
X44700Y65208D01*
X44658Y65625D01*
X44742Y66167D01*
X44867Y66458D01*
X45075Y66750D01*
X45367Y66958D01*
X45658Y67000D01*
X45950Y66917D01*
X46158Y66708D01*
G01X47633Y65000D02*
X47883Y64708D01*
X48217Y64542D01*
X48592Y64500D01*
X48925Y64542D01*
X49258Y64750D01*
X49467Y65000D01*
X49508Y65250D01*
X49425Y65542D01*
X49133Y65750D01*
X48842Y65833D01*
X48467D01*
G01X48842D02*
X49092Y65958D01*
X49300Y66167D01*
X49383Y66417D01*
X49300Y66667D01*
X49092Y66875D01*
X48717Y67000D01*
X48342Y66958D01*
X47967Y66792D01*
G01X50858Y65542D02*
X51150Y65833D01*
X51400Y66000D01*
X51733Y66083D01*
X52025Y66000D01*
X52233Y65833D01*
X52400Y65583D01*
X52442Y65292D01*
X52400Y65042D01*
X52233Y64792D01*
X51983Y64583D01*
X51692Y64500D01*
X51358Y64583D01*
X51067Y64833D01*
X50900Y65208D01*
X50858Y65625D01*
X50942Y66167D01*
X51067Y66458D01*
X51275Y66750D01*
X51567Y66958D01*
X51858Y67000D01*
X52150Y66917D01*
X52358Y66708D01*
G01X54800Y67500D02*
Y63500D01*
X62200D01*
G01X56000Y69517D02*
X53500D01*
Y70558D01*
X53625Y70892D01*
X53792Y71100D01*
X54125Y71183D01*
X54458Y71100D01*
X54667Y70850D01*
X54792Y70558D01*
Y69517D01*
G01Y70558D02*
X56000Y71183D01*
G01X54958Y72658D02*
X54667Y72950D01*
X54500Y73200D01*
X54417Y73533D01*
X54500Y73825D01*
X54667Y74033D01*
X54917Y74200D01*
X55208Y74242D01*
X55458Y74200D01*
X55708Y74033D01*
X55917Y73783D01*
X56000Y73492D01*
X55917Y73158D01*
X55667Y72867D01*
X55292Y72700D01*
X54875Y72658D01*
X54333Y72742D01*
X54042Y72867D01*
X53750Y73075D01*
X53542Y73367D01*
X53500Y73658D01*
X53583Y73950D01*
X53792Y74158D01*
G01X55500Y75633D02*
X55792Y75883D01*
X55958Y76217D01*
X56000Y76592D01*
X55958Y76925D01*
X55750Y77258D01*
X55500Y77467D01*
X55250Y77508D01*
X54958Y77425D01*
X54750Y77133D01*
X54667Y76842D01*
Y76467D01*
G01Y76842D02*
X54542Y77092D01*
X54333Y77300D01*
X54083Y77383D01*
X53833Y77300D01*
X53625Y77092D01*
X53500Y76717D01*
X53542Y76342D01*
X53708Y75967D01*
G01X56000Y79650D02*
X55958Y79942D01*
X55833Y80275D01*
X55625Y80483D01*
X55333Y80567D01*
X55042Y80483D01*
X54792Y80233D01*
X54667Y79858D01*
Y79442D01*
X54583Y79192D01*
X54375Y78983D01*
X54083Y78900D01*
X53792Y79025D01*
X53583Y79317D01*
X53500Y79650D01*
X53583Y79983D01*
X53792Y80275D01*
X54083Y80400D01*
X54375Y80317D01*
X54583Y80108D01*
X54667Y79858D01*
Y79442D01*
X54792Y79067D01*
X55042Y78817D01*
X55333Y78733D01*
X55625Y78817D01*
X55833Y79025D01*
X55958Y79358D01*
X56000Y79650D01*
G01X58000Y67800D02*
X62000D01*
Y75200D01*
G01X73500Y49017D02*
X71000D01*
Y50058D01*
X71125Y50392D01*
X71292Y50600D01*
X71625Y50683D01*
X71958Y50600D01*
X72167Y50350D01*
X72292Y50058D01*
Y49017D01*
G01Y50058D02*
X73500Y50683D01*
G01X72458Y52158D02*
X72167Y52450D01*
X72000Y52700D01*
X71917Y53033D01*
X72000Y53325D01*
X72167Y53533D01*
X72417Y53700D01*
X72708Y53742D01*
X72958Y53700D01*
X73208Y53533D01*
X73417Y53283D01*
X73500Y52992D01*
X73417Y52658D01*
X73167Y52367D01*
X72792Y52200D01*
X72375Y52158D01*
X71833Y52242D01*
X71542Y52367D01*
X71250Y52575D01*
X71042Y52867D01*
X71000Y53158D01*
X71083Y53450D01*
X71292Y53658D01*
G01X73000Y55133D02*
X73292Y55383D01*
X73458Y55717D01*
X73500Y56092D01*
X73458Y56425D01*
X73250Y56758D01*
X73000Y56967D01*
X72750Y57008D01*
X72458Y56925D01*
X72250Y56633D01*
X72167Y56342D01*
Y55967D01*
G01Y56342D02*
X72042Y56592D01*
X71833Y56800D01*
X71583Y56883D01*
X71333Y56800D01*
X71125Y56592D01*
X71000Y56217D01*
X71042Y55842D01*
X71208Y55467D01*
G01X73208Y58442D02*
X73417Y58733D01*
X73500Y59067D01*
X73417Y59400D01*
X73167Y59692D01*
X72792Y59900D01*
X72417Y59983D01*
X71958D01*
X71583Y59900D01*
X71250Y59692D01*
X71083Y59442D01*
X71000Y59150D01*
X71083Y58817D01*
X71250Y58567D01*
X71500Y58400D01*
X71833Y58317D01*
X72125Y58400D01*
X72417Y58608D01*
X72583Y58858D01*
X72625Y59150D01*
X72542Y59483D01*
X72333Y59733D01*
X71958Y59983D01*
G01X74500Y69200D02*
X70500D01*
Y61800D01*
G01X66500Y49483D02*
X64000D01*
Y50317D01*
X64125Y50650D01*
X64292Y50900D01*
X64542Y51108D01*
X64833Y51275D01*
X65250Y51317D01*
X65667Y51275D01*
X65958Y51108D01*
X66208Y50900D01*
X66375Y50650D01*
X66500Y50317D01*
Y49483D01*
G01X64417Y52708D02*
X64167Y52958D01*
X64042Y53250D01*
X64000Y53583D01*
X64083Y54000D01*
X64292Y54292D01*
X64542Y54375D01*
X64792Y54333D01*
X65000Y54167D01*
X65417Y53333D01*
X65708Y52958D01*
X66125Y52708D01*
X66500Y52625D01*
Y54375D01*
G01Y57100D02*
X64000D01*
X65792Y55558D01*
Y57642D01*
G01X70000Y78000D02*
Y61900D01*
G01X63000Y78000D02*
X70000D01*
G01X63000Y61900D02*
Y78000D01*
G01X70000Y61900D02*
X63000D01*
G01X73500Y75350D02*
X73458Y75017D01*
X73292Y74725D01*
X73042Y74475D01*
X72750Y74308D01*
X72417Y74225D01*
X72083D01*
X71750Y74308D01*
X71458Y74475D01*
X71208Y74725D01*
X71042Y75017D01*
X71000Y75350D01*
X71042Y75683D01*
X71208Y75975D01*
X71458Y76225D01*
X71750Y76392D01*
X72083Y76475D01*
X72417D01*
X72750Y76392D01*
X73042Y76225D01*
X73292Y75975D01*
X73458Y75683D01*
X73500Y75350D01*
G01X72833Y75683D02*
X73500Y76183D01*
G01Y78450D02*
X71000D01*
X71500Y77950D01*
G01X73500D02*
Y78950D01*
G01Y81550D02*
X71000D01*
X71500Y81050D01*
G01X73500D02*
Y82050D01*
G01X73208Y83942D02*
X73417Y84233D01*
X73500Y84567D01*
X73417Y84900D01*
X73167Y85192D01*
X72792Y85400D01*
X72417Y85483D01*
X71958D01*
X71583Y85400D01*
X71250Y85192D01*
X71083Y84942D01*
X71000Y84650D01*
X71083Y84317D01*
X71250Y84067D01*
X71500Y83900D01*
X71833Y83817D01*
X72125Y83900D01*
X72417Y84108D01*
X72583Y84358D01*
X72625Y84650D01*
X72542Y84983D01*
X72333Y85233D01*
X71958Y85483D01*
G01X86200Y83700D02*
X74800D01*
G01X86200Y70300D02*
Y83700D01*
G01X74800Y70300D02*
X86200D01*
G01X74800Y83700D02*
Y70300D01*
G01X42767Y101792D02*
X42517Y101917D01*
X42225Y102000D01*
X41892D01*
X41517Y101875D01*
X41225Y101667D01*
X41017Y101417D01*
X40850Y101000D01*
X40808Y100625D01*
X40892Y100250D01*
X41017Y100000D01*
X41267Y99750D01*
X41558Y99583D01*
X41850Y99500D01*
X42142D01*
X42433Y99583D01*
X42683Y99708D01*
X42892Y99875D01*
G01X44033Y100000D02*
X44283Y99708D01*
X44617Y99542D01*
X44992Y99500D01*
X45325Y99542D01*
X45658Y99750D01*
X45867Y100000D01*
X45908Y100250D01*
X45825Y100542D01*
X45533Y100750D01*
X45242Y100833D01*
X44867D01*
G01X45242D02*
X45492Y100958D01*
X45700Y101167D01*
X45783Y101417D01*
X45700Y101667D01*
X45492Y101875D01*
X45117Y102000D01*
X44742Y101958D01*
X44367Y101792D01*
G01X47133Y99875D02*
X47383Y99667D01*
X47675Y99542D01*
X48050Y99500D01*
X48425Y99583D01*
X48717Y99750D01*
X48925Y100042D01*
X48967Y100375D01*
X48883Y100708D01*
X48675Y100917D01*
X48383Y101083D01*
X48092Y101125D01*
X47800Y101083D01*
X47425Y100917D01*
X47550Y102000D01*
X48675D01*
G01X51150Y99500D02*
Y102000D01*
X50650Y101500D01*
G01Y99500D02*
X51650D01*
G01X41017Y95500D02*
Y98000D01*
X42058D01*
X42392Y97875D01*
X42600Y97708D01*
X42683Y97375D01*
X42600Y97042D01*
X42350Y96833D01*
X42058Y96708D01*
X41017D01*
G01X42058D02*
X42683Y95500D01*
G01X44158Y96542D02*
X44450Y96833D01*
X44700Y97000D01*
X45033Y97083D01*
X45325Y97000D01*
X45533Y96833D01*
X45700Y96583D01*
X45742Y96292D01*
X45700Y96042D01*
X45533Y95792D01*
X45283Y95583D01*
X44992Y95500D01*
X44658Y95583D01*
X44367Y95833D01*
X44200Y96208D01*
X44158Y96625D01*
X44242Y97167D01*
X44367Y97458D01*
X44575Y97750D01*
X44867Y97958D01*
X45158Y98000D01*
X45450Y97917D01*
X45658Y97708D01*
G01X47133Y96000D02*
X47383Y95708D01*
X47717Y95542D01*
X48092Y95500D01*
X48425Y95542D01*
X48758Y95750D01*
X48967Y96000D01*
X49008Y96250D01*
X48925Y96542D01*
X48633Y96750D01*
X48342Y96833D01*
X47967D01*
G01X48342D02*
X48592Y96958D01*
X48800Y97167D01*
X48883Y97417D01*
X48800Y97667D01*
X48592Y97875D01*
X48217Y98000D01*
X47842Y97958D01*
X47467Y97792D01*
G01X51067Y95500D02*
X51150Y96042D01*
X51275Y96500D01*
X51442Y96917D01*
X51650Y97375D01*
X51983Y98000D01*
X50317D01*
G01X62200Y94500D02*
Y98500D01*
X54800D01*
G01X72777Y156858D02*
X72527Y156983D01*
X72235Y157066D01*
X71902D01*
X71527Y156941D01*
X71235Y156733D01*
X71027Y156483D01*
X70860Y156066D01*
X70818Y155691D01*
X70902Y155316D01*
X71027Y155066D01*
X71277Y154816D01*
X71568Y154649D01*
X71860Y154566D01*
X72152D01*
X72443Y154649D01*
X72693Y154774D01*
X72902Y154941D01*
G01X74043Y155066D02*
X74293Y154774D01*
X74627Y154608D01*
X75002Y154566D01*
X75335Y154608D01*
X75668Y154816D01*
X75877Y155066D01*
X75918Y155316D01*
X75835Y155608D01*
X75543Y155816D01*
X75252Y155899D01*
X74877D01*
G01X75252D02*
X75502Y156024D01*
X75710Y156233D01*
X75793Y156483D01*
X75710Y156733D01*
X75502Y156941D01*
X75127Y157066D01*
X74752Y157024D01*
X74377Y156858D01*
G01X78560Y154566D02*
Y157066D01*
X77018Y155274D01*
X79102D01*
G01X80368Y156649D02*
X80618Y156899D01*
X80910Y157024D01*
X81243Y157066D01*
X81660Y156983D01*
X81952Y156774D01*
X82035Y156524D01*
X81993Y156274D01*
X81827Y156066D01*
X80993Y155649D01*
X80618Y155358D01*
X80368Y154941D01*
X80285Y154566D01*
X82035D01*
G01X82267Y183792D02*
X82017Y183917D01*
X81725Y184000D01*
X81392D01*
X81017Y183875D01*
X80725Y183667D01*
X80517Y183417D01*
X80350Y183000D01*
X80308Y182625D01*
X80392Y182250D01*
X80517Y182000D01*
X80767Y181750D01*
X81058Y181583D01*
X81350Y181500D01*
X81642D01*
X81933Y181583D01*
X82183Y181708D01*
X82392Y181875D01*
G01X83533Y182000D02*
X83783Y181708D01*
X84117Y181542D01*
X84492Y181500D01*
X84825Y181542D01*
X85158Y181750D01*
X85367Y182000D01*
X85408Y182250D01*
X85325Y182542D01*
X85033Y182750D01*
X84742Y182833D01*
X84367D01*
G01X84742D02*
X84992Y182958D01*
X85200Y183167D01*
X85283Y183417D01*
X85200Y183667D01*
X84992Y183875D01*
X84617Y184000D01*
X84242Y183958D01*
X83867Y183792D01*
G01X88050Y181500D02*
Y184000D01*
X86508Y182208D01*
X88592D01*
G01X90650Y181500D02*
X90942Y181542D01*
X91275Y181667D01*
X91483Y181875D01*
X91567Y182167D01*
X91483Y182458D01*
X91233Y182708D01*
X90858Y182833D01*
X90442D01*
X90192Y182917D01*
X89983Y183125D01*
X89900Y183417D01*
X90025Y183708D01*
X90317Y183917D01*
X90650Y184000D01*
X90983Y183917D01*
X91275Y183708D01*
X91400Y183417D01*
X91317Y183125D01*
X91108Y182917D01*
X90858Y182833D01*
X90442D01*
X90067Y182708D01*
X89817Y182458D01*
X89733Y182167D01*
X89817Y181875D01*
X90025Y181667D01*
X90358Y181542D01*
X90650Y181500D01*
G01X77850Y118500D02*
X77517Y118542D01*
X77225Y118708D01*
X76975Y118958D01*
X76808Y119250D01*
X76725Y119583D01*
Y119917D01*
X76808Y120250D01*
X76975Y120542D01*
X77225Y120792D01*
X77517Y120958D01*
X77850Y121000D01*
X78183Y120958D01*
X78475Y120792D01*
X78725Y120542D01*
X78892Y120250D01*
X78975Y119917D01*
Y119583D01*
X78892Y119250D01*
X78725Y118958D01*
X78475Y118708D01*
X78183Y118542D01*
X77850Y118500D01*
G01X78183Y119167D02*
X78683Y118500D01*
G01X80950D02*
Y121000D01*
X80450Y120500D01*
G01Y118500D02*
X81450D01*
G01X84050D02*
Y121000D01*
X83550Y120500D01*
G01Y118500D02*
X84550D01*
G01X87150D02*
X87442Y118542D01*
X87775Y118667D01*
X87983Y118875D01*
X88067Y119167D01*
X87983Y119458D01*
X87733Y119708D01*
X87358Y119833D01*
X86942D01*
X86692Y119917D01*
X86483Y120125D01*
X86400Y120417D01*
X86525Y120708D01*
X86817Y120917D01*
X87150Y121000D01*
X87483Y120917D01*
X87775Y120708D01*
X87900Y120417D01*
X87817Y120125D01*
X87608Y119917D01*
X87358Y119833D01*
X86942D01*
X86567Y119708D01*
X86317Y119458D01*
X86233Y119167D01*
X86317Y118875D01*
X86525Y118667D01*
X86858Y118542D01*
X87150Y118500D01*
G01X92200Y101500D02*
X90100Y103300D01*
X92200Y105500D01*
G01X92300Y109100D02*
X73100D01*
Y97900D01*
X92300D01*
Y109100D01*
X91900D01*
G01X34850Y121500D02*
X34517Y121542D01*
X34225Y121708D01*
X33975Y121958D01*
X33808Y122250D01*
X33725Y122583D01*
Y122917D01*
X33808Y123250D01*
X33975Y123542D01*
X34225Y123792D01*
X34517Y123958D01*
X34850Y124000D01*
X35183Y123958D01*
X35475Y123792D01*
X35725Y123542D01*
X35892Y123250D01*
X35975Y122917D01*
Y122583D01*
X35892Y122250D01*
X35725Y121958D01*
X35475Y121708D01*
X35183Y121542D01*
X34850Y121500D01*
G01X35183Y122167D02*
X35683Y121500D01*
G01X37950D02*
Y124000D01*
X37450Y123500D01*
G01Y121500D02*
X38450D01*
G01X40258Y123583D02*
X40508Y123833D01*
X40800Y123958D01*
X41133Y124000D01*
X41550Y123917D01*
X41842Y123708D01*
X41925Y123458D01*
X41883Y123208D01*
X41717Y123000D01*
X40883Y122583D01*
X40508Y122292D01*
X40258Y121875D01*
X40175Y121500D01*
X41925D01*
G01X44150Y124000D02*
X43817Y123917D01*
X43567Y123708D01*
X43400Y123458D01*
X43275Y123125D01*
X43233Y122750D01*
X43275Y122375D01*
X43400Y122042D01*
X43567Y121792D01*
X43817Y121583D01*
X44150Y121500D01*
X44483Y121583D01*
X44733Y121792D01*
X44900Y122042D01*
X45025Y122375D01*
X45067Y122750D01*
X45025Y123125D01*
X44900Y123458D01*
X44733Y123708D01*
X44483Y123917D01*
X44150Y124000D01*
G01X47800Y123500D02*
X49900Y121700D01*
X47800Y119500D01*
G01X47700Y115900D02*
X66900D01*
Y127100D01*
X47700D01*
Y115900D01*
X48100D01*
G01X72776Y153160D02*
X72526Y153285D01*
X72234Y153368D01*
X71901D01*
X71526Y153243D01*
X71234Y153035D01*
X71026Y152785D01*
X70859Y152368D01*
X70817Y151993D01*
X70901Y151618D01*
X71026Y151368D01*
X71276Y151118D01*
X71567Y150951D01*
X71859Y150868D01*
X72151D01*
X72442Y150951D01*
X72692Y151076D01*
X72901Y151243D01*
G01X74042Y151368D02*
X74292Y151076D01*
X74626Y150910D01*
X75001Y150868D01*
X75334Y150910D01*
X75667Y151118D01*
X75876Y151368D01*
X75917Y151618D01*
X75834Y151910D01*
X75542Y152118D01*
X75251Y152201D01*
X74876D01*
G01X75251D02*
X75501Y152326D01*
X75709Y152535D01*
X75792Y152785D01*
X75709Y153035D01*
X75501Y153243D01*
X75126Y153368D01*
X74751Y153326D01*
X74376Y153160D01*
G01X78559Y150868D02*
Y153368D01*
X77017Y151576D01*
X79101D01*
G01X80242Y151368D02*
X80492Y151076D01*
X80826Y150910D01*
X81201Y150868D01*
X81534Y150910D01*
X81867Y151118D01*
X82076Y151368D01*
X82117Y151618D01*
X82034Y151910D01*
X81742Y152118D01*
X81451Y152201D01*
X81076D01*
G01X81451D02*
X81701Y152326D01*
X81909Y152535D01*
X81992Y152785D01*
X81909Y153035D01*
X81701Y153243D01*
X81326Y153368D01*
X80951Y153326D01*
X80576Y153160D01*
G01X87800Y122000D02*
X82300D01*
G01X87800Y130000D02*
Y122000D01*
G01X82300Y130000D02*
X87800D01*
G01X70200D02*
X75700D01*
G01X70200Y122000D02*
Y130000D01*
G01X75700Y122000D02*
X70200D01*
G01X95000Y141017D02*
X92500D01*
Y142058D01*
X92625Y142392D01*
X92792Y142600D01*
X93125Y142683D01*
X93458Y142600D01*
X93667Y142350D01*
X93792Y142058D01*
Y141017D01*
G01Y142058D02*
X95000Y142683D01*
G01X93958Y144158D02*
X93667Y144450D01*
X93500Y144700D01*
X93417Y145033D01*
X93500Y145325D01*
X93667Y145533D01*
X93917Y145700D01*
X94208Y145742D01*
X94458Y145700D01*
X94708Y145533D01*
X94917Y145283D01*
X95000Y144992D01*
X94917Y144658D01*
X94667Y144367D01*
X94292Y144200D01*
X93875Y144158D01*
X93333Y144242D01*
X93042Y144367D01*
X92750Y144575D01*
X92542Y144867D01*
X92500Y145158D01*
X92583Y145450D01*
X92792Y145658D01*
G01X92917Y147258D02*
X92667Y147508D01*
X92542Y147800D01*
X92500Y148133D01*
X92583Y148550D01*
X92792Y148842D01*
X93042Y148925D01*
X93292Y148883D01*
X93500Y148717D01*
X93917Y147883D01*
X94208Y147508D01*
X94625Y147258D01*
X95000Y147175D01*
Y148925D01*
G01Y151150D02*
X92500D01*
X93000Y150650D01*
G01X95000D02*
Y151650D01*
G01X89500Y139800D02*
X97500D01*
Y122200D01*
X89500D01*
Y139800D01*
G01X71017Y158500D02*
Y161000D01*
X72058D01*
X72392Y160875D01*
X72600Y160708D01*
X72683Y160375D01*
X72600Y160042D01*
X72350Y159833D01*
X72058Y159708D01*
X71017D01*
G01X72058D02*
X72683Y158500D01*
G01X74158Y159542D02*
X74450Y159833D01*
X74700Y160000D01*
X75033Y160083D01*
X75325Y160000D01*
X75533Y159833D01*
X75700Y159583D01*
X75742Y159292D01*
X75700Y159042D01*
X75533Y158792D01*
X75283Y158583D01*
X74992Y158500D01*
X74658Y158583D01*
X74367Y158833D01*
X74200Y159208D01*
X74158Y159625D01*
X74242Y160167D01*
X74367Y160458D01*
X74575Y160750D01*
X74867Y160958D01*
X75158Y161000D01*
X75450Y160917D01*
X75658Y160708D01*
G01X77258Y160583D02*
X77508Y160833D01*
X77800Y160958D01*
X78133Y161000D01*
X78550Y160917D01*
X78842Y160708D01*
X78925Y160458D01*
X78883Y160208D01*
X78717Y160000D01*
X77883Y159583D01*
X77508Y159292D01*
X77258Y158875D01*
X77175Y158500D01*
X78925D01*
G01X80233Y159000D02*
X80483Y158708D01*
X80817Y158542D01*
X81192Y158500D01*
X81525Y158542D01*
X81858Y158750D01*
X82067Y159000D01*
X82108Y159250D01*
X82025Y159542D01*
X81733Y159750D01*
X81442Y159833D01*
X81067D01*
G01X81442D02*
X81692Y159958D01*
X81900Y160167D01*
X81983Y160417D01*
X81900Y160667D01*
X81692Y160875D01*
X81317Y161000D01*
X80942Y160958D01*
X80567Y160792D01*
G01X65700Y136500D02*
Y144500D01*
X83300D01*
Y136500D01*
X65700D01*
G01X54767Y147792D02*
X54517Y147917D01*
X54225Y148000D01*
X53892D01*
X53517Y147875D01*
X53225Y147667D01*
X53017Y147417D01*
X52850Y147000D01*
X52808Y146625D01*
X52892Y146250D01*
X53017Y146000D01*
X53267Y145750D01*
X53558Y145583D01*
X53850Y145500D01*
X54142D01*
X54433Y145583D01*
X54683Y145708D01*
X54892Y145875D01*
G01X56033Y146000D02*
X56283Y145708D01*
X56617Y145542D01*
X56992Y145500D01*
X57325Y145542D01*
X57658Y145750D01*
X57867Y146000D01*
X57908Y146250D01*
X57825Y146542D01*
X57533Y146750D01*
X57242Y146833D01*
X56867D01*
G01X57242D02*
X57492Y146958D01*
X57700Y147167D01*
X57783Y147417D01*
X57700Y147667D01*
X57492Y147875D01*
X57117Y148000D01*
X56742Y147958D01*
X56367Y147792D01*
G01X60550Y145500D02*
Y148000D01*
X59008Y146208D01*
X61092D01*
G01X62358Y146542D02*
X62650Y146833D01*
X62900Y147000D01*
X63233Y147083D01*
X63525Y147000D01*
X63733Y146833D01*
X63900Y146583D01*
X63942Y146292D01*
X63900Y146042D01*
X63733Y145792D01*
X63483Y145583D01*
X63192Y145500D01*
X62858Y145583D01*
X62567Y145833D01*
X62400Y146208D01*
X62358Y146625D01*
X62442Y147167D01*
X62567Y147458D01*
X62775Y147750D01*
X63067Y147958D01*
X63358Y148000D01*
X63650Y147917D01*
X63858Y147708D01*
G01X78767Y172792D02*
X78517Y172917D01*
X78225Y173000D01*
X77892D01*
X77517Y172875D01*
X77225Y172667D01*
X77017Y172417D01*
X76850Y172000D01*
X76808Y171625D01*
X76892Y171250D01*
X77017Y171000D01*
X77267Y170750D01*
X77558Y170583D01*
X77850Y170500D01*
X78142D01*
X78433Y170583D01*
X78683Y170708D01*
X78892Y170875D01*
G01X80033Y171000D02*
X80283Y170708D01*
X80617Y170542D01*
X80992Y170500D01*
X81325Y170542D01*
X81658Y170750D01*
X81867Y171000D01*
X81908Y171250D01*
X81825Y171542D01*
X81533Y171750D01*
X81242Y171833D01*
X80867D01*
G01X81242D02*
X81492Y171958D01*
X81700Y172167D01*
X81783Y172417D01*
X81700Y172667D01*
X81492Y172875D01*
X81117Y173000D01*
X80742Y172958D01*
X80367Y172792D01*
G01X84550Y170500D02*
Y173000D01*
X83008Y171208D01*
X85092D01*
G01X87067Y170500D02*
X87150Y171042D01*
X87275Y171500D01*
X87442Y171917D01*
X87650Y172375D01*
X87983Y173000D01*
X86317D01*
G01X64967Y269500D02*
Y267000D01*
X66633D01*
G01X69733D02*
X68067D01*
Y269500D01*
X69733D01*
G01X69067Y268292D02*
X68067D01*
G01X71083Y267000D02*
Y269500D01*
X71917D01*
X72250Y269375D01*
X72500Y269208D01*
X72708Y268958D01*
X72875Y268667D01*
X72917Y268250D01*
X72875Y267833D01*
X72708Y267542D01*
X72500Y267292D01*
X72250Y267125D01*
X71917Y267000D01*
X71083D01*
G01X75100D02*
Y269500D01*
X74600Y269000D01*
G01Y267000D02*
X75600D01*
G01X77283Y267500D02*
X77533Y267208D01*
X77867Y267042D01*
X78242Y267000D01*
X78575Y267042D01*
X78908Y267250D01*
X79117Y267500D01*
X79158Y267750D01*
X79075Y268042D01*
X78783Y268250D01*
X78492Y268333D01*
X78117D01*
G01X78492D02*
X78742Y268458D01*
X78950Y268667D01*
X79033Y268917D01*
X78950Y269167D01*
X78742Y269375D01*
X78367Y269500D01*
X77992Y269458D01*
X77617Y269292D01*
G01X65679Y251880D02*
Y263080D01*
X74479D01*
Y251880D01*
X65679D01*
G01X40017Y378500D02*
Y381000D01*
X41058D01*
X41392Y380875D01*
X41600Y380708D01*
X41683Y380375D01*
X41600Y380042D01*
X41350Y379833D01*
X41058Y379708D01*
X40017D01*
G01X41058D02*
X41683Y378500D01*
G01X43033Y379000D02*
X43283Y378708D01*
X43617Y378542D01*
X43992Y378500D01*
X44325Y378542D01*
X44658Y378750D01*
X44867Y379000D01*
X44908Y379250D01*
X44825Y379542D01*
X44533Y379750D01*
X44242Y379833D01*
X43867D01*
G01X44242D02*
X44492Y379958D01*
X44700Y380167D01*
X44783Y380417D01*
X44700Y380667D01*
X44492Y380875D01*
X44117Y381000D01*
X43742Y380958D01*
X43367Y380792D01*
G01X47550Y378500D02*
Y381000D01*
X46008Y379208D01*
X48092D01*
G01X50150Y378500D02*
Y381000D01*
X49650Y380500D01*
G01Y378500D02*
X50650D01*
G01X94124Y560075D02*
X99174D01*
Y658775D01*
X123824D01*
Y474375D01*
X99174D01*
Y533075D01*
X94124D01*
Y560075D01*
G01X60659Y381528D02*
Y385528D01*
X53259D01*
G01X65017Y406500D02*
Y409000D01*
X66058D01*
X66392Y408875D01*
X66600Y408708D01*
X66683Y408375D01*
X66600Y408042D01*
X66350Y407833D01*
X66058Y407708D01*
X65017D01*
G01X66058D02*
X66683Y406500D01*
G01X68033Y407000D02*
X68283Y406708D01*
X68617Y406542D01*
X68992Y406500D01*
X69325Y406542D01*
X69658Y406750D01*
X69867Y407000D01*
X69908Y407250D01*
X69825Y407542D01*
X69533Y407750D01*
X69242Y407833D01*
X68867D01*
G01X69242D02*
X69492Y407958D01*
X69700Y408167D01*
X69783Y408417D01*
X69700Y408667D01*
X69492Y408875D01*
X69117Y409000D01*
X68742Y408958D01*
X68367Y408792D01*
G01X71133Y407000D02*
X71383Y406708D01*
X71717Y406542D01*
X72092Y406500D01*
X72425Y406542D01*
X72758Y406750D01*
X72967Y407000D01*
X73008Y407250D01*
X72925Y407542D01*
X72633Y407750D01*
X72342Y407833D01*
X71967D01*
G01X72342D02*
X72592Y407958D01*
X72800Y408167D01*
X72883Y408417D01*
X72800Y408667D01*
X72592Y408875D01*
X72217Y409000D01*
X71842Y408958D01*
X71467Y408792D01*
G01X75150Y406500D02*
X75442Y406542D01*
X75775Y406667D01*
X75983Y406875D01*
X76067Y407167D01*
X75983Y407458D01*
X75733Y407708D01*
X75358Y407833D01*
X74942D01*
X74692Y407917D01*
X74483Y408125D01*
X74400Y408417D01*
X74525Y408708D01*
X74817Y408917D01*
X75150Y409000D01*
X75483Y408917D01*
X75775Y408708D01*
X75900Y408417D01*
X75817Y408125D01*
X75608Y407917D01*
X75358Y407833D01*
X74942D01*
X74567Y407708D01*
X74317Y407458D01*
X74233Y407167D01*
X74317Y406875D01*
X74525Y406667D01*
X74858Y406542D01*
X75150Y406500D01*
G01X75392Y401305D02*
Y405305D01*
X67992D01*
G01X81267Y400163D02*
X78767D01*
Y401204D01*
X78892Y401538D01*
X79059Y401746D01*
X79392Y401829D01*
X79725Y401746D01*
X79934Y401496D01*
X80059Y401204D01*
Y400163D01*
G01Y401204D02*
X81267Y401829D01*
G01X80767Y403179D02*
X81059Y403429D01*
X81225Y403763D01*
X81267Y404138D01*
X81225Y404471D01*
X81017Y404804D01*
X80767Y405013D01*
X80517Y405054D01*
X80225Y404971D01*
X80017Y404679D01*
X79934Y404388D01*
Y404013D01*
G01Y404388D02*
X79809Y404638D01*
X79600Y404846D01*
X79350Y404929D01*
X79100Y404846D01*
X78892Y404638D01*
X78767Y404263D01*
X78809Y403888D01*
X78975Y403513D01*
G01X81267Y407196D02*
X81225Y407488D01*
X81100Y407821D01*
X80892Y408029D01*
X80600Y408113D01*
X80309Y408029D01*
X80059Y407779D01*
X79934Y407404D01*
Y406988D01*
X79850Y406738D01*
X79642Y406529D01*
X79350Y406446D01*
X79059Y406571D01*
X78850Y406863D01*
X78767Y407196D01*
X78850Y407529D01*
X79059Y407821D01*
X79350Y407946D01*
X79642Y407863D01*
X79850Y407654D01*
X79934Y407404D01*
Y406988D01*
X80059Y406613D01*
X80309Y406363D01*
X80600Y406279D01*
X80892Y406363D01*
X81100Y406571D01*
X81225Y406904D01*
X81267Y407196D01*
G01X79184Y409504D02*
X78934Y409754D01*
X78809Y410046D01*
X78767Y410379D01*
X78850Y410796D01*
X79059Y411088D01*
X79309Y411171D01*
X79559Y411129D01*
X79767Y410963D01*
X80184Y410129D01*
X80475Y409754D01*
X80892Y409504D01*
X81267Y409421D01*
Y411171D01*
G01X85267Y400163D02*
X82767D01*
Y401204D01*
X82892Y401538D01*
X83059Y401746D01*
X83392Y401829D01*
X83725Y401746D01*
X83934Y401496D01*
X84059Y401204D01*
Y400163D01*
G01Y401204D02*
X85267Y401829D01*
G01X84767Y403179D02*
X85059Y403429D01*
X85225Y403763D01*
X85267Y404138D01*
X85225Y404471D01*
X85017Y404804D01*
X84767Y405013D01*
X84517Y405054D01*
X84225Y404971D01*
X84017Y404679D01*
X83934Y404388D01*
Y404013D01*
G01Y404388D02*
X83809Y404638D01*
X83600Y404846D01*
X83350Y404929D01*
X83100Y404846D01*
X82892Y404638D01*
X82767Y404263D01*
X82809Y403888D01*
X82975Y403513D01*
G01X85267Y407196D02*
X85225Y407488D01*
X85100Y407821D01*
X84892Y408029D01*
X84600Y408113D01*
X84309Y408029D01*
X84059Y407779D01*
X83934Y407404D01*
Y406988D01*
X83850Y406738D01*
X83642Y406529D01*
X83350Y406446D01*
X83059Y406571D01*
X82850Y406863D01*
X82767Y407196D01*
X82850Y407529D01*
X83059Y407821D01*
X83350Y407946D01*
X83642Y407863D01*
X83850Y407654D01*
X83934Y407404D01*
Y406988D01*
X84059Y406613D01*
X84309Y406363D01*
X84600Y406279D01*
X84892Y406363D01*
X85100Y406571D01*
X85225Y406904D01*
X85267Y407196D01*
G01Y410213D02*
X84725Y410296D01*
X84267Y410421D01*
X83850Y410588D01*
X83392Y410796D01*
X82767Y411129D01*
Y409463D01*
G01X57350Y401500D02*
X57017Y401542D01*
X56725Y401708D01*
X56475Y401958D01*
X56308Y402250D01*
X56225Y402583D01*
Y402917D01*
X56308Y403250D01*
X56475Y403542D01*
X56725Y403792D01*
X57017Y403958D01*
X57350Y404000D01*
X57683Y403958D01*
X57975Y403792D01*
X58225Y403542D01*
X58392Y403250D01*
X58475Y402917D01*
Y402583D01*
X58392Y402250D01*
X58225Y401958D01*
X57975Y401708D01*
X57683Y401542D01*
X57350Y401500D01*
G01X57683Y402167D02*
X58183Y401500D01*
G01X59658Y403583D02*
X59908Y403833D01*
X60200Y403958D01*
X60533Y404000D01*
X60950Y403917D01*
X61242Y403708D01*
X61325Y403458D01*
X61283Y403208D01*
X61117Y403000D01*
X60283Y402583D01*
X59908Y402292D01*
X59658Y401875D01*
X59575Y401500D01*
X61325D01*
G01X62633Y402000D02*
X62883Y401708D01*
X63217Y401542D01*
X63592Y401500D01*
X63925Y401542D01*
X64258Y401750D01*
X64467Y402000D01*
X64508Y402250D01*
X64425Y402542D01*
X64133Y402750D01*
X63842Y402833D01*
X63467D01*
G01X63842D02*
X64092Y402958D01*
X64300Y403167D01*
X64383Y403417D01*
X64300Y403667D01*
X64092Y403875D01*
X63717Y404000D01*
X63342Y403958D01*
X62967Y403792D01*
G01X66650Y401500D02*
Y404000D01*
X66150Y403500D01*
G01Y401500D02*
X67150D01*
G01X76067Y385846D02*
Y399846D01*
G01X63067Y385846D02*
X76067D01*
G01X63067Y399846D02*
Y385846D01*
G01X76067Y399846D02*
X63067D01*
G01X40850Y382500D02*
X40517Y382542D01*
X40225Y382708D01*
X39975Y382958D01*
X39808Y383250D01*
X39725Y383583D01*
Y383917D01*
X39808Y384250D01*
X39975Y384542D01*
X40225Y384792D01*
X40517Y384958D01*
X40850Y385000D01*
X41183Y384958D01*
X41475Y384792D01*
X41725Y384542D01*
X41892Y384250D01*
X41975Y383917D01*
Y383583D01*
X41892Y383250D01*
X41725Y382958D01*
X41475Y382708D01*
X41183Y382542D01*
X40850Y382500D01*
G01X41183Y383167D02*
X41683Y382500D01*
G01X43158Y384583D02*
X43408Y384833D01*
X43700Y384958D01*
X44033Y385000D01*
X44450Y384917D01*
X44742Y384708D01*
X44825Y384458D01*
X44783Y384208D01*
X44617Y384000D01*
X43783Y383583D01*
X43408Y383292D01*
X43158Y382875D01*
X43075Y382500D01*
X44825D01*
G01X46133Y382875D02*
X46383Y382667D01*
X46675Y382542D01*
X47050Y382500D01*
X47425Y382583D01*
X47717Y382750D01*
X47925Y383042D01*
X47967Y383375D01*
X47883Y383708D01*
X47675Y383917D01*
X47383Y384083D01*
X47092Y384125D01*
X46800Y384083D01*
X46425Y383917D01*
X46550Y385000D01*
X47675D01*
G01X49233Y382875D02*
X49483Y382667D01*
X49775Y382542D01*
X50150Y382500D01*
X50525Y382583D01*
X50817Y382750D01*
X51025Y383042D01*
X51067Y383375D01*
X50983Y383708D01*
X50775Y383917D01*
X50483Y384083D01*
X50192Y384125D01*
X49900Y384083D01*
X49525Y383917D01*
X49650Y385000D01*
X50775D01*
G01X47959Y386753D02*
X61959D01*
G01X47959Y399753D02*
Y386753D01*
G01X61959Y399753D02*
X47959D01*
G01X61959Y386753D02*
Y399753D01*
G01X51267Y544953D02*
X51017Y545078D01*
X50725Y545161D01*
X50392D01*
X50017Y545036D01*
X49725Y544828D01*
X49517Y544578D01*
X49350Y544161D01*
X49308Y543786D01*
X49392Y543411D01*
X49517Y543161D01*
X49767Y542911D01*
X50058Y542744D01*
X50350Y542661D01*
X50642D01*
X50933Y542744D01*
X51183Y542869D01*
X51392Y543036D01*
G01X53450Y542661D02*
Y545161D01*
X52950Y544661D01*
G01Y542661D02*
X53950D01*
G01X55842Y542953D02*
X56133Y542744D01*
X56467Y542661D01*
X56800Y542744D01*
X57092Y542994D01*
X57300Y543369D01*
X57383Y543744D01*
Y544203D01*
X57300Y544578D01*
X57092Y544911D01*
X56842Y545078D01*
X56550Y545161D01*
X56217Y545078D01*
X55967Y544911D01*
X55800Y544661D01*
X55717Y544328D01*
X55800Y544036D01*
X56008Y543744D01*
X56258Y543578D01*
X56550Y543536D01*
X56883Y543619D01*
X57133Y543828D01*
X57383Y544203D01*
G01X60150Y542661D02*
Y545161D01*
X58608Y543369D01*
X60692D01*
G01X43267Y554453D02*
X43017Y554578D01*
X42725Y554661D01*
X42392D01*
X42017Y554536D01*
X41725Y554328D01*
X41517Y554078D01*
X41350Y553661D01*
X41308Y553286D01*
X41392Y552911D01*
X41517Y552661D01*
X41767Y552411D01*
X42058Y552244D01*
X42350Y552161D01*
X42642D01*
X42933Y552244D01*
X43183Y552369D01*
X43392Y552536D01*
G01X45450Y552161D02*
Y554661D01*
X44950Y554161D01*
G01Y552161D02*
X45950D01*
G01X47842Y552453D02*
X48133Y552244D01*
X48467Y552161D01*
X48800Y552244D01*
X49092Y552494D01*
X49300Y552869D01*
X49383Y553244D01*
Y553703D01*
X49300Y554078D01*
X49092Y554411D01*
X48842Y554578D01*
X48550Y554661D01*
X48217Y554578D01*
X47967Y554411D01*
X47800Y554161D01*
X47717Y553828D01*
X47800Y553536D01*
X48008Y553244D01*
X48258Y553078D01*
X48550Y553036D01*
X48883Y553119D01*
X49133Y553328D01*
X49383Y553703D01*
G01X50733Y552536D02*
X50983Y552328D01*
X51275Y552203D01*
X51650Y552161D01*
X52025Y552244D01*
X52317Y552411D01*
X52525Y552703D01*
X52567Y553036D01*
X52483Y553369D01*
X52275Y553578D01*
X51983Y553744D01*
X51692Y553786D01*
X51400Y553744D01*
X51025Y553578D01*
X51150Y554661D01*
X52275D01*
G01X49517Y538661D02*
Y541161D01*
X50558D01*
X50892Y541036D01*
X51100Y540869D01*
X51183Y540536D01*
X51100Y540203D01*
X50850Y539994D01*
X50558Y539869D01*
X49517D01*
G01X50558D02*
X51183Y538661D01*
G01X52533Y539161D02*
X52783Y538869D01*
X53117Y538703D01*
X53492Y538661D01*
X53825Y538703D01*
X54158Y538911D01*
X54367Y539161D01*
X54408Y539411D01*
X54325Y539703D01*
X54033Y539911D01*
X53742Y539994D01*
X53367D01*
G01X53742D02*
X53992Y540119D01*
X54200Y540328D01*
X54283Y540578D01*
X54200Y540828D01*
X53992Y541036D01*
X53617Y541161D01*
X53242Y541119D01*
X52867Y540953D01*
G01X55633Y539036D02*
X55883Y538828D01*
X56175Y538703D01*
X56550Y538661D01*
X56925Y538744D01*
X57217Y538911D01*
X57425Y539203D01*
X57467Y539536D01*
X57383Y539869D01*
X57175Y540078D01*
X56883Y540244D01*
X56592Y540286D01*
X56300Y540244D01*
X55925Y540078D01*
X56050Y541161D01*
X57175D01*
G01X58733Y539036D02*
X58983Y538828D01*
X59275Y538703D01*
X59650Y538661D01*
X60025Y538744D01*
X60317Y538911D01*
X60525Y539203D01*
X60567Y539536D01*
X60483Y539869D01*
X60275Y540078D01*
X59983Y540244D01*
X59692Y540286D01*
X59400Y540244D01*
X59025Y540078D01*
X59150Y541161D01*
X60275D01*
G01X62300Y545500D02*
Y541500D01*
X69700D01*
G01X85517Y506500D02*
Y509000D01*
X86558D01*
X86892Y508875D01*
X87100Y508708D01*
X87183Y508375D01*
X87100Y508042D01*
X86850Y507833D01*
X86558Y507708D01*
X85517D01*
G01X86558D02*
X87183Y506500D01*
G01X88533Y507000D02*
X88783Y506708D01*
X89117Y506542D01*
X89492Y506500D01*
X89825Y506542D01*
X90158Y506750D01*
X90367Y507000D01*
X90408Y507250D01*
X90325Y507542D01*
X90033Y507750D01*
X89742Y507833D01*
X89367D01*
G01X89742D02*
X89992Y507958D01*
X90200Y508167D01*
X90283Y508417D01*
X90200Y508667D01*
X89992Y508875D01*
X89617Y509000D01*
X89242Y508958D01*
X88867Y508792D01*
G01X91633Y506875D02*
X91883Y506667D01*
X92175Y506542D01*
X92550Y506500D01*
X92925Y506583D01*
X93217Y506750D01*
X93425Y507042D01*
X93467Y507375D01*
X93383Y507708D01*
X93175Y507917D01*
X92883Y508083D01*
X92592Y508125D01*
X92300Y508083D01*
X91925Y507917D01*
X92050Y509000D01*
X93175D01*
G01X94858Y507542D02*
X95150Y507833D01*
X95400Y508000D01*
X95733Y508083D01*
X96025Y508000D01*
X96233Y507833D01*
X96400Y507583D01*
X96442Y507292D01*
X96400Y507042D01*
X96233Y506792D01*
X95983Y506583D01*
X95692Y506500D01*
X95358Y506583D01*
X95067Y506833D01*
X94900Y507208D01*
X94858Y507625D01*
X94942Y508167D01*
X95067Y508458D01*
X95275Y508750D01*
X95567Y508958D01*
X95858Y509000D01*
X96150Y508917D01*
X96358Y508708D01*
G01X94000Y523300D02*
Y527300D01*
X86600D01*
G01X85517Y502000D02*
Y504500D01*
X86558D01*
X86892Y504375D01*
X87100Y504208D01*
X87183Y503875D01*
X87100Y503542D01*
X86850Y503333D01*
X86558Y503208D01*
X85517D01*
G01X86558D02*
X87183Y502000D01*
G01X88533Y502500D02*
X88783Y502208D01*
X89117Y502042D01*
X89492Y502000D01*
X89825Y502042D01*
X90158Y502250D01*
X90367Y502500D01*
X90408Y502750D01*
X90325Y503042D01*
X90033Y503250D01*
X89742Y503333D01*
X89367D01*
G01X89742D02*
X89992Y503458D01*
X90200Y503667D01*
X90283Y503917D01*
X90200Y504167D01*
X89992Y504375D01*
X89617Y504500D01*
X89242Y504458D01*
X88867Y504292D01*
G01X91633Y502375D02*
X91883Y502167D01*
X92175Y502042D01*
X92550Y502000D01*
X92925Y502083D01*
X93217Y502250D01*
X93425Y502542D01*
X93467Y502875D01*
X93383Y503208D01*
X93175Y503417D01*
X92883Y503583D01*
X92592Y503625D01*
X92300Y503583D01*
X91925Y503417D01*
X92050Y504500D01*
X93175D01*
G01X95650Y502000D02*
X95942Y502042D01*
X96275Y502167D01*
X96483Y502375D01*
X96567Y502667D01*
X96483Y502958D01*
X96233Y503208D01*
X95858Y503333D01*
X95442D01*
X95192Y503417D01*
X94983Y503625D01*
X94900Y503917D01*
X95025Y504208D01*
X95317Y504417D01*
X95650Y504500D01*
X95983Y504417D01*
X96275Y504208D01*
X96400Y503917D01*
X96317Y503625D01*
X96108Y503417D01*
X95858Y503333D01*
X95442D01*
X95067Y503208D01*
X94817Y502958D01*
X94733Y502667D01*
X94817Y502375D01*
X95025Y502167D01*
X95358Y502042D01*
X95650Y502000D01*
G01X92300Y514800D02*
Y518800D01*
X84900D01*
G01X85517Y510500D02*
Y513000D01*
X86558D01*
X86892Y512875D01*
X87100Y512708D01*
X87183Y512375D01*
X87100Y512042D01*
X86850Y511833D01*
X86558Y511708D01*
X85517D01*
G01X86558D02*
X87183Y510500D01*
G01X88533Y511000D02*
X88783Y510708D01*
X89117Y510542D01*
X89492Y510500D01*
X89825Y510542D01*
X90158Y510750D01*
X90367Y511000D01*
X90408Y511250D01*
X90325Y511542D01*
X90033Y511750D01*
X89742Y511833D01*
X89367D01*
G01X89742D02*
X89992Y511958D01*
X90200Y512167D01*
X90283Y512417D01*
X90200Y512667D01*
X89992Y512875D01*
X89617Y513000D01*
X89242Y512958D01*
X88867Y512792D01*
G01X91633Y510875D02*
X91883Y510667D01*
X92175Y510542D01*
X92550Y510500D01*
X92925Y510583D01*
X93217Y510750D01*
X93425Y511042D01*
X93467Y511375D01*
X93383Y511708D01*
X93175Y511917D01*
X92883Y512083D01*
X92592Y512125D01*
X92300Y512083D01*
X91925Y511917D01*
X92050Y513000D01*
X93175D01*
G01X94942Y510792D02*
X95233Y510583D01*
X95567Y510500D01*
X95900Y510583D01*
X96192Y510833D01*
X96400Y511208D01*
X96483Y511583D01*
Y512042D01*
X96400Y512417D01*
X96192Y512750D01*
X95942Y512917D01*
X95650Y513000D01*
X95317Y512917D01*
X95067Y512750D01*
X94900Y512500D01*
X94817Y512167D01*
X94900Y511875D01*
X95108Y511583D01*
X95358Y511417D01*
X95650Y511375D01*
X95983Y511458D01*
X96233Y511667D01*
X96483Y512042D01*
G01X86800Y531500D02*
Y527500D01*
X94200D01*
G01X50517Y511000D02*
Y513500D01*
X51558D01*
X51892Y513375D01*
X52100Y513208D01*
X52183Y512875D01*
X52100Y512542D01*
X51850Y512333D01*
X51558Y512208D01*
X50517D01*
G01X51558D02*
X52183Y511000D01*
G01X53533Y511500D02*
X53783Y511208D01*
X54117Y511042D01*
X54492Y511000D01*
X54825Y511042D01*
X55158Y511250D01*
X55367Y511500D01*
X55408Y511750D01*
X55325Y512042D01*
X55033Y512250D01*
X54742Y512333D01*
X54367D01*
G01X54742D02*
X54992Y512458D01*
X55200Y512667D01*
X55283Y512917D01*
X55200Y513167D01*
X54992Y513375D01*
X54617Y513500D01*
X54242Y513458D01*
X53867Y513292D01*
G01X56758Y512042D02*
X57050Y512333D01*
X57300Y512500D01*
X57633Y512583D01*
X57925Y512500D01*
X58133Y512333D01*
X58300Y512083D01*
X58342Y511792D01*
X58300Y511542D01*
X58133Y511292D01*
X57883Y511083D01*
X57592Y511000D01*
X57258Y511083D01*
X56967Y511333D01*
X56800Y511708D01*
X56758Y512125D01*
X56842Y512667D01*
X56967Y512958D01*
X57175Y513250D01*
X57467Y513458D01*
X57758Y513500D01*
X58050Y513417D01*
X58258Y513208D01*
G01X60650Y513500D02*
X60317Y513417D01*
X60067Y513208D01*
X59900Y512958D01*
X59775Y512625D01*
X59733Y512250D01*
X59775Y511875D01*
X59900Y511542D01*
X60067Y511292D01*
X60317Y511083D01*
X60650Y511000D01*
X60983Y511083D01*
X61233Y511292D01*
X61400Y511542D01*
X61525Y511875D01*
X61567Y512250D01*
X61525Y512625D01*
X61400Y512958D01*
X61233Y513208D01*
X60983Y513417D01*
X60650Y513500D01*
G01X54800Y520000D02*
Y516000D01*
X62200D01*
G01X41517Y548161D02*
Y550661D01*
X42558D01*
X42892Y550536D01*
X43100Y550369D01*
X43183Y550036D01*
X43100Y549703D01*
X42850Y549494D01*
X42558Y549369D01*
X41517D01*
G01X42558D02*
X43183Y548161D01*
G01X44533Y548661D02*
X44783Y548369D01*
X45117Y548203D01*
X45492Y548161D01*
X45825Y548203D01*
X46158Y548411D01*
X46367Y548661D01*
X46408Y548911D01*
X46325Y549203D01*
X46033Y549411D01*
X45742Y549494D01*
X45367D01*
G01X45742D02*
X45992Y549619D01*
X46200Y549828D01*
X46283Y550078D01*
X46200Y550328D01*
X45992Y550536D01*
X45617Y550661D01*
X45242Y550619D01*
X44867Y550453D01*
G01X47758Y549203D02*
X48050Y549494D01*
X48300Y549661D01*
X48633Y549744D01*
X48925Y549661D01*
X49133Y549494D01*
X49300Y549244D01*
X49342Y548953D01*
X49300Y548703D01*
X49133Y548453D01*
X48883Y548244D01*
X48592Y548161D01*
X48258Y548244D01*
X47967Y548494D01*
X47800Y548869D01*
X47758Y549286D01*
X47842Y549828D01*
X47967Y550119D01*
X48175Y550411D01*
X48467Y550619D01*
X48758Y550661D01*
X49050Y550578D01*
X49258Y550369D01*
G01X51650Y548161D02*
Y550661D01*
X51150Y550161D01*
G01Y548161D02*
X52150D01*
G01X62200Y547000D02*
Y551000D01*
X54800D01*
G01X56000Y521517D02*
X53500D01*
Y522558D01*
X53625Y522892D01*
X53792Y523100D01*
X54125Y523183D01*
X54458Y523100D01*
X54667Y522850D01*
X54792Y522558D01*
Y521517D01*
G01Y522558D02*
X56000Y523183D01*
G01X55500Y524533D02*
X55792Y524783D01*
X55958Y525117D01*
X56000Y525492D01*
X55958Y525825D01*
X55750Y526158D01*
X55500Y526367D01*
X55250Y526408D01*
X54958Y526325D01*
X54750Y526033D01*
X54667Y525742D01*
Y525367D01*
G01Y525742D02*
X54542Y525992D01*
X54333Y526200D01*
X54083Y526283D01*
X53833Y526200D01*
X53625Y525992D01*
X53500Y525617D01*
X53542Y525242D01*
X53708Y524867D01*
G01X54958Y527758D02*
X54667Y528050D01*
X54500Y528300D01*
X54417Y528633D01*
X54500Y528925D01*
X54667Y529133D01*
X54917Y529300D01*
X55208Y529342D01*
X55458Y529300D01*
X55708Y529133D01*
X55917Y528883D01*
X56000Y528592D01*
X55917Y528258D01*
X55667Y527967D01*
X55292Y527800D01*
X54875Y527758D01*
X54333Y527842D01*
X54042Y527967D01*
X53750Y528175D01*
X53542Y528467D01*
X53500Y528758D01*
X53583Y529050D01*
X53792Y529258D01*
G01X53917Y530858D02*
X53667Y531108D01*
X53542Y531400D01*
X53500Y531733D01*
X53583Y532150D01*
X53792Y532442D01*
X54042Y532525D01*
X54292Y532483D01*
X54500Y532317D01*
X54917Y531483D01*
X55208Y531108D01*
X55625Y530858D01*
X56000Y530775D01*
Y532525D01*
G01X58000Y520300D02*
X62000D01*
Y527700D01*
G01X73500Y500017D02*
X71000D01*
Y501058D01*
X71125Y501392D01*
X71292Y501600D01*
X71625Y501683D01*
X71958Y501600D01*
X72167Y501350D01*
X72292Y501058D01*
Y500017D01*
G01Y501058D02*
X73500Y501683D01*
G01X73000Y503033D02*
X73292Y503283D01*
X73458Y503617D01*
X73500Y503992D01*
X73458Y504325D01*
X73250Y504658D01*
X73000Y504867D01*
X72750Y504908D01*
X72458Y504825D01*
X72250Y504533D01*
X72167Y504242D01*
Y503867D01*
G01Y504242D02*
X72042Y504492D01*
X71833Y504700D01*
X71583Y504783D01*
X71333Y504700D01*
X71125Y504492D01*
X71000Y504117D01*
X71042Y503742D01*
X71208Y503367D01*
G01X72458Y506258D02*
X72167Y506550D01*
X72000Y506800D01*
X71917Y507133D01*
X72000Y507425D01*
X72167Y507633D01*
X72417Y507800D01*
X72708Y507842D01*
X72958Y507800D01*
X73208Y507633D01*
X73417Y507383D01*
X73500Y507092D01*
X73417Y506758D01*
X73167Y506467D01*
X72792Y506300D01*
X72375Y506258D01*
X71833Y506342D01*
X71542Y506467D01*
X71250Y506675D01*
X71042Y506967D01*
X71000Y507258D01*
X71083Y507550D01*
X71292Y507758D01*
G01X73000Y509233D02*
X73292Y509483D01*
X73458Y509817D01*
X73500Y510192D01*
X73458Y510525D01*
X73250Y510858D01*
X73000Y511067D01*
X72750Y511108D01*
X72458Y511025D01*
X72250Y510733D01*
X72167Y510442D01*
Y510067D01*
G01Y510442D02*
X72042Y510692D01*
X71833Y510900D01*
X71583Y510983D01*
X71333Y510900D01*
X71125Y510692D01*
X71000Y510317D01*
X71042Y509942D01*
X71208Y509567D01*
G01X74500Y521700D02*
X70500D01*
Y514300D01*
G01X78900Y571000D02*
X78567Y571042D01*
X78275Y571208D01*
X78025Y571458D01*
X77858Y571750D01*
X77775Y572083D01*
Y572417D01*
X77858Y572750D01*
X78025Y573042D01*
X78275Y573292D01*
X78567Y573458D01*
X78900Y573500D01*
X79233Y573458D01*
X79525Y573292D01*
X79775Y573042D01*
X79942Y572750D01*
X80025Y572417D01*
Y572083D01*
X79942Y571750D01*
X79775Y571458D01*
X79525Y571208D01*
X79233Y571042D01*
X78900Y571000D01*
G01X79233Y571667D02*
X79733Y571000D01*
G01X82500D02*
Y573500D01*
X80958Y571708D01*
X83042D01*
G01X84308Y572042D02*
X84600Y572333D01*
X84850Y572500D01*
X85183Y572583D01*
X85475Y572500D01*
X85683Y572333D01*
X85850Y572083D01*
X85892Y571792D01*
X85850Y571542D01*
X85683Y571292D01*
X85433Y571083D01*
X85142Y571000D01*
X84808Y571083D01*
X84517Y571333D01*
X84350Y571708D01*
X84308Y572125D01*
X84392Y572667D01*
X84517Y572958D01*
X84725Y573250D01*
X85017Y573458D01*
X85308Y573500D01*
X85600Y573417D01*
X85808Y573208D01*
G01X92200Y554000D02*
X90100Y555800D01*
X92200Y558000D01*
G01X92300Y561600D02*
X73100D01*
Y550400D01*
X92300D01*
Y561600D01*
X91900D01*
G01X47700Y568400D02*
X66900D01*
Y579600D01*
X47700D01*
Y568400D01*
X48100D01*
G01X67500Y503483D02*
X65000D01*
Y504317D01*
X65125Y504650D01*
X65292Y504900D01*
X65542Y505108D01*
X65833Y505275D01*
X66250Y505317D01*
X66667Y505275D01*
X66958Y505108D01*
X67208Y504900D01*
X67375Y504650D01*
X67500Y504317D01*
Y503483D01*
G01Y507500D02*
X65000D01*
X65500Y507000D01*
G01X67500D02*
Y508000D01*
G01X65417Y509808D02*
X65167Y510058D01*
X65042Y510350D01*
X65000Y510683D01*
X65083Y511100D01*
X65292Y511392D01*
X65542Y511475D01*
X65792Y511433D01*
X66000Y511267D01*
X66417Y510433D01*
X66708Y510058D01*
X67125Y509808D01*
X67500Y509725D01*
Y511475D01*
G01X70000Y530500D02*
Y514400D01*
G01X63000Y530500D02*
X70000D01*
G01X63000Y514400D02*
Y530500D01*
G01X70000Y514400D02*
X63000D01*
G01X74000Y528900D02*
X73958Y528567D01*
X73792Y528275D01*
X73542Y528025D01*
X73250Y527858D01*
X72917Y527775D01*
X72583D01*
X72250Y527858D01*
X71958Y528025D01*
X71708Y528275D01*
X71542Y528567D01*
X71500Y528900D01*
X71542Y529233D01*
X71708Y529525D01*
X71958Y529775D01*
X72250Y529942D01*
X72583Y530025D01*
X72917D01*
X73250Y529942D01*
X73542Y529775D01*
X73792Y529525D01*
X73958Y529233D01*
X74000Y528900D01*
G01X73333Y529233D02*
X74000Y529733D01*
G01Y532500D02*
X71500D01*
X73292Y530958D01*
Y533042D01*
G01X74000Y535017D02*
X73458Y535100D01*
X73000Y535225D01*
X72583Y535392D01*
X72125Y535600D01*
X71500Y535933D01*
Y534267D01*
G01X86200Y536200D02*
X74800D01*
G01X86200Y522800D02*
Y536200D01*
G01X74800Y522800D02*
X86200D01*
G01X74800Y536200D02*
Y522800D01*
G01X99275Y661500D02*
Y664000D01*
G01X101025D02*
Y661500D01*
G01Y662750D02*
X99275D01*
G01X102333Y661500D02*
Y664000D01*
X103167D01*
X103500Y663875D01*
X103750Y663708D01*
X103958Y663458D01*
X104125Y663167D01*
X104167Y662750D01*
X104125Y662333D01*
X103958Y662042D01*
X103750Y661792D01*
X103500Y661625D01*
X103167Y661500D01*
X102333D01*
G01X105433D02*
Y664000D01*
X106267D01*
X106600Y663875D01*
X106850Y663708D01*
X107058Y663458D01*
X107225Y663167D01*
X107267Y662750D01*
X107225Y662333D01*
X107058Y662042D01*
X106850Y661792D01*
X106600Y661625D01*
X106267Y661500D01*
X105433D01*
G01X108575Y661833D02*
X108908Y661625D01*
X109283Y661500D01*
X109617D01*
X109950Y661625D01*
X110200Y661833D01*
X110325Y662125D01*
X110242Y662417D01*
X110033Y662667D01*
X109658Y662833D01*
X109158Y662917D01*
X108867Y663083D01*
X108742Y663375D01*
X108825Y663667D01*
X109033Y663875D01*
X109325Y664000D01*
X109617D01*
X109908Y663917D01*
X110158Y663708D01*
G01X111508Y661500D02*
X112550Y664000D01*
X113592Y661500D01*
G01X113217Y662375D02*
X111883D01*
G01X114775Y661833D02*
X115108Y661625D01*
X115483Y661500D01*
X115817D01*
X116150Y661625D01*
X116400Y661833D01*
X116525Y662125D01*
X116442Y662417D01*
X116233Y662667D01*
X115858Y662833D01*
X115358Y662917D01*
X115067Y663083D01*
X114942Y663375D01*
X115025Y663667D01*
X115233Y663875D01*
X115525Y664000D01*
X115817D01*
X116108Y663917D01*
X116358Y663708D01*
G01X118750Y661500D02*
Y664000D01*
X118250Y663500D01*
G01Y661500D02*
X119250D01*
G01X121058Y663583D02*
X121308Y663833D01*
X121600Y663958D01*
X121933Y664000D01*
X122350Y663917D01*
X122642Y663708D01*
X122725Y663458D01*
X122683Y663208D01*
X122517Y663000D01*
X121683Y662583D01*
X121308Y662292D01*
X121058Y661875D01*
X120975Y661500D01*
X122725D01*
G01X71667Y609292D02*
X71417Y609417D01*
X71125Y609500D01*
X70792D01*
X70417Y609375D01*
X70125Y609167D01*
X69917Y608917D01*
X69750Y608500D01*
X69708Y608125D01*
X69792Y607750D01*
X69917Y607500D01*
X70167Y607250D01*
X70458Y607083D01*
X70750Y607000D01*
X71042D01*
X71333Y607083D01*
X71583Y607208D01*
X71792Y607375D01*
G01X73850Y607000D02*
Y609500D01*
X73350Y609000D01*
G01Y607000D02*
X74350D01*
G01X76950D02*
X77242Y607042D01*
X77575Y607167D01*
X77783Y607375D01*
X77867Y607667D01*
X77783Y607958D01*
X77533Y608208D01*
X77158Y608333D01*
X76742D01*
X76492Y608417D01*
X76283Y608625D01*
X76200Y608917D01*
X76325Y609208D01*
X76617Y609417D01*
X76950Y609500D01*
X77283Y609417D01*
X77575Y609208D01*
X77700Y608917D01*
X77617Y608625D01*
X77408Y608417D01*
X77158Y608333D01*
X76742D01*
X76367Y608208D01*
X76117Y607958D01*
X76033Y607667D01*
X76117Y607375D01*
X76325Y607167D01*
X76658Y607042D01*
X76950Y607000D01*
G01X79258Y608042D02*
X79550Y608333D01*
X79800Y608500D01*
X80133Y608583D01*
X80425Y608500D01*
X80633Y608333D01*
X80800Y608083D01*
X80842Y607792D01*
X80800Y607542D01*
X80633Y607292D01*
X80383Y607083D01*
X80092Y607000D01*
X79758Y607083D01*
X79467Y607333D01*
X79300Y607708D01*
X79258Y608125D01*
X79342Y608667D01*
X79467Y608958D01*
X79675Y609250D01*
X79967Y609458D01*
X80258Y609500D01*
X80550Y609417D01*
X80758Y609208D01*
G01X88708Y632767D02*
X88583Y632517D01*
X88500Y632225D01*
Y631892D01*
X88625Y631517D01*
X88833Y631225D01*
X89083Y631017D01*
X89500Y630850D01*
X89875Y630808D01*
X90250Y630892D01*
X90500Y631017D01*
X90750Y631267D01*
X90917Y631558D01*
X91000Y631850D01*
Y632142D01*
X90917Y632433D01*
X90792Y632683D01*
X90625Y632892D01*
G01X91000Y634950D02*
X88500D01*
X89000Y634450D01*
G01X91000D02*
Y635450D01*
G01X90708Y637342D02*
X90917Y637633D01*
X91000Y637967D01*
X90917Y638300D01*
X90667Y638592D01*
X90292Y638800D01*
X89917Y638883D01*
X89458D01*
X89083Y638800D01*
X88750Y638592D01*
X88583Y638342D01*
X88500Y638050D01*
X88583Y637717D01*
X88750Y637467D01*
X89000Y637300D01*
X89333Y637217D01*
X89625Y637300D01*
X89917Y637508D01*
X90083Y637758D01*
X90125Y638050D01*
X90042Y638383D01*
X89833Y638633D01*
X89458Y638883D01*
G01X90500Y640233D02*
X90792Y640483D01*
X90958Y640817D01*
X91000Y641192D01*
X90958Y641525D01*
X90750Y641858D01*
X90500Y642067D01*
X90250Y642108D01*
X89958Y642025D01*
X89750Y641733D01*
X89667Y641442D01*
Y641067D01*
G01Y641442D02*
X89542Y641692D01*
X89333Y641900D01*
X89083Y641983D01*
X88833Y641900D01*
X88625Y641692D01*
X88500Y641317D01*
X88542Y640942D01*
X88708Y640567D01*
G01X38900Y572500D02*
X38567Y572542D01*
X38275Y572708D01*
X38025Y572958D01*
X37858Y573250D01*
X37775Y573583D01*
Y573917D01*
X37858Y574250D01*
X38025Y574542D01*
X38275Y574792D01*
X38567Y574958D01*
X38900Y575000D01*
X39233Y574958D01*
X39525Y574792D01*
X39775Y574542D01*
X39942Y574250D01*
X40025Y573917D01*
Y573583D01*
X39942Y573250D01*
X39775Y572958D01*
X39525Y572708D01*
X39233Y572542D01*
X38900Y572500D01*
G01X39233Y573167D02*
X39733Y572500D01*
G01X42500D02*
Y575000D01*
X40958Y573208D01*
X43042D01*
G01X45100Y572500D02*
X45392Y572542D01*
X45725Y572667D01*
X45933Y572875D01*
X46017Y573167D01*
X45933Y573458D01*
X45683Y573708D01*
X45308Y573833D01*
X44892D01*
X44642Y573917D01*
X44433Y574125D01*
X44350Y574417D01*
X44475Y574708D01*
X44767Y574917D01*
X45100Y575000D01*
X45433Y574917D01*
X45725Y574708D01*
X45850Y574417D01*
X45767Y574125D01*
X45558Y573917D01*
X45308Y573833D01*
X44892D01*
X44517Y573708D01*
X44267Y573458D01*
X44183Y573167D01*
X44267Y572875D01*
X44475Y572667D01*
X44808Y572542D01*
X45100Y572500D01*
G01X47800Y576000D02*
X49900Y574200D01*
X47800Y572000D01*
G01X71767Y604953D02*
X71517Y605078D01*
X71225Y605161D01*
X70892D01*
X70517Y605036D01*
X70225Y604828D01*
X70017Y604578D01*
X69850Y604161D01*
X69808Y603786D01*
X69892Y603411D01*
X70017Y603161D01*
X70267Y602911D01*
X70558Y602744D01*
X70850Y602661D01*
X71142D01*
X71433Y602744D01*
X71683Y602869D01*
X71892Y603036D01*
G01X73950Y602661D02*
Y605161D01*
X73450Y604661D01*
G01Y602661D02*
X74450D01*
G01X77050D02*
X77342Y602703D01*
X77675Y602828D01*
X77883Y603036D01*
X77967Y603328D01*
X77883Y603619D01*
X77633Y603869D01*
X77258Y603994D01*
X76842D01*
X76592Y604078D01*
X76383Y604286D01*
X76300Y604578D01*
X76425Y604869D01*
X76717Y605078D01*
X77050Y605161D01*
X77383Y605078D01*
X77675Y604869D01*
X77800Y604578D01*
X77717Y604286D01*
X77508Y604078D01*
X77258Y603994D01*
X76842D01*
X76467Y603869D01*
X76217Y603619D01*
X76133Y603328D01*
X76217Y603036D01*
X76425Y602828D01*
X76758Y602703D01*
X77050Y602661D01*
G01X80067D02*
X80150Y603203D01*
X80275Y603661D01*
X80442Y604078D01*
X80650Y604536D01*
X80983Y605161D01*
X79317D01*
G01X87800Y574500D02*
X82300D01*
G01X87800Y582500D02*
Y574500D01*
G01X82300Y582500D02*
X87800D01*
G01X70200D02*
X75700D01*
G01X70200Y574500D02*
Y582500D01*
G01X75700Y574500D02*
X70200D01*
G01X95000Y594017D02*
X92500D01*
Y595058D01*
X92625Y595392D01*
X92792Y595600D01*
X93125Y595683D01*
X93458Y595600D01*
X93667Y595350D01*
X93792Y595058D01*
Y594017D01*
G01Y595058D02*
X95000Y595683D01*
G01X94500Y597033D02*
X94792Y597283D01*
X94958Y597617D01*
X95000Y597992D01*
X94958Y598325D01*
X94750Y598658D01*
X94500Y598867D01*
X94250Y598908D01*
X93958Y598825D01*
X93750Y598533D01*
X93667Y598242D01*
Y597867D01*
G01Y598242D02*
X93542Y598492D01*
X93333Y598700D01*
X93083Y598783D01*
X92833Y598700D01*
X92625Y598492D01*
X92500Y598117D01*
X92542Y597742D01*
X92708Y597367D01*
G01X94625Y600133D02*
X94833Y600383D01*
X94958Y600675D01*
X95000Y601050D01*
X94917Y601425D01*
X94750Y601717D01*
X94458Y601925D01*
X94125Y601967D01*
X93792Y601883D01*
X93583Y601675D01*
X93417Y601383D01*
X93375Y601092D01*
X93417Y600800D01*
X93583Y600425D01*
X92500Y600550D01*
Y601675D01*
G01Y604150D02*
X92583Y603817D01*
X92792Y603567D01*
X93042Y603400D01*
X93375Y603275D01*
X93750Y603233D01*
X94125Y603275D01*
X94458Y603400D01*
X94708Y603567D01*
X94917Y603817D01*
X95000Y604150D01*
X94917Y604483D01*
X94708Y604733D01*
X94458Y604900D01*
X94125Y605025D01*
X93750Y605067D01*
X93375Y605025D01*
X93042Y604900D01*
X92792Y604733D01*
X92583Y604483D01*
X92500Y604150D01*
G01X89500Y592300D02*
X97500D01*
Y574700D01*
X89500D01*
Y592300D01*
G01X70017Y611000D02*
Y613500D01*
X71058D01*
X71392Y613375D01*
X71600Y613208D01*
X71683Y612875D01*
X71600Y612542D01*
X71350Y612333D01*
X71058Y612208D01*
X70017D01*
G01X71058D02*
X71683Y611000D01*
G01X73033Y611500D02*
X73283Y611208D01*
X73617Y611042D01*
X73992Y611000D01*
X74325Y611042D01*
X74658Y611250D01*
X74867Y611500D01*
X74908Y611750D01*
X74825Y612042D01*
X74533Y612250D01*
X74242Y612333D01*
X73867D01*
G01X74242D02*
X74492Y612458D01*
X74700Y612667D01*
X74783Y612917D01*
X74700Y613167D01*
X74492Y613375D01*
X74117Y613500D01*
X73742Y613458D01*
X73367Y613292D01*
G01X76133Y611375D02*
X76383Y611167D01*
X76675Y611042D01*
X77050Y611000D01*
X77425Y611083D01*
X77717Y611250D01*
X77925Y611542D01*
X77967Y611875D01*
X77883Y612208D01*
X77675Y612417D01*
X77383Y612583D01*
X77092Y612625D01*
X76800Y612583D01*
X76425Y612417D01*
X76550Y613500D01*
X77675D01*
G01X79358Y613083D02*
X79608Y613333D01*
X79900Y613458D01*
X80233Y613500D01*
X80650Y613417D01*
X80942Y613208D01*
X81025Y612958D01*
X80983Y612708D01*
X80817Y612500D01*
X79983Y612083D01*
X79608Y611792D01*
X79358Y611375D01*
X79275Y611000D01*
X81025D01*
G01X65700Y589000D02*
Y597000D01*
X83300D01*
Y589000D01*
X65700D01*
G01X53767Y600792D02*
X53517Y600917D01*
X53225Y601000D01*
X52892D01*
X52517Y600875D01*
X52225Y600667D01*
X52017Y600417D01*
X51850Y600000D01*
X51808Y599625D01*
X51892Y599250D01*
X52017Y599000D01*
X52267Y598750D01*
X52558Y598583D01*
X52850Y598500D01*
X53142D01*
X53433Y598583D01*
X53683Y598708D01*
X53892Y598875D01*
G01X55950Y598500D02*
Y601000D01*
X55450Y600500D01*
G01Y598500D02*
X56450D01*
G01X58342Y598792D02*
X58633Y598583D01*
X58967Y598500D01*
X59300Y598583D01*
X59592Y598833D01*
X59800Y599208D01*
X59883Y599583D01*
Y600042D01*
X59800Y600417D01*
X59592Y600750D01*
X59342Y600917D01*
X59050Y601000D01*
X58717Y600917D01*
X58467Y600750D01*
X58300Y600500D01*
X58217Y600167D01*
X58300Y599875D01*
X58508Y599583D01*
X58758Y599417D01*
X59050Y599375D01*
X59383Y599458D01*
X59633Y599667D01*
X59883Y600042D01*
G01X62150Y598500D02*
Y601000D01*
X61650Y600500D01*
G01Y598500D02*
X62650D01*
G01X86208Y619267D02*
X86083Y619017D01*
X86000Y618725D01*
Y618392D01*
X86125Y618017D01*
X86333Y617725D01*
X86583Y617517D01*
X87000Y617350D01*
X87375Y617308D01*
X87750Y617392D01*
X88000Y617517D01*
X88250Y617767D01*
X88417Y618058D01*
X88500Y618350D01*
Y618642D01*
X88417Y618933D01*
X88292Y619183D01*
X88125Y619392D01*
G01X88500Y621450D02*
X86000D01*
X86500Y620950D01*
G01X88500D02*
Y621950D01*
G01X88208Y623842D02*
X88417Y624133D01*
X88500Y624467D01*
X88417Y624800D01*
X88167Y625092D01*
X87792Y625300D01*
X87417Y625383D01*
X86958D01*
X86583Y625300D01*
X86250Y625092D01*
X86083Y624842D01*
X86000Y624550D01*
X86083Y624217D01*
X86250Y623967D01*
X86500Y623800D01*
X86833Y623717D01*
X87125Y623800D01*
X87417Y624008D01*
X87583Y624258D01*
X87625Y624550D01*
X87542Y624883D01*
X87333Y625133D01*
X86958Y625383D01*
G01X86417Y626858D02*
X86167Y627108D01*
X86042Y627400D01*
X86000Y627733D01*
X86083Y628150D01*
X86292Y628442D01*
X86542Y628525D01*
X86792Y628483D01*
X87000Y628317D01*
X87417Y627483D01*
X87708Y627108D01*
X88125Y626858D01*
X88500Y626775D01*
Y628525D01*
G01X64517Y721000D02*
Y718500D01*
X66183D01*
G01X69283D02*
X67617D01*
Y721000D01*
X69283D01*
G01X68617Y719792D02*
X67617D01*
G01X70633Y718500D02*
Y721000D01*
X71467D01*
X71800Y720875D01*
X72050Y720708D01*
X72258Y720458D01*
X72425Y720167D01*
X72467Y719750D01*
X72425Y719333D01*
X72258Y719042D01*
X72050Y718792D01*
X71800Y718625D01*
X71467Y718500D01*
X70633D01*
G01X74650D02*
Y721000D01*
X74150Y720500D01*
G01Y718500D02*
X75150D01*
G01X65679Y704636D02*
Y715836D01*
X74479D01*
Y704636D01*
X65679D01*
G01X28017Y834500D02*
Y837000D01*
X29058D01*
X29392Y836875D01*
X29600Y836708D01*
X29683Y836375D01*
X29600Y836042D01*
X29350Y835833D01*
X29058Y835708D01*
X28017D01*
G01X29058D02*
X29683Y834500D01*
G01X31950D02*
Y837000D01*
X31450Y836500D01*
G01Y834500D02*
X32450D01*
G01X34133Y834875D02*
X34383Y834667D01*
X34675Y834542D01*
X35050Y834500D01*
X35425Y834583D01*
X35717Y834750D01*
X35925Y835042D01*
X35967Y835375D01*
X35883Y835708D01*
X35675Y835917D01*
X35383Y836083D01*
X35092Y836125D01*
X34800Y836083D01*
X34425Y835917D01*
X34550Y837000D01*
X35675D01*
G01X37233Y834875D02*
X37483Y834667D01*
X37775Y834542D01*
X38150Y834500D01*
X38525Y834583D01*
X38817Y834750D01*
X39025Y835042D01*
X39067Y835375D01*
X38983Y835708D01*
X38775Y835917D01*
X38483Y836083D01*
X38192Y836125D01*
X37900Y836083D01*
X37525Y835917D01*
X37650Y837000D01*
X38775D01*
G01X48392Y834182D02*
Y838182D01*
X40992D01*
G01X63125Y853959D02*
Y857959D01*
X55725D01*
G01X74000Y853017D02*
X71500D01*
Y854058D01*
X71625Y854392D01*
X71792Y854600D01*
X72125Y854683D01*
X72458Y854600D01*
X72667Y854350D01*
X72792Y854058D01*
Y853017D01*
G01Y854058D02*
X74000Y854683D01*
G01X71917Y856158D02*
X71667Y856408D01*
X71542Y856700D01*
X71500Y857033D01*
X71583Y857450D01*
X71792Y857742D01*
X72042Y857825D01*
X72292Y857783D01*
X72500Y857617D01*
X72917Y856783D01*
X73208Y856408D01*
X73625Y856158D01*
X74000Y856075D01*
Y857825D01*
G01X71500Y860050D02*
X71583Y859717D01*
X71792Y859467D01*
X72042Y859300D01*
X72375Y859175D01*
X72750Y859133D01*
X73125Y859175D01*
X73458Y859300D01*
X73708Y859467D01*
X73917Y859717D01*
X74000Y860050D01*
X73917Y860383D01*
X73708Y860633D01*
X73458Y860800D01*
X73125Y860925D01*
X72750Y860967D01*
X72375Y860925D01*
X72042Y860800D01*
X71792Y860633D01*
X71583Y860383D01*
X71500Y860050D01*
G01X74000Y863650D02*
X71500D01*
X73292Y862108D01*
Y864192D01*
G01X70000Y853017D02*
X67500D01*
Y854058D01*
X67625Y854392D01*
X67792Y854600D01*
X68125Y854683D01*
X68458Y854600D01*
X68667Y854350D01*
X68792Y854058D01*
Y853017D01*
G01Y854058D02*
X70000Y854683D01*
G01X67917Y856158D02*
X67667Y856408D01*
X67542Y856700D01*
X67500Y857033D01*
X67583Y857450D01*
X67792Y857742D01*
X68042Y857825D01*
X68292Y857783D01*
X68500Y857617D01*
X68917Y856783D01*
X69208Y856408D01*
X69625Y856158D01*
X70000Y856075D01*
Y857825D01*
G01X67500Y860050D02*
X67583Y859717D01*
X67792Y859467D01*
X68042Y859300D01*
X68375Y859175D01*
X68750Y859133D01*
X69125Y859175D01*
X69458Y859300D01*
X69708Y859467D01*
X69917Y859717D01*
X70000Y860050D01*
X69917Y860383D01*
X69708Y860633D01*
X69458Y860800D01*
X69125Y860925D01*
X68750Y860967D01*
X68375Y860925D01*
X68042Y860800D01*
X67792Y860633D01*
X67583Y860383D01*
X67500Y860050D01*
G01X69625Y862233D02*
X69833Y862483D01*
X69958Y862775D01*
X70000Y863150D01*
X69917Y863525D01*
X69750Y863817D01*
X69458Y864025D01*
X69125Y864067D01*
X68792Y863983D01*
X68583Y863775D01*
X68417Y863483D01*
X68375Y863192D01*
X68417Y862900D01*
X68583Y862525D01*
X67500Y862650D01*
Y863775D01*
G01X54850Y834500D02*
X54517Y834542D01*
X54225Y834708D01*
X53975Y834958D01*
X53808Y835250D01*
X53725Y835583D01*
Y835917D01*
X53808Y836250D01*
X53975Y836542D01*
X54225Y836792D01*
X54517Y836958D01*
X54850Y837000D01*
X55183Y836958D01*
X55475Y836792D01*
X55725Y836542D01*
X55892Y836250D01*
X55975Y835917D01*
Y835583D01*
X55892Y835250D01*
X55725Y834958D01*
X55475Y834708D01*
X55183Y834542D01*
X54850Y834500D01*
G01X55183Y835167D02*
X55683Y834500D01*
G01X57158Y836583D02*
X57408Y836833D01*
X57700Y836958D01*
X58033Y837000D01*
X58450Y836917D01*
X58742Y836708D01*
X58825Y836458D01*
X58783Y836208D01*
X58617Y836000D01*
X57783Y835583D01*
X57408Y835292D01*
X57158Y834875D01*
X57075Y834500D01*
X58825D01*
G01X61050D02*
Y837000D01*
X60550Y836500D01*
G01Y834500D02*
X61550D01*
G01X63442Y834792D02*
X63733Y834583D01*
X64067Y834500D01*
X64400Y834583D01*
X64692Y834833D01*
X64900Y835208D01*
X64983Y835583D01*
Y836042D01*
X64900Y836417D01*
X64692Y836750D01*
X64442Y836917D01*
X64150Y837000D01*
X63817Y836917D01*
X63567Y836750D01*
X63400Y836500D01*
X63317Y836167D01*
X63400Y835875D01*
X63608Y835583D01*
X63858Y835417D01*
X64150Y835375D01*
X64483Y835458D01*
X64733Y835667D01*
X64983Y836042D01*
G01X63800Y838500D02*
Y852500D01*
G01X50800Y838500D02*
X63800D01*
G01X50800Y852500D02*
Y838500D01*
G01X63800Y852500D02*
X50800D01*
G01X33350Y854500D02*
X33017Y854542D01*
X32725Y854708D01*
X32475Y854958D01*
X32308Y855250D01*
X32225Y855583D01*
Y855917D01*
X32308Y856250D01*
X32475Y856542D01*
X32725Y856792D01*
X33017Y856958D01*
X33350Y857000D01*
X33683Y856958D01*
X33975Y856792D01*
X34225Y856542D01*
X34392Y856250D01*
X34475Y855917D01*
Y855583D01*
X34392Y855250D01*
X34225Y854958D01*
X33975Y854708D01*
X33683Y854542D01*
X33350Y854500D01*
G01X33683Y855167D02*
X34183Y854500D01*
G01X35658Y856583D02*
X35908Y856833D01*
X36200Y856958D01*
X36533Y857000D01*
X36950Y856917D01*
X37242Y856708D01*
X37325Y856458D01*
X37283Y856208D01*
X37117Y856000D01*
X36283Y855583D01*
X35908Y855292D01*
X35658Y854875D01*
X35575Y854500D01*
X37325D01*
G01X40050D02*
Y857000D01*
X38508Y855208D01*
X40592D01*
G01X41733Y855000D02*
X41983Y854708D01*
X42317Y854542D01*
X42692Y854500D01*
X43025Y854542D01*
X43358Y854750D01*
X43567Y855000D01*
X43608Y855250D01*
X43525Y855542D01*
X43233Y855750D01*
X42942Y855833D01*
X42567D01*
G01X42942D02*
X43192Y855958D01*
X43400Y856167D01*
X43483Y856417D01*
X43400Y856667D01*
X43192Y856875D01*
X42817Y857000D01*
X42442Y856958D01*
X42067Y856792D01*
G01X35692Y839407D02*
X49692D01*
G01X35692Y852407D02*
Y839407D01*
G01X49692Y852407D02*
X35692D01*
G01X49692Y839407D02*
Y852407D01*
G01X94124Y1012831D02*
X99174D01*
Y1111531D01*
X123824D01*
Y927131D01*
X99174D01*
Y985831D01*
X94124D01*
Y1012831D01*
G01X84967Y923000D02*
Y925500D01*
X86008D01*
X86342Y925375D01*
X86550Y925208D01*
X86633Y924875D01*
X86550Y924542D01*
X86300Y924333D01*
X86008Y924208D01*
X84967D01*
G01X86008D02*
X86633Y923000D01*
G01X88900D02*
Y925500D01*
X88400Y925000D01*
G01Y923000D02*
X89400D01*
G01X92000D02*
Y925500D01*
X91500Y925000D01*
G01Y923000D02*
X92500D01*
G01X95100Y925500D02*
X94767Y925417D01*
X94517Y925208D01*
X94350Y924958D01*
X94225Y924625D01*
X94183Y924250D01*
X94225Y923875D01*
X94350Y923542D01*
X94517Y923292D01*
X94767Y923083D01*
X95100Y923000D01*
X95433Y923083D01*
X95683Y923292D01*
X95850Y923542D01*
X95975Y923875D01*
X96017Y924250D01*
X95975Y924625D01*
X95850Y924958D01*
X95683Y925208D01*
X95433Y925417D01*
X95100Y925500D01*
G01X98200D02*
X97867Y925417D01*
X97617Y925208D01*
X97450Y924958D01*
X97325Y924625D01*
X97283Y924250D01*
X97325Y923875D01*
X97450Y923542D01*
X97617Y923292D01*
X97867Y923083D01*
X98200Y923000D01*
X98533Y923083D01*
X98783Y923292D01*
X98950Y923542D01*
X99075Y923875D01*
X99117Y924250D01*
X99075Y924625D01*
X98950Y924958D01*
X98783Y925208D01*
X98533Y925417D01*
X98200Y925500D01*
G01X99963Y906025D02*
Y910025D01*
X92563D01*
G01X84967Y915000D02*
Y917500D01*
X86008D01*
X86342Y917375D01*
X86550Y917208D01*
X86633Y916875D01*
X86550Y916542D01*
X86300Y916333D01*
X86008Y916208D01*
X84967D01*
G01X86008D02*
X86633Y915000D01*
G01X88900D02*
Y917500D01*
X88400Y917000D01*
G01Y915000D02*
X89400D01*
G01X92000D02*
Y917500D01*
X91500Y917000D01*
G01Y915000D02*
X92500D01*
G01X95100Y917500D02*
X94767Y917417D01*
X94517Y917208D01*
X94350Y916958D01*
X94225Y916625D01*
X94183Y916250D01*
X94225Y915875D01*
X94350Y915542D01*
X94517Y915292D01*
X94767Y915083D01*
X95100Y915000D01*
X95433Y915083D01*
X95683Y915292D01*
X95850Y915542D01*
X95975Y915875D01*
X96017Y916250D01*
X95975Y916625D01*
X95850Y916958D01*
X95683Y917208D01*
X95433Y917417D01*
X95100Y917500D01*
G01X97283Y915375D02*
X97533Y915167D01*
X97825Y915042D01*
X98200Y915000D01*
X98575Y915083D01*
X98867Y915250D01*
X99075Y915542D01*
X99117Y915875D01*
X99033Y916208D01*
X98825Y916417D01*
X98533Y916583D01*
X98242Y916625D01*
X97950Y916583D01*
X97575Y916417D01*
X97700Y917500D01*
X98825D01*
G01X99055Y897023D02*
Y901023D01*
X91655D01*
G01X68967Y916000D02*
Y918500D01*
X70008D01*
X70342Y918375D01*
X70550Y918208D01*
X70633Y917875D01*
X70550Y917542D01*
X70300Y917333D01*
X70008Y917208D01*
X68967D01*
G01X70008D02*
X70633Y916000D01*
G01X72900D02*
Y918500D01*
X72400Y918000D01*
G01Y916000D02*
X73400D01*
G01X76000D02*
Y918500D01*
X75500Y918000D01*
G01Y916000D02*
X76500D01*
G01X79100Y918500D02*
X78767Y918417D01*
X78517Y918208D01*
X78350Y917958D01*
X78225Y917625D01*
X78183Y917250D01*
X78225Y916875D01*
X78350Y916542D01*
X78517Y916292D01*
X78767Y916083D01*
X79100Y916000D01*
X79433Y916083D01*
X79683Y916292D01*
X79850Y916542D01*
X79975Y916875D01*
X80017Y917250D01*
X79975Y917625D01*
X79850Y917958D01*
X79683Y918208D01*
X79433Y918417D01*
X79100Y918500D01*
G01X82117Y916000D02*
X82200Y916542D01*
X82325Y917000D01*
X82492Y917417D01*
X82700Y917875D01*
X83033Y918500D01*
X81367D01*
G01X91597Y899301D02*
Y903301D01*
X84197D01*
G01X68967Y920500D02*
Y923000D01*
X70008D01*
X70342Y922875D01*
X70550Y922708D01*
X70633Y922375D01*
X70550Y922042D01*
X70300Y921833D01*
X70008Y921708D01*
X68967D01*
G01X70008D02*
X70633Y920500D01*
G01X72900D02*
Y923000D01*
X72400Y922500D01*
G01Y920500D02*
X73400D01*
G01X76000D02*
Y923000D01*
X75500Y922500D01*
G01Y920500D02*
X76500D01*
G01X79100Y923000D02*
X78767Y922917D01*
X78517Y922708D01*
X78350Y922458D01*
X78225Y922125D01*
X78183Y921750D01*
X78225Y921375D01*
X78350Y921042D01*
X78517Y920792D01*
X78767Y920583D01*
X79100Y920500D01*
X79433Y920583D01*
X79683Y920792D01*
X79850Y921042D01*
X79975Y921375D01*
X80017Y921750D01*
X79975Y922125D01*
X79850Y922458D01*
X79683Y922708D01*
X79433Y922917D01*
X79100Y923000D01*
G01X82200Y920500D02*
X82492Y920542D01*
X82825Y920667D01*
X83033Y920875D01*
X83117Y921167D01*
X83033Y921458D01*
X82783Y921708D01*
X82408Y921833D01*
X81992D01*
X81742Y921917D01*
X81533Y922125D01*
X81450Y922417D01*
X81575Y922708D01*
X81867Y922917D01*
X82200Y923000D01*
X82533Y922917D01*
X82825Y922708D01*
X82950Y922417D01*
X82867Y922125D01*
X82658Y921917D01*
X82408Y921833D01*
X81992D01*
X81617Y921708D01*
X81367Y921458D01*
X81283Y921167D01*
X81367Y920875D01*
X81575Y920667D01*
X81908Y920542D01*
X82200Y920500D01*
G01X84195Y907367D02*
Y903367D01*
X91595D01*
G01X52967Y912000D02*
Y914500D01*
X54008D01*
X54342Y914375D01*
X54550Y914208D01*
X54633Y913875D01*
X54550Y913542D01*
X54300Y913333D01*
X54008Y913208D01*
X52967D01*
G01X54008D02*
X54633Y912000D01*
G01X56900D02*
Y914500D01*
X56400Y914000D01*
G01Y912000D02*
X57400D01*
G01X60000D02*
Y914500D01*
X59500Y914000D01*
G01Y912000D02*
X60500D01*
G01X63100D02*
Y914500D01*
X62600Y914000D01*
G01Y912000D02*
X63600D01*
G01X66200Y914500D02*
X65867Y914417D01*
X65617Y914208D01*
X65450Y913958D01*
X65325Y913625D01*
X65283Y913250D01*
X65325Y912875D01*
X65450Y912542D01*
X65617Y912292D01*
X65867Y912083D01*
X66200Y912000D01*
X66533Y912083D01*
X66783Y912292D01*
X66950Y912542D01*
X67075Y912875D01*
X67117Y913250D01*
X67075Y913625D01*
X66950Y913958D01*
X66783Y914208D01*
X66533Y914417D01*
X66200Y914500D01*
G01X76763Y907325D02*
Y911325D01*
X69363D01*
G01X51967Y890500D02*
Y893000D01*
X53008D01*
X53342Y892875D01*
X53550Y892708D01*
X53633Y892375D01*
X53550Y892042D01*
X53300Y891833D01*
X53008Y891708D01*
X51967D01*
G01X53008D02*
X53633Y890500D01*
G01X55900D02*
Y893000D01*
X55400Y892500D01*
G01Y890500D02*
X56400D01*
G01X59000D02*
Y893000D01*
X58500Y892500D01*
G01Y890500D02*
X59500D01*
G01X62100D02*
Y893000D01*
X61600Y892500D01*
G01Y890500D02*
X62600D01*
G01X64408Y892583D02*
X64658Y892833D01*
X64950Y892958D01*
X65283Y893000D01*
X65700Y892917D01*
X65992Y892708D01*
X66075Y892458D01*
X66033Y892208D01*
X65867Y892000D01*
X65033Y891583D01*
X64658Y891292D01*
X64408Y890875D01*
X64325Y890500D01*
X66075D01*
G01X75463Y890025D02*
Y894025D01*
X68063D01*
G01X67000Y895967D02*
X64500D01*
Y897008D01*
X64625Y897342D01*
X64792Y897550D01*
X65125Y897633D01*
X65458Y897550D01*
X65667Y897300D01*
X65792Y897008D01*
Y895967D01*
G01Y897008D02*
X67000Y897633D01*
G01Y899900D02*
X64500D01*
X65000Y899400D01*
G01X67000D02*
Y900400D01*
G01Y903000D02*
X64500D01*
X65000Y902500D01*
G01X67000D02*
Y903500D01*
G01Y906100D02*
X64500D01*
X65000Y905600D01*
G01X67000D02*
Y906600D01*
G01Y909700D02*
X64500D01*
X66292Y908158D01*
Y910242D01*
G01X79700Y899880D02*
X83700D01*
Y907280D01*
G01X63000Y895967D02*
X60500D01*
Y897008D01*
X60625Y897342D01*
X60792Y897550D01*
X61125Y897633D01*
X61458Y897550D01*
X61667Y897300D01*
X61792Y897008D01*
Y895967D01*
G01Y897008D02*
X63000Y897633D01*
G01Y899900D02*
X60500D01*
X61000Y899400D01*
G01X63000D02*
Y900400D01*
G01Y903000D02*
X60500D01*
X61000Y902500D01*
G01X63000D02*
Y903500D01*
G01Y906100D02*
X60500D01*
X61000Y905600D01*
G01X63000D02*
Y906600D01*
G01X62625Y908283D02*
X62833Y908533D01*
X62958Y908825D01*
X63000Y909200D01*
X62917Y909575D01*
X62750Y909867D01*
X62458Y910075D01*
X62125Y910117D01*
X61792Y910033D01*
X61583Y909825D01*
X61417Y909533D01*
X61375Y909242D01*
X61417Y908950D01*
X61583Y908575D01*
X60500Y908700D01*
Y909825D01*
G01X75563Y899825D02*
X79563D01*
Y907225D01*
G01X54517Y859500D02*
Y862000D01*
X55558D01*
X55892Y861875D01*
X56100Y861708D01*
X56183Y861375D01*
X56100Y861042D01*
X55850Y860833D01*
X55558Y860708D01*
X54517D01*
G01X55558D02*
X56183Y859500D01*
G01X58450D02*
Y862000D01*
X57950Y861500D01*
G01Y859500D02*
X58950D01*
G01X60633Y859875D02*
X60883Y859667D01*
X61175Y859542D01*
X61550Y859500D01*
X61925Y859583D01*
X62217Y859750D01*
X62425Y860042D01*
X62467Y860375D01*
X62383Y860708D01*
X62175Y860917D01*
X61883Y861083D01*
X61592Y861125D01*
X61300Y861083D01*
X60925Y860917D01*
X61050Y862000D01*
X62175D01*
G01X65150Y859500D02*
Y862000D01*
X63608Y860208D01*
X65692D01*
G01X86767Y921292D02*
X86517Y921417D01*
X86225Y921500D01*
X85892D01*
X85517Y921375D01*
X85225Y921167D01*
X85017Y920917D01*
X84850Y920500D01*
X84808Y920125D01*
X84892Y919750D01*
X85017Y919500D01*
X85267Y919250D01*
X85558Y919083D01*
X85850Y919000D01*
X86142D01*
X86433Y919083D01*
X86683Y919208D01*
X86892Y919375D01*
G01X88158Y920042D02*
X88450Y920333D01*
X88700Y920500D01*
X89033Y920583D01*
X89325Y920500D01*
X89533Y920333D01*
X89700Y920083D01*
X89742Y919792D01*
X89700Y919542D01*
X89533Y919292D01*
X89283Y919083D01*
X88992Y919000D01*
X88658Y919083D01*
X88367Y919333D01*
X88200Y919708D01*
X88158Y920125D01*
X88242Y920667D01*
X88367Y920958D01*
X88575Y921250D01*
X88867Y921458D01*
X89158Y921500D01*
X89450Y921417D01*
X89658Y921208D01*
G01X91258Y921083D02*
X91508Y921333D01*
X91800Y921458D01*
X92133Y921500D01*
X92550Y921417D01*
X92842Y921208D01*
X92925Y920958D01*
X92883Y920708D01*
X92717Y920500D01*
X91883Y920083D01*
X91508Y919792D01*
X91258Y919375D01*
X91175Y919000D01*
X92925D01*
G01X94233Y919500D02*
X94483Y919208D01*
X94817Y919042D01*
X95192Y919000D01*
X95525Y919042D01*
X95858Y919250D01*
X96067Y919500D01*
X96108Y919750D01*
X96025Y920042D01*
X95733Y920250D01*
X95442Y920333D01*
X95067D01*
G01X95442D02*
X95692Y920458D01*
X95900Y920667D01*
X95983Y920917D01*
X95900Y921167D01*
X95692Y921375D01*
X95317Y921500D01*
X94942Y921458D01*
X94567Y921292D01*
G01X101000Y874967D02*
X98500D01*
Y876008D01*
X98625Y876342D01*
X98792Y876550D01*
X99125Y876633D01*
X99458Y876550D01*
X99667Y876300D01*
X99792Y876008D01*
Y874967D01*
G01Y876008D02*
X101000Y876633D01*
G01Y878900D02*
X98500D01*
X99000Y878400D01*
G01X101000D02*
Y879400D01*
G01Y882000D02*
X98500D01*
X99000Y881500D01*
G01X101000D02*
Y882500D01*
G01X98500Y885100D02*
X98583Y884767D01*
X98792Y884517D01*
X99042Y884350D01*
X99375Y884225D01*
X99750Y884183D01*
X100125Y884225D01*
X100458Y884350D01*
X100708Y884517D01*
X100917Y884767D01*
X101000Y885100D01*
X100917Y885433D01*
X100708Y885683D01*
X100458Y885850D01*
X100125Y885975D01*
X99750Y886017D01*
X99375Y885975D01*
X99042Y885850D01*
X98792Y885683D01*
X98583Y885433D01*
X98500Y885100D01*
G01X101000Y888200D02*
X98500D01*
X99000Y887700D01*
G01X101000D02*
Y888700D01*
G01X52557Y883320D02*
X52307Y883445D01*
X52015Y883528D01*
X51682D01*
X51307Y883403D01*
X51015Y883195D01*
X50807Y882945D01*
X50640Y882528D01*
X50598Y882153D01*
X50682Y881778D01*
X50807Y881528D01*
X51057Y881278D01*
X51348Y881111D01*
X51640Y881028D01*
X51932D01*
X52223Y881111D01*
X52473Y881236D01*
X52682Y881403D01*
G01X53948Y882070D02*
X54240Y882361D01*
X54490Y882528D01*
X54823Y882611D01*
X55115Y882528D01*
X55323Y882361D01*
X55490Y882111D01*
X55532Y881820D01*
X55490Y881570D01*
X55323Y881320D01*
X55073Y881111D01*
X54782Y881028D01*
X54448Y881111D01*
X54157Y881361D01*
X53990Y881736D01*
X53948Y882153D01*
X54032Y882695D01*
X54157Y882986D01*
X54365Y883278D01*
X54657Y883486D01*
X54948Y883528D01*
X55240Y883445D01*
X55448Y883236D01*
G01X57048Y883111D02*
X57298Y883361D01*
X57590Y883486D01*
X57923Y883528D01*
X58340Y883445D01*
X58632Y883236D01*
X58715Y882986D01*
X58673Y882736D01*
X58507Y882528D01*
X57673Y882111D01*
X57298Y881820D01*
X57048Y881403D01*
X56965Y881028D01*
X58715D01*
G01X60940D02*
Y883528D01*
X60440Y883028D01*
G01Y881028D02*
X61440D01*
G01X52557Y875659D02*
X52307Y875784D01*
X52015Y875867D01*
X51682D01*
X51307Y875742D01*
X51015Y875534D01*
X50807Y875284D01*
X50640Y874867D01*
X50598Y874492D01*
X50682Y874117D01*
X50807Y873867D01*
X51057Y873617D01*
X51348Y873450D01*
X51640Y873367D01*
X51932D01*
X52223Y873450D01*
X52473Y873575D01*
X52682Y873742D01*
G01X53948Y874409D02*
X54240Y874700D01*
X54490Y874867D01*
X54823Y874950D01*
X55115Y874867D01*
X55323Y874700D01*
X55490Y874450D01*
X55532Y874159D01*
X55490Y873909D01*
X55323Y873659D01*
X55073Y873450D01*
X54782Y873367D01*
X54448Y873450D01*
X54157Y873700D01*
X53990Y874075D01*
X53948Y874492D01*
X54032Y875034D01*
X54157Y875325D01*
X54365Y875617D01*
X54657Y875825D01*
X54948Y875867D01*
X55240Y875784D01*
X55448Y875575D01*
G01X57048Y875450D02*
X57298Y875700D01*
X57590Y875825D01*
X57923Y875867D01*
X58340Y875784D01*
X58632Y875575D01*
X58715Y875325D01*
X58673Y875075D01*
X58507Y874867D01*
X57673Y874450D01*
X57298Y874159D01*
X57048Y873742D01*
X56965Y873367D01*
X58715D01*
G01X60148Y875450D02*
X60398Y875700D01*
X60690Y875825D01*
X61023Y875867D01*
X61440Y875784D01*
X61732Y875575D01*
X61815Y875325D01*
X61773Y875075D01*
X61607Y874867D01*
X60773Y874450D01*
X60398Y874159D01*
X60148Y873742D01*
X60065Y873367D01*
X61815D01*
G01X85417Y864000D02*
Y866500D01*
X86458D01*
X86792Y866375D01*
X87000Y866208D01*
X87083Y865875D01*
X87000Y865542D01*
X86750Y865333D01*
X86458Y865208D01*
X85417D01*
G01X86458D02*
X87083Y864000D01*
G01X89350D02*
Y866500D01*
X88850Y866000D01*
G01Y864000D02*
X89850D01*
G01X92450D02*
Y866500D01*
X91950Y866000D01*
G01Y864000D02*
X92950D01*
G01X95550Y866500D02*
X95217Y866417D01*
X94967Y866208D01*
X94800Y865958D01*
X94675Y865625D01*
X94633Y865250D01*
X94675Y864875D01*
X94800Y864542D01*
X94967Y864292D01*
X95217Y864083D01*
X95550Y864000D01*
X95883Y864083D01*
X96133Y864292D01*
X96300Y864542D01*
X96425Y864875D01*
X96467Y865250D01*
X96425Y865625D01*
X96300Y865958D01*
X96133Y866208D01*
X95883Y866417D01*
X95550Y866500D01*
G01X99150Y864000D02*
Y866500D01*
X97608Y864708D01*
X99692D01*
G01X97694Y868875D02*
X92494D01*
G01X97694Y875875D02*
X89894D01*
G01X97694Y868875D02*
Y875875D01*
G01X84294Y868875D02*
X92994D01*
G01X84294Y875875D02*
Y868875D01*
G01X90694Y875875D02*
X84294D01*
G01X43267Y1007953D02*
X43017Y1008078D01*
X42725Y1008161D01*
X42392D01*
X42017Y1008036D01*
X41725Y1007828D01*
X41517Y1007578D01*
X41350Y1007161D01*
X41308Y1006786D01*
X41392Y1006411D01*
X41517Y1006161D01*
X41767Y1005911D01*
X42058Y1005744D01*
X42350Y1005661D01*
X42642D01*
X42933Y1005744D01*
X43183Y1005869D01*
X43392Y1006036D01*
G01X44533D02*
X44783Y1005828D01*
X45075Y1005703D01*
X45450Y1005661D01*
X45825Y1005744D01*
X46117Y1005911D01*
X46325Y1006203D01*
X46367Y1006536D01*
X46283Y1006869D01*
X46075Y1007078D01*
X45783Y1007244D01*
X45492Y1007286D01*
X45200Y1007244D01*
X44825Y1007078D01*
X44950Y1008161D01*
X46075D01*
G01X48550D02*
X48217Y1008078D01*
X47967Y1007869D01*
X47800Y1007619D01*
X47675Y1007286D01*
X47633Y1006911D01*
X47675Y1006536D01*
X47800Y1006203D01*
X47967Y1005953D01*
X48217Y1005744D01*
X48550Y1005661D01*
X48883Y1005744D01*
X49133Y1005953D01*
X49300Y1006203D01*
X49425Y1006536D01*
X49467Y1006911D01*
X49425Y1007286D01*
X49300Y1007619D01*
X49133Y1007869D01*
X48883Y1008078D01*
X48550Y1008161D01*
G01X51567Y1005661D02*
X51650Y1006203D01*
X51775Y1006661D01*
X51942Y1007078D01*
X52150Y1007536D01*
X52483Y1008161D01*
X50817D01*
G01X48767Y998953D02*
X48517Y999078D01*
X48225Y999161D01*
X47892D01*
X47517Y999036D01*
X47225Y998828D01*
X47017Y998578D01*
X46850Y998161D01*
X46808Y997786D01*
X46892Y997411D01*
X47017Y997161D01*
X47267Y996911D01*
X47558Y996744D01*
X47850Y996661D01*
X48142D01*
X48433Y996744D01*
X48683Y996869D01*
X48892Y997036D01*
G01X50033D02*
X50283Y996828D01*
X50575Y996703D01*
X50950Y996661D01*
X51325Y996744D01*
X51617Y996911D01*
X51825Y997203D01*
X51867Y997536D01*
X51783Y997869D01*
X51575Y998078D01*
X51283Y998244D01*
X50992Y998286D01*
X50700Y998244D01*
X50325Y998078D01*
X50450Y999161D01*
X51575D01*
G01X54050D02*
X53717Y999078D01*
X53467Y998869D01*
X53300Y998619D01*
X53175Y998286D01*
X53133Y997911D01*
X53175Y997536D01*
X53300Y997203D01*
X53467Y996953D01*
X53717Y996744D01*
X54050Y996661D01*
X54383Y996744D01*
X54633Y996953D01*
X54800Y997203D01*
X54925Y997536D01*
X54967Y997911D01*
X54925Y998286D01*
X54800Y998619D01*
X54633Y998869D01*
X54383Y999078D01*
X54050Y999161D01*
G01X56358Y997703D02*
X56650Y997994D01*
X56900Y998161D01*
X57233Y998244D01*
X57525Y998161D01*
X57733Y997994D01*
X57900Y997744D01*
X57942Y997453D01*
X57900Y997203D01*
X57733Y996953D01*
X57483Y996744D01*
X57192Y996661D01*
X56858Y996744D01*
X56567Y996994D01*
X56400Y997369D01*
X56358Y997786D01*
X56442Y998328D01*
X56567Y998619D01*
X56775Y998911D01*
X57067Y999119D01*
X57358Y999161D01*
X57650Y999078D01*
X57858Y998869D01*
G01X39417Y967900D02*
Y970400D01*
X40458D01*
X40792Y970275D01*
X41000Y970108D01*
X41083Y969775D01*
X41000Y969442D01*
X40750Y969233D01*
X40458Y969108D01*
X39417D01*
G01X40458D02*
X41083Y967900D01*
G01X42642Y968192D02*
X42933Y967983D01*
X43267Y967900D01*
X43600Y967983D01*
X43892Y968233D01*
X44100Y968608D01*
X44183Y968983D01*
Y969442D01*
X44100Y969817D01*
X43892Y970150D01*
X43642Y970317D01*
X43350Y970400D01*
X43017Y970317D01*
X42767Y970150D01*
X42600Y969900D01*
X42517Y969567D01*
X42600Y969275D01*
X42808Y968983D01*
X43058Y968817D01*
X43350Y968775D01*
X43683Y968858D01*
X43933Y969067D01*
X44183Y969442D01*
G01X46450Y967900D02*
Y970400D01*
X45950Y969900D01*
G01Y967900D02*
X46950D01*
G01X48758Y969983D02*
X49008Y970233D01*
X49300Y970358D01*
X49633Y970400D01*
X50050Y970317D01*
X50342Y970108D01*
X50425Y969858D01*
X50383Y969608D01*
X50217Y969400D01*
X49383Y968983D01*
X49008Y968692D01*
X48758Y968275D01*
X48675Y967900D01*
X50425D01*
G01X54800Y973000D02*
Y969000D01*
X62200D01*
G01X41517Y1001661D02*
Y1004161D01*
X42558D01*
X42892Y1004036D01*
X43100Y1003869D01*
X43183Y1003536D01*
X43100Y1003203D01*
X42850Y1002994D01*
X42558Y1002869D01*
X41517D01*
G01X42558D02*
X43183Y1001661D01*
G01X44742Y1001953D02*
X45033Y1001744D01*
X45367Y1001661D01*
X45700Y1001744D01*
X45992Y1001994D01*
X46200Y1002369D01*
X46283Y1002744D01*
Y1003203D01*
X46200Y1003578D01*
X45992Y1003911D01*
X45742Y1004078D01*
X45450Y1004161D01*
X45117Y1004078D01*
X44867Y1003911D01*
X44700Y1003661D01*
X44617Y1003328D01*
X44700Y1003036D01*
X44908Y1002744D01*
X45158Y1002578D01*
X45450Y1002536D01*
X45783Y1002619D01*
X46033Y1002828D01*
X46283Y1003203D01*
G01X48550Y1001661D02*
Y1004161D01*
X48050Y1003661D01*
G01Y1001661D02*
X49050D01*
G01X50733Y1002161D02*
X50983Y1001869D01*
X51317Y1001703D01*
X51692Y1001661D01*
X52025Y1001703D01*
X52358Y1001911D01*
X52567Y1002161D01*
X52608Y1002411D01*
X52525Y1002703D01*
X52233Y1002911D01*
X51942Y1002994D01*
X51567D01*
G01X51942D02*
X52192Y1003119D01*
X52400Y1003328D01*
X52483Y1003578D01*
X52400Y1003828D01*
X52192Y1004036D01*
X51817Y1004161D01*
X51442Y1004119D01*
X51067Y1003953D01*
G01X62200Y1000000D02*
Y1004000D01*
X54800D01*
G01X55500Y975517D02*
X53000D01*
Y976558D01*
X53125Y976892D01*
X53292Y977100D01*
X53625Y977183D01*
X53958Y977100D01*
X54167Y976850D01*
X54292Y976558D01*
Y975517D01*
G01Y976558D02*
X55500Y977183D01*
G01X55208Y978742D02*
X55417Y979033D01*
X55500Y979367D01*
X55417Y979700D01*
X55167Y979992D01*
X54792Y980200D01*
X54417Y980283D01*
X53958D01*
X53583Y980200D01*
X53250Y979992D01*
X53083Y979742D01*
X53000Y979450D01*
X53083Y979117D01*
X53250Y978867D01*
X53500Y978700D01*
X53833Y978617D01*
X54125Y978700D01*
X54417Y978908D01*
X54583Y979158D01*
X54625Y979450D01*
X54542Y979783D01*
X54333Y980033D01*
X53958Y980283D01*
G01X55500Y982550D02*
X53000D01*
X53500Y982050D01*
G01X55500D02*
Y983050D01*
G01Y986150D02*
X53000D01*
X54792Y984608D01*
Y986692D01*
G01X58000Y973300D02*
X62000D01*
Y980700D01*
G01X74000Y954517D02*
X71500D01*
Y955558D01*
X71625Y955892D01*
X71792Y956100D01*
X72125Y956183D01*
X72458Y956100D01*
X72667Y955850D01*
X72792Y955558D01*
Y954517D01*
G01Y955558D02*
X74000Y956183D01*
G01X73708Y957742D02*
X73917Y958033D01*
X74000Y958367D01*
X73917Y958700D01*
X73667Y958992D01*
X73292Y959200D01*
X72917Y959283D01*
X72458D01*
X72083Y959200D01*
X71750Y958992D01*
X71583Y958742D01*
X71500Y958450D01*
X71583Y958117D01*
X71750Y957867D01*
X72000Y957700D01*
X72333Y957617D01*
X72625Y957700D01*
X72917Y957908D01*
X73083Y958158D01*
X73125Y958450D01*
X73042Y958783D01*
X72833Y959033D01*
X72458Y959283D01*
G01X74000Y961550D02*
X71500D01*
X72000Y961050D01*
G01X74000D02*
Y962050D01*
G01X73625Y963733D02*
X73833Y963983D01*
X73958Y964275D01*
X74000Y964650D01*
X73917Y965025D01*
X73750Y965317D01*
X73458Y965525D01*
X73125Y965567D01*
X72792Y965483D01*
X72583Y965275D01*
X72417Y964983D01*
X72375Y964692D01*
X72417Y964400D01*
X72583Y964025D01*
X71500Y964150D01*
Y965275D01*
G01X74500Y974700D02*
X70500D01*
Y967300D01*
G01X85617Y953100D02*
Y955600D01*
X86658D01*
X86992Y955475D01*
X87200Y955308D01*
X87283Y954975D01*
X87200Y954642D01*
X86950Y954433D01*
X86658Y954308D01*
X85617D01*
G01X86658D02*
X87283Y953100D01*
G01X88842Y953392D02*
X89133Y953183D01*
X89467Y953100D01*
X89800Y953183D01*
X90092Y953433D01*
X90300Y953808D01*
X90383Y954183D01*
Y954642D01*
X90300Y955017D01*
X90092Y955350D01*
X89842Y955517D01*
X89550Y955600D01*
X89217Y955517D01*
X88967Y955350D01*
X88800Y955100D01*
X88717Y954767D01*
X88800Y954475D01*
X89008Y954183D01*
X89258Y954017D01*
X89550Y953975D01*
X89883Y954058D01*
X90133Y954267D01*
X90383Y954642D01*
G01X92650Y955600D02*
X92317Y955517D01*
X92067Y955308D01*
X91900Y955058D01*
X91775Y954725D01*
X91733Y954350D01*
X91775Y953975D01*
X91900Y953642D01*
X92067Y953392D01*
X92317Y953183D01*
X92650Y953100D01*
X92983Y953183D01*
X93233Y953392D01*
X93400Y953642D01*
X93525Y953975D01*
X93567Y954350D01*
X93525Y954725D01*
X93400Y955058D01*
X93233Y955308D01*
X92983Y955517D01*
X92650Y955600D01*
G01X95750Y953100D02*
X96042Y953142D01*
X96375Y953267D01*
X96583Y953475D01*
X96667Y953767D01*
X96583Y954058D01*
X96333Y954308D01*
X95958Y954433D01*
X95542D01*
X95292Y954517D01*
X95083Y954725D01*
X95000Y955017D01*
X95125Y955308D01*
X95417Y955517D01*
X95750Y955600D01*
X96083Y955517D01*
X96375Y955308D01*
X96500Y955017D01*
X96417Y954725D01*
X96208Y954517D01*
X95958Y954433D01*
X95542D01*
X95167Y954308D01*
X94917Y954058D01*
X94833Y953767D01*
X94917Y953475D01*
X95125Y953267D01*
X95458Y953142D01*
X95750Y953100D01*
G01X94200Y966000D02*
Y970000D01*
X86800D01*
G01X85617Y957100D02*
Y959600D01*
X86658D01*
X86992Y959475D01*
X87200Y959308D01*
X87283Y958975D01*
X87200Y958642D01*
X86950Y958433D01*
X86658Y958308D01*
X85617D01*
G01X86658D02*
X87283Y957100D01*
G01X88842Y957392D02*
X89133Y957183D01*
X89467Y957100D01*
X89800Y957183D01*
X90092Y957433D01*
X90300Y957808D01*
X90383Y958183D01*
Y958642D01*
X90300Y959017D01*
X90092Y959350D01*
X89842Y959517D01*
X89550Y959600D01*
X89217Y959517D01*
X88967Y959350D01*
X88800Y959100D01*
X88717Y958767D01*
X88800Y958475D01*
X89008Y958183D01*
X89258Y958017D01*
X89550Y957975D01*
X89883Y958058D01*
X90133Y958267D01*
X90383Y958642D01*
G01X92650Y959600D02*
X92317Y959517D01*
X92067Y959308D01*
X91900Y959058D01*
X91775Y958725D01*
X91733Y958350D01*
X91775Y957975D01*
X91900Y957642D01*
X92067Y957392D01*
X92317Y957183D01*
X92650Y957100D01*
X92983Y957183D01*
X93233Y957392D01*
X93400Y957642D01*
X93525Y957975D01*
X93567Y958350D01*
X93525Y958725D01*
X93400Y959058D01*
X93233Y959308D01*
X92983Y959517D01*
X92650Y959600D01*
G01X94958Y958142D02*
X95250Y958433D01*
X95500Y958600D01*
X95833Y958683D01*
X96125Y958600D01*
X96333Y958433D01*
X96500Y958183D01*
X96542Y957892D01*
X96500Y957642D01*
X96333Y957392D01*
X96083Y957183D01*
X95792Y957100D01*
X95458Y957183D01*
X95167Y957433D01*
X95000Y957808D01*
X94958Y958225D01*
X95042Y958767D01*
X95167Y959058D01*
X95375Y959350D01*
X95667Y959558D01*
X95958Y959600D01*
X96250Y959517D01*
X96458Y959308D01*
G01X94200Y970500D02*
Y974500D01*
X86800D01*
G01X85517Y961000D02*
Y963500D01*
X86558D01*
X86892Y963375D01*
X87100Y963208D01*
X87183Y962875D01*
X87100Y962542D01*
X86850Y962333D01*
X86558Y962208D01*
X85517D01*
G01X86558D02*
X87183Y961000D01*
G01X88742Y961292D02*
X89033Y961083D01*
X89367Y961000D01*
X89700Y961083D01*
X89992Y961333D01*
X90200Y961708D01*
X90283Y962083D01*
Y962542D01*
X90200Y962917D01*
X89992Y963250D01*
X89742Y963417D01*
X89450Y963500D01*
X89117Y963417D01*
X88867Y963250D01*
X88700Y963000D01*
X88617Y962667D01*
X88700Y962375D01*
X88908Y962083D01*
X89158Y961917D01*
X89450Y961875D01*
X89783Y961958D01*
X90033Y962167D01*
X90283Y962542D01*
G01X92550Y961000D02*
Y963500D01*
X92050Y963000D01*
G01Y961000D02*
X93050D01*
G01X95650Y963500D02*
X95317Y963417D01*
X95067Y963208D01*
X94900Y962958D01*
X94775Y962625D01*
X94733Y962250D01*
X94775Y961875D01*
X94900Y961542D01*
X95067Y961292D01*
X95317Y961083D01*
X95650Y961000D01*
X95983Y961083D01*
X96233Y961292D01*
X96400Y961542D01*
X96525Y961875D01*
X96567Y962250D01*
X96525Y962625D01*
X96400Y962958D01*
X96233Y963208D01*
X95983Y963417D01*
X95650Y963500D01*
G01X86800Y984500D02*
Y980500D01*
X94200D01*
G01X47017Y992661D02*
Y995161D01*
X48058D01*
X48392Y995036D01*
X48600Y994869D01*
X48683Y994536D01*
X48600Y994203D01*
X48350Y993994D01*
X48058Y993869D01*
X47017D01*
G01X48058D02*
X48683Y992661D01*
G01X50242Y992953D02*
X50533Y992744D01*
X50867Y992661D01*
X51200Y992744D01*
X51492Y992994D01*
X51700Y993369D01*
X51783Y993744D01*
Y994203D01*
X51700Y994578D01*
X51492Y994911D01*
X51242Y995078D01*
X50950Y995161D01*
X50617Y995078D01*
X50367Y994911D01*
X50200Y994661D01*
X50117Y994328D01*
X50200Y994036D01*
X50408Y993744D01*
X50658Y993578D01*
X50950Y993536D01*
X51283Y993619D01*
X51533Y993828D01*
X51783Y994203D01*
G01X54050Y995161D02*
X53717Y995078D01*
X53467Y994869D01*
X53300Y994619D01*
X53175Y994286D01*
X53133Y993911D01*
X53175Y993536D01*
X53300Y993203D01*
X53467Y992953D01*
X53717Y992744D01*
X54050Y992661D01*
X54383Y992744D01*
X54633Y992953D01*
X54800Y993203D01*
X54925Y993536D01*
X54967Y993911D01*
X54925Y994286D01*
X54800Y994619D01*
X54633Y994869D01*
X54383Y995078D01*
X54050Y995161D01*
G01X56233Y993036D02*
X56483Y992828D01*
X56775Y992703D01*
X57150Y992661D01*
X57525Y992744D01*
X57817Y992911D01*
X58025Y993203D01*
X58067Y993536D01*
X57983Y993869D01*
X57775Y994078D01*
X57483Y994244D01*
X57192Y994286D01*
X56900Y994244D01*
X56525Y994078D01*
X56650Y995161D01*
X57775D01*
G01X62300Y998500D02*
Y994500D01*
X69700D01*
G01X77350Y1024000D02*
X77017Y1024042D01*
X76725Y1024208D01*
X76475Y1024458D01*
X76308Y1024750D01*
X76225Y1025083D01*
Y1025417D01*
X76308Y1025750D01*
X76475Y1026042D01*
X76725Y1026292D01*
X77017Y1026458D01*
X77350Y1026500D01*
X77683Y1026458D01*
X77975Y1026292D01*
X78225Y1026042D01*
X78392Y1025750D01*
X78475Y1025417D01*
Y1025083D01*
X78392Y1024750D01*
X78225Y1024458D01*
X77975Y1024208D01*
X77683Y1024042D01*
X77350Y1024000D01*
G01X77683Y1024667D02*
X78183Y1024000D01*
G01X80450D02*
Y1026500D01*
X79950Y1026000D01*
G01Y1024000D02*
X80950D01*
G01X83550D02*
X83842Y1024042D01*
X84175Y1024167D01*
X84383Y1024375D01*
X84467Y1024667D01*
X84383Y1024958D01*
X84133Y1025208D01*
X83758Y1025333D01*
X83342D01*
X83092Y1025417D01*
X82883Y1025625D01*
X82800Y1025917D01*
X82925Y1026208D01*
X83217Y1026417D01*
X83550Y1026500D01*
X83883Y1026417D01*
X84175Y1026208D01*
X84300Y1025917D01*
X84217Y1025625D01*
X84008Y1025417D01*
X83758Y1025333D01*
X83342D01*
X82967Y1025208D01*
X82717Y1024958D01*
X82633Y1024667D01*
X82717Y1024375D01*
X82925Y1024167D01*
X83258Y1024042D01*
X83550Y1024000D01*
G01X85942Y1024292D02*
X86233Y1024083D01*
X86567Y1024000D01*
X86900Y1024083D01*
X87192Y1024333D01*
X87400Y1024708D01*
X87483Y1025083D01*
Y1025542D01*
X87400Y1025917D01*
X87192Y1026250D01*
X86942Y1026417D01*
X86650Y1026500D01*
X86317Y1026417D01*
X86067Y1026250D01*
X85900Y1026000D01*
X85817Y1025667D01*
X85900Y1025375D01*
X86108Y1025083D01*
X86358Y1024917D01*
X86650Y1024875D01*
X86983Y1024958D01*
X87233Y1025167D01*
X87483Y1025542D01*
G01X92200Y1007000D02*
X90100Y1008800D01*
X92200Y1011000D01*
G01X92300Y1014600D02*
X73100D01*
Y1003400D01*
X92300D01*
Y1014600D01*
X91900D01*
G01X34950Y1026000D02*
X34617Y1026042D01*
X34325Y1026208D01*
X34075Y1026458D01*
X33908Y1026750D01*
X33825Y1027083D01*
Y1027417D01*
X33908Y1027750D01*
X34075Y1028042D01*
X34325Y1028292D01*
X34617Y1028458D01*
X34950Y1028500D01*
X35283Y1028458D01*
X35575Y1028292D01*
X35825Y1028042D01*
X35992Y1027750D01*
X36075Y1027417D01*
Y1027083D01*
X35992Y1026750D01*
X35825Y1026458D01*
X35575Y1026208D01*
X35283Y1026042D01*
X34950Y1026000D01*
G01X35283Y1026667D02*
X35783Y1026000D01*
G01X38050D02*
Y1028500D01*
X37550Y1028000D01*
G01Y1026000D02*
X38550D01*
G01X40442Y1026292D02*
X40733Y1026083D01*
X41067Y1026000D01*
X41400Y1026083D01*
X41692Y1026333D01*
X41900Y1026708D01*
X41983Y1027083D01*
Y1027542D01*
X41900Y1027917D01*
X41692Y1028250D01*
X41442Y1028417D01*
X41150Y1028500D01*
X40817Y1028417D01*
X40567Y1028250D01*
X40400Y1028000D01*
X40317Y1027667D01*
X40400Y1027375D01*
X40608Y1027083D01*
X40858Y1026917D01*
X41150Y1026875D01*
X41483Y1026958D01*
X41733Y1027167D01*
X41983Y1027542D01*
G01X43458Y1028083D02*
X43708Y1028333D01*
X44000Y1028458D01*
X44333Y1028500D01*
X44750Y1028417D01*
X45042Y1028208D01*
X45125Y1027958D01*
X45083Y1027708D01*
X44917Y1027500D01*
X44083Y1027083D01*
X43708Y1026792D01*
X43458Y1026375D01*
X43375Y1026000D01*
X45125D01*
G01X47800Y1029000D02*
X49900Y1027200D01*
X47800Y1025000D01*
G01X47700Y1021400D02*
X66900D01*
Y1032600D01*
X47700D01*
Y1021400D01*
X48100D01*
G01X87800Y1027500D02*
X82300D01*
G01X87800Y1035500D02*
Y1027500D01*
G01X82300Y1035500D02*
X87800D01*
G01X70200D02*
X75700D01*
G01X70200Y1027500D02*
Y1035500D01*
G01X75700Y1027500D02*
X70200D01*
G01X69100Y957183D02*
X66600D01*
Y958017D01*
X66725Y958350D01*
X66892Y958600D01*
X67142Y958808D01*
X67433Y958975D01*
X67850Y959017D01*
X68267Y958975D01*
X68558Y958808D01*
X68808Y958600D01*
X68975Y958350D01*
X69100Y958017D01*
Y957183D01*
G01X68600Y960283D02*
X68892Y960533D01*
X69058Y960867D01*
X69100Y961242D01*
X69058Y961575D01*
X68850Y961908D01*
X68600Y962117D01*
X68350Y962158D01*
X68058Y962075D01*
X67850Y961783D01*
X67767Y961492D01*
Y961117D01*
G01Y961492D02*
X67642Y961742D01*
X67433Y961950D01*
X67183Y962033D01*
X66933Y961950D01*
X66725Y961742D01*
X66600Y961367D01*
X66642Y960992D01*
X66808Y960617D01*
G01X68058Y963508D02*
X67767Y963800D01*
X67600Y964050D01*
X67517Y964383D01*
X67600Y964675D01*
X67767Y964883D01*
X68017Y965050D01*
X68308Y965092D01*
X68558Y965050D01*
X68808Y964883D01*
X69017Y964633D01*
X69100Y964342D01*
X69017Y964008D01*
X68767Y963717D01*
X68392Y963550D01*
X67975Y963508D01*
X67433Y963592D01*
X67142Y963717D01*
X66850Y963925D01*
X66642Y964217D01*
X66600Y964508D01*
X66683Y964800D01*
X66892Y965008D01*
G01X70000Y983500D02*
Y967400D01*
G01X63000Y983500D02*
X70000D01*
G01X63000Y967400D02*
Y983500D01*
G01X70000Y967400D02*
X63000D01*
G01X74000Y980850D02*
X73958Y980517D01*
X73792Y980225D01*
X73542Y979975D01*
X73250Y979808D01*
X72917Y979725D01*
X72583D01*
X72250Y979808D01*
X71958Y979975D01*
X71708Y980225D01*
X71542Y980517D01*
X71500Y980850D01*
X71542Y981183D01*
X71708Y981475D01*
X71958Y981725D01*
X72250Y981892D01*
X72583Y981975D01*
X72917D01*
X73250Y981892D01*
X73542Y981725D01*
X73792Y981475D01*
X73958Y981183D01*
X74000Y980850D01*
G01X73333Y981183D02*
X74000Y981683D01*
G01Y983950D02*
X71500D01*
X72000Y983450D01*
G01X74000D02*
Y984450D01*
G01X73708Y986342D02*
X73917Y986633D01*
X74000Y986967D01*
X73917Y987300D01*
X73667Y987592D01*
X73292Y987800D01*
X72917Y987883D01*
X72458D01*
X72083Y987800D01*
X71750Y987592D01*
X71583Y987342D01*
X71500Y987050D01*
X71583Y986717D01*
X71750Y986467D01*
X72000Y986300D01*
X72333Y986217D01*
X72625Y986300D01*
X72917Y986508D01*
X73083Y986758D01*
X73125Y987050D01*
X73042Y987383D01*
X72833Y987633D01*
X72458Y987883D01*
G01X74000Y990150D02*
X71500D01*
X72000Y989650D01*
G01X74000D02*
Y990650D01*
G01X86200Y989200D02*
X74800D01*
G01X86200Y975800D02*
Y989200D01*
G01X74800Y975800D02*
X86200D01*
G01X74800Y989200D02*
Y975800D01*
G01X95000Y1046517D02*
X92500D01*
Y1047558D01*
X92625Y1047892D01*
X92792Y1048100D01*
X93125Y1048183D01*
X93458Y1048100D01*
X93667Y1047850D01*
X93792Y1047558D01*
Y1046517D01*
G01Y1047558D02*
X95000Y1048183D01*
G01Y1050450D02*
X94958Y1050742D01*
X94833Y1051075D01*
X94625Y1051283D01*
X94333Y1051367D01*
X94042Y1051283D01*
X93792Y1051033D01*
X93667Y1050658D01*
Y1050242D01*
X93583Y1049992D01*
X93375Y1049783D01*
X93083Y1049700D01*
X92792Y1049825D01*
X92583Y1050117D01*
X92500Y1050450D01*
X92583Y1050783D01*
X92792Y1051075D01*
X93083Y1051200D01*
X93375Y1051117D01*
X93583Y1050908D01*
X93667Y1050658D01*
Y1050242D01*
X93792Y1049867D01*
X94042Y1049617D01*
X94333Y1049533D01*
X94625Y1049617D01*
X94833Y1049825D01*
X94958Y1050158D01*
X95000Y1050450D01*
G01X94708Y1052842D02*
X94917Y1053133D01*
X95000Y1053467D01*
X94917Y1053800D01*
X94667Y1054092D01*
X94292Y1054300D01*
X93917Y1054383D01*
X93458D01*
X93083Y1054300D01*
X92750Y1054092D01*
X92583Y1053842D01*
X92500Y1053550D01*
X92583Y1053217D01*
X92750Y1052967D01*
X93000Y1052800D01*
X93333Y1052717D01*
X93625Y1052800D01*
X93917Y1053008D01*
X94083Y1053258D01*
X94125Y1053550D01*
X94042Y1053883D01*
X93833Y1054133D01*
X93458Y1054383D01*
G01X95000Y1056567D02*
X94458Y1056650D01*
X94000Y1056775D01*
X93583Y1056942D01*
X93125Y1057150D01*
X92500Y1057483D01*
Y1055817D01*
G01X89500Y1045300D02*
X97500D01*
Y1027700D01*
X89500D01*
Y1045300D01*
G01X65700Y1042000D02*
Y1050000D01*
X83300D01*
Y1042000D01*
X65700D01*
G01X72567Y1062192D02*
X72317Y1062317D01*
X72025Y1062400D01*
X71692D01*
X71317Y1062275D01*
X71025Y1062067D01*
X70817Y1061817D01*
X70650Y1061400D01*
X70608Y1061025D01*
X70692Y1060650D01*
X70817Y1060400D01*
X71067Y1060150D01*
X71358Y1059983D01*
X71650Y1059900D01*
X71942D01*
X72233Y1059983D01*
X72483Y1060108D01*
X72692Y1060275D01*
G01X75250Y1059900D02*
Y1062400D01*
X73708Y1060608D01*
X75792D01*
G01X77142Y1060192D02*
X77433Y1059983D01*
X77767Y1059900D01*
X78100Y1059983D01*
X78392Y1060233D01*
X78600Y1060608D01*
X78683Y1060983D01*
Y1061442D01*
X78600Y1061817D01*
X78392Y1062150D01*
X78142Y1062317D01*
X77850Y1062400D01*
X77517Y1062317D01*
X77267Y1062150D01*
X77100Y1061900D01*
X77017Y1061567D01*
X77100Y1061275D01*
X77308Y1060983D01*
X77558Y1060817D01*
X77850Y1060775D01*
X78183Y1060858D01*
X78433Y1061067D01*
X78683Y1061442D01*
G01X80950Y1059900D02*
X81242Y1059942D01*
X81575Y1060067D01*
X81783Y1060275D01*
X81867Y1060567D01*
X81783Y1060858D01*
X81533Y1061108D01*
X81158Y1061233D01*
X80742D01*
X80492Y1061317D01*
X80283Y1061525D01*
X80200Y1061817D01*
X80325Y1062108D01*
X80617Y1062317D01*
X80950Y1062400D01*
X81283Y1062317D01*
X81575Y1062108D01*
X81700Y1061817D01*
X81617Y1061525D01*
X81408Y1061317D01*
X81158Y1061233D01*
X80742D01*
X80367Y1061108D01*
X80117Y1060858D01*
X80033Y1060567D01*
X80117Y1060275D01*
X80325Y1060067D01*
X80658Y1059942D01*
X80950Y1059900D01*
G01X90208Y1085767D02*
X90083Y1085517D01*
X90000Y1085225D01*
Y1084892D01*
X90125Y1084517D01*
X90333Y1084225D01*
X90583Y1084017D01*
X91000Y1083850D01*
X91375Y1083808D01*
X91750Y1083892D01*
X92000Y1084017D01*
X92250Y1084267D01*
X92417Y1084558D01*
X92500Y1084850D01*
Y1085142D01*
X92417Y1085433D01*
X92292Y1085683D01*
X92125Y1085892D01*
G01Y1087033D02*
X92333Y1087283D01*
X92458Y1087575D01*
X92500Y1087950D01*
X92417Y1088325D01*
X92250Y1088617D01*
X91958Y1088825D01*
X91625Y1088867D01*
X91292Y1088783D01*
X91083Y1088575D01*
X90917Y1088283D01*
X90875Y1087992D01*
X90917Y1087700D01*
X91083Y1087325D01*
X90000Y1087450D01*
Y1088575D01*
G01Y1091050D02*
X90083Y1090717D01*
X90292Y1090467D01*
X90542Y1090300D01*
X90875Y1090175D01*
X91250Y1090133D01*
X91625Y1090175D01*
X91958Y1090300D01*
X92208Y1090467D01*
X92417Y1090717D01*
X92500Y1091050D01*
X92417Y1091383D01*
X92208Y1091633D01*
X91958Y1091800D01*
X91625Y1091925D01*
X91250Y1091967D01*
X90875Y1091925D01*
X90542Y1091800D01*
X90292Y1091633D01*
X90083Y1091383D01*
X90000Y1091050D01*
G01X92500Y1094650D02*
X90000D01*
X91792Y1093108D01*
Y1095192D01*
G01X72767Y1057953D02*
X72517Y1058078D01*
X72225Y1058161D01*
X71892D01*
X71517Y1058036D01*
X71225Y1057828D01*
X71017Y1057578D01*
X70850Y1057161D01*
X70808Y1056786D01*
X70892Y1056411D01*
X71017Y1056161D01*
X71267Y1055911D01*
X71558Y1055744D01*
X71850Y1055661D01*
X72142D01*
X72433Y1055744D01*
X72683Y1055869D01*
X72892Y1056036D01*
G01X75450Y1055661D02*
Y1058161D01*
X73908Y1056369D01*
X75992D01*
G01X77342Y1055953D02*
X77633Y1055744D01*
X77967Y1055661D01*
X78300Y1055744D01*
X78592Y1055994D01*
X78800Y1056369D01*
X78883Y1056744D01*
Y1057203D01*
X78800Y1057578D01*
X78592Y1057911D01*
X78342Y1058078D01*
X78050Y1058161D01*
X77717Y1058078D01*
X77467Y1057911D01*
X77300Y1057661D01*
X77217Y1057328D01*
X77300Y1057036D01*
X77508Y1056744D01*
X77758Y1056578D01*
X78050Y1056536D01*
X78383Y1056619D01*
X78633Y1056828D01*
X78883Y1057203D01*
G01X80442Y1055953D02*
X80733Y1055744D01*
X81067Y1055661D01*
X81400Y1055744D01*
X81692Y1055994D01*
X81900Y1056369D01*
X81983Y1056744D01*
Y1057203D01*
X81900Y1057578D01*
X81692Y1057911D01*
X81442Y1058078D01*
X81150Y1058161D01*
X80817Y1058078D01*
X80567Y1057911D01*
X80400Y1057661D01*
X80317Y1057328D01*
X80400Y1057036D01*
X80608Y1056744D01*
X80858Y1056578D01*
X81150Y1056536D01*
X81483Y1056619D01*
X81733Y1056828D01*
X81983Y1057203D01*
G01X71017Y1064000D02*
Y1066500D01*
X72058D01*
X72392Y1066375D01*
X72600Y1066208D01*
X72683Y1065875D01*
X72600Y1065542D01*
X72350Y1065333D01*
X72058Y1065208D01*
X71017D01*
G01X72058D02*
X72683Y1064000D01*
G01X74950D02*
X75242Y1064042D01*
X75575Y1064167D01*
X75783Y1064375D01*
X75867Y1064667D01*
X75783Y1064958D01*
X75533Y1065208D01*
X75158Y1065333D01*
X74742D01*
X74492Y1065417D01*
X74283Y1065625D01*
X74200Y1065917D01*
X74325Y1066208D01*
X74617Y1066417D01*
X74950Y1066500D01*
X75283Y1066417D01*
X75575Y1066208D01*
X75700Y1065917D01*
X75617Y1065625D01*
X75408Y1065417D01*
X75158Y1065333D01*
X74742D01*
X74367Y1065208D01*
X74117Y1064958D01*
X74033Y1064667D01*
X74117Y1064375D01*
X74325Y1064167D01*
X74658Y1064042D01*
X74950Y1064000D01*
G01X77342Y1064292D02*
X77633Y1064083D01*
X77967Y1064000D01*
X78300Y1064083D01*
X78592Y1064333D01*
X78800Y1064708D01*
X78883Y1065083D01*
Y1065542D01*
X78800Y1065917D01*
X78592Y1066250D01*
X78342Y1066417D01*
X78050Y1066500D01*
X77717Y1066417D01*
X77467Y1066250D01*
X77300Y1066000D01*
X77217Y1065667D01*
X77300Y1065375D01*
X77508Y1065083D01*
X77758Y1064917D01*
X78050Y1064875D01*
X78383Y1064958D01*
X78633Y1065167D01*
X78883Y1065542D01*
G01X80442Y1064292D02*
X80733Y1064083D01*
X81067Y1064000D01*
X81400Y1064083D01*
X81692Y1064333D01*
X81900Y1064708D01*
X81983Y1065083D01*
Y1065542D01*
X81900Y1065917D01*
X81692Y1066250D01*
X81442Y1066417D01*
X81150Y1066500D01*
X80817Y1066417D01*
X80567Y1066250D01*
X80400Y1066000D01*
X80317Y1065667D01*
X80400Y1065375D01*
X80608Y1065083D01*
X80858Y1064917D01*
X81150Y1064875D01*
X81483Y1064958D01*
X81733Y1065167D01*
X81983Y1065542D01*
G01X55267Y1055292D02*
X55017Y1055417D01*
X54725Y1055500D01*
X54392D01*
X54017Y1055375D01*
X53725Y1055167D01*
X53517Y1054917D01*
X53350Y1054500D01*
X53308Y1054125D01*
X53392Y1053750D01*
X53517Y1053500D01*
X53767Y1053250D01*
X54058Y1053083D01*
X54350Y1053000D01*
X54642D01*
X54933Y1053083D01*
X55183Y1053208D01*
X55392Y1053375D01*
G01X56533D02*
X56783Y1053167D01*
X57075Y1053042D01*
X57450Y1053000D01*
X57825Y1053083D01*
X58117Y1053250D01*
X58325Y1053542D01*
X58367Y1053875D01*
X58283Y1054208D01*
X58075Y1054417D01*
X57783Y1054583D01*
X57492Y1054625D01*
X57200Y1054583D01*
X56825Y1054417D01*
X56950Y1055500D01*
X58075D01*
G01X60550D02*
X60217Y1055417D01*
X59967Y1055208D01*
X59800Y1054958D01*
X59675Y1054625D01*
X59633Y1054250D01*
X59675Y1053875D01*
X59800Y1053542D01*
X59967Y1053292D01*
X60217Y1053083D01*
X60550Y1053000D01*
X60883Y1053083D01*
X61133Y1053292D01*
X61300Y1053542D01*
X61425Y1053875D01*
X61467Y1054250D01*
X61425Y1054625D01*
X61300Y1054958D01*
X61133Y1055208D01*
X60883Y1055417D01*
X60550Y1055500D01*
G01X62858Y1055083D02*
X63108Y1055333D01*
X63400Y1055458D01*
X63733Y1055500D01*
X64150Y1055417D01*
X64442Y1055208D01*
X64525Y1054958D01*
X64483Y1054708D01*
X64317Y1054500D01*
X63483Y1054083D01*
X63108Y1053792D01*
X62858Y1053375D01*
X62775Y1053000D01*
X64525D01*
G01X86708Y1072767D02*
X86583Y1072517D01*
X86500Y1072225D01*
Y1071892D01*
X86625Y1071517D01*
X86833Y1071225D01*
X87083Y1071017D01*
X87500Y1070850D01*
X87875Y1070808D01*
X88250Y1070892D01*
X88500Y1071017D01*
X88750Y1071267D01*
X88917Y1071558D01*
X89000Y1071850D01*
Y1072142D01*
X88917Y1072433D01*
X88792Y1072683D01*
X88625Y1072892D01*
G01Y1074033D02*
X88833Y1074283D01*
X88958Y1074575D01*
X89000Y1074950D01*
X88917Y1075325D01*
X88750Y1075617D01*
X88458Y1075825D01*
X88125Y1075867D01*
X87792Y1075783D01*
X87583Y1075575D01*
X87417Y1075283D01*
X87375Y1074992D01*
X87417Y1074700D01*
X87583Y1074325D01*
X86500Y1074450D01*
Y1075575D01*
G01Y1078050D02*
X86583Y1077717D01*
X86792Y1077467D01*
X87042Y1077300D01*
X87375Y1077175D01*
X87750Y1077133D01*
X88125Y1077175D01*
X88458Y1077300D01*
X88708Y1077467D01*
X88917Y1077717D01*
X89000Y1078050D01*
X88917Y1078383D01*
X88708Y1078633D01*
X88458Y1078800D01*
X88125Y1078925D01*
X87750Y1078967D01*
X87375Y1078925D01*
X87042Y1078800D01*
X86792Y1078633D01*
X86583Y1078383D01*
X86500Y1078050D01*
G01X88500Y1080233D02*
X88792Y1080483D01*
X88958Y1080817D01*
X89000Y1081192D01*
X88958Y1081525D01*
X88750Y1081858D01*
X88500Y1082067D01*
X88250Y1082108D01*
X87958Y1082025D01*
X87750Y1081733D01*
X87667Y1081442D01*
Y1081067D01*
G01Y1081442D02*
X87542Y1081692D01*
X87333Y1081900D01*
X87083Y1081983D01*
X86833Y1081900D01*
X86625Y1081692D01*
X86500Y1081317D01*
X86542Y1080942D01*
X86708Y1080567D01*
G01X99382Y1450567D02*
X99257Y1450317D01*
X99174Y1450025D01*
Y1449692D01*
X99299Y1449317D01*
X99507Y1449025D01*
X99757Y1448817D01*
X100174Y1448650D01*
X100549Y1448608D01*
X100924Y1448692D01*
X101174Y1448817D01*
X101424Y1449067D01*
X101591Y1449358D01*
X101674Y1449650D01*
Y1449942D01*
X101591Y1450233D01*
X101466Y1450483D01*
X101299Y1450692D01*
G01Y1451833D02*
X101507Y1452083D01*
X101632Y1452375D01*
X101674Y1452750D01*
X101591Y1453125D01*
X101424Y1453417D01*
X101132Y1453625D01*
X100799Y1453667D01*
X100466Y1453583D01*
X100257Y1453375D01*
X100091Y1453083D01*
X100049Y1452792D01*
X100091Y1452500D01*
X100257Y1452125D01*
X99174Y1452250D01*
Y1453375D01*
G01X101674Y1455850D02*
X99174D01*
X99674Y1455350D01*
G01X101674D02*
Y1456350D01*
G01X101382Y1458242D02*
X101591Y1458533D01*
X101674Y1458867D01*
X101591Y1459200D01*
X101341Y1459492D01*
X100966Y1459700D01*
X100591Y1459783D01*
X100132D01*
X99757Y1459700D01*
X99424Y1459492D01*
X99257Y1459242D01*
X99174Y1458950D01*
X99257Y1458617D01*
X99424Y1458367D01*
X99674Y1458200D01*
X100007Y1458117D01*
X100299Y1458200D01*
X100591Y1458408D01*
X100757Y1458658D01*
X100799Y1458950D01*
X100716Y1459283D01*
X100507Y1459533D01*
X100132Y1459783D01*
G01X71982Y1454567D02*
X71857Y1454317D01*
X71774Y1454025D01*
Y1453692D01*
X71899Y1453317D01*
X72107Y1453025D01*
X72357Y1452817D01*
X72774Y1452650D01*
X73149Y1452608D01*
X73524Y1452692D01*
X73774Y1452817D01*
X74024Y1453067D01*
X74191Y1453358D01*
X74274Y1453650D01*
Y1453942D01*
X74191Y1454233D01*
X74066Y1454483D01*
X73899Y1454692D01*
G01X74274Y1456667D02*
X73732Y1456750D01*
X73274Y1456875D01*
X72857Y1457042D01*
X72399Y1457250D01*
X71774Y1457583D01*
Y1455917D01*
G01X74274Y1459850D02*
X71774D01*
X72274Y1459350D01*
G01X74274D02*
Y1460350D01*
G01X71774Y1462950D02*
X71857Y1462617D01*
X72066Y1462367D01*
X72316Y1462200D01*
X72649Y1462075D01*
X73024Y1462033D01*
X73399Y1462075D01*
X73732Y1462200D01*
X73982Y1462367D01*
X74191Y1462617D01*
X74274Y1462950D01*
X74191Y1463283D01*
X73982Y1463533D01*
X73732Y1463700D01*
X73399Y1463825D01*
X73024Y1463867D01*
X72649Y1463825D01*
X72316Y1463700D01*
X72066Y1463533D01*
X71857Y1463283D01*
X71774Y1462950D01*
G01X97474Y1448617D02*
X94974D01*
Y1449658D01*
X95099Y1449992D01*
X95266Y1450200D01*
X95599Y1450283D01*
X95932Y1450200D01*
X96141Y1449950D01*
X96266Y1449658D01*
Y1448617D01*
G01Y1449658D02*
X97474Y1450283D01*
G01X97182Y1451842D02*
X97391Y1452133D01*
X97474Y1452467D01*
X97391Y1452800D01*
X97141Y1453092D01*
X96766Y1453300D01*
X96391Y1453383D01*
X95932D01*
X95557Y1453300D01*
X95224Y1453092D01*
X95057Y1452842D01*
X94974Y1452550D01*
X95057Y1452217D01*
X95224Y1451967D01*
X95474Y1451800D01*
X95807Y1451717D01*
X96099Y1451800D01*
X96391Y1452008D01*
X96557Y1452258D01*
X96599Y1452550D01*
X96516Y1452883D01*
X96307Y1453133D01*
X95932Y1453383D01*
G01X95391Y1454858D02*
X95141Y1455108D01*
X95016Y1455400D01*
X94974Y1455733D01*
X95057Y1456150D01*
X95266Y1456442D01*
X95516Y1456525D01*
X95766Y1456483D01*
X95974Y1456317D01*
X96391Y1455483D01*
X96682Y1455108D01*
X97099Y1454858D01*
X97474Y1454775D01*
Y1456525D01*
G01X95391Y1457958D02*
X95141Y1458208D01*
X95016Y1458500D01*
X94974Y1458833D01*
X95057Y1459250D01*
X95266Y1459542D01*
X95516Y1459625D01*
X95766Y1459583D01*
X95974Y1459417D01*
X96391Y1458583D01*
X96682Y1458208D01*
X97099Y1457958D01*
X97474Y1457875D01*
Y1459625D01*
G01X81891Y1451000D02*
Y1453500D01*
X82932D01*
X83266Y1453375D01*
X83474Y1453208D01*
X83557Y1452875D01*
X83474Y1452542D01*
X83224Y1452333D01*
X82932Y1452208D01*
X81891D01*
G01X82932D02*
X83557Y1451000D01*
G01X85116Y1451292D02*
X85407Y1451083D01*
X85741Y1451000D01*
X86074Y1451083D01*
X86366Y1451333D01*
X86574Y1451708D01*
X86657Y1452083D01*
Y1452542D01*
X86574Y1452917D01*
X86366Y1453250D01*
X86116Y1453417D01*
X85824Y1453500D01*
X85491Y1453417D01*
X85241Y1453250D01*
X85074Y1453000D01*
X84991Y1452667D01*
X85074Y1452375D01*
X85282Y1452083D01*
X85532Y1451917D01*
X85824Y1451875D01*
X86157Y1451958D01*
X86407Y1452167D01*
X86657Y1452542D01*
G01X88132Y1453083D02*
X88382Y1453333D01*
X88674Y1453458D01*
X89007Y1453500D01*
X89424Y1453417D01*
X89716Y1453208D01*
X89799Y1452958D01*
X89757Y1452708D01*
X89591Y1452500D01*
X88757Y1452083D01*
X88382Y1451792D01*
X88132Y1451375D01*
X88049Y1451000D01*
X89799D01*
G01X91232Y1452042D02*
X91524Y1452333D01*
X91774Y1452500D01*
X92107Y1452583D01*
X92399Y1452500D01*
X92607Y1452333D01*
X92774Y1452083D01*
X92816Y1451792D01*
X92774Y1451542D01*
X92607Y1451292D01*
X92357Y1451083D01*
X92066Y1451000D01*
X91732Y1451083D01*
X91441Y1451333D01*
X91274Y1451708D01*
X91232Y1452125D01*
X91316Y1452667D01*
X91441Y1452958D01*
X91649Y1453250D01*
X91941Y1453458D01*
X92232Y1453500D01*
X92524Y1453417D01*
X92732Y1453208D01*
G01X96491Y1479700D02*
Y1482200D01*
X97532D01*
X97866Y1482075D01*
X98074Y1481908D01*
X98157Y1481575D01*
X98074Y1481242D01*
X97824Y1481033D01*
X97532Y1480908D01*
X96491D01*
G01X97532D02*
X98157Y1479700D01*
G01X100424D02*
Y1482200D01*
X99924Y1481700D01*
G01Y1479700D02*
X100924D01*
G01X103441D02*
X103524Y1480242D01*
X103649Y1480700D01*
X103816Y1481117D01*
X104024Y1481575D01*
X104357Y1482200D01*
X102691D01*
G01X105707Y1480200D02*
X105957Y1479908D01*
X106291Y1479742D01*
X106666Y1479700D01*
X106999Y1479742D01*
X107332Y1479950D01*
X107541Y1480200D01*
X107582Y1480450D01*
X107499Y1480742D01*
X107207Y1480950D01*
X106916Y1481033D01*
X106541D01*
G01X106916D02*
X107166Y1481158D01*
X107374Y1481367D01*
X107457Y1481617D01*
X107374Y1481867D01*
X107166Y1482075D01*
X106791Y1482200D01*
X106416Y1482158D01*
X106041Y1481992D01*
G01X101674Y1464467D02*
X99174D01*
Y1465508D01*
X99299Y1465842D01*
X99466Y1466050D01*
X99799Y1466133D01*
X100132Y1466050D01*
X100341Y1465800D01*
X100466Y1465508D01*
Y1464467D01*
G01Y1465508D02*
X101674Y1466133D01*
G01Y1468400D02*
X99174D01*
X99674Y1467900D01*
G01X101674D02*
Y1468900D01*
G01X101174Y1470583D02*
X101466Y1470833D01*
X101632Y1471167D01*
X101674Y1471542D01*
X101632Y1471875D01*
X101424Y1472208D01*
X101174Y1472417D01*
X100924Y1472458D01*
X100632Y1472375D01*
X100424Y1472083D01*
X100341Y1471792D01*
Y1471417D01*
G01Y1471792D02*
X100216Y1472042D01*
X100007Y1472250D01*
X99757Y1472333D01*
X99507Y1472250D01*
X99299Y1472042D01*
X99174Y1471667D01*
X99216Y1471292D01*
X99382Y1470917D01*
G01X99174Y1474600D02*
X99257Y1474267D01*
X99466Y1474017D01*
X99716Y1473850D01*
X100049Y1473725D01*
X100424Y1473683D01*
X100799Y1473725D01*
X101132Y1473850D01*
X101382Y1474017D01*
X101591Y1474267D01*
X101674Y1474600D01*
X101591Y1474933D01*
X101382Y1475183D01*
X101132Y1475350D01*
X100799Y1475475D01*
X100424Y1475517D01*
X100049Y1475475D01*
X99716Y1475350D01*
X99466Y1475183D01*
X99257Y1474933D01*
X99174Y1474600D01*
G01X101674Y1477700D02*
X99174D01*
X99674Y1477200D01*
G01X101674D02*
Y1478200D01*
G01X81891Y1455500D02*
Y1458000D01*
X82932D01*
X83266Y1457875D01*
X83474Y1457708D01*
X83557Y1457375D01*
X83474Y1457042D01*
X83224Y1456833D01*
X82932Y1456708D01*
X81891D01*
G01X82932D02*
X83557Y1455500D01*
G01X85116Y1455792D02*
X85407Y1455583D01*
X85741Y1455500D01*
X86074Y1455583D01*
X86366Y1455833D01*
X86574Y1456208D01*
X86657Y1456583D01*
Y1457042D01*
X86574Y1457417D01*
X86366Y1457750D01*
X86116Y1457917D01*
X85824Y1458000D01*
X85491Y1457917D01*
X85241Y1457750D01*
X85074Y1457500D01*
X84991Y1457167D01*
X85074Y1456875D01*
X85282Y1456583D01*
X85532Y1456417D01*
X85824Y1456375D01*
X86157Y1456458D01*
X86407Y1456667D01*
X86657Y1457042D01*
G01X88132Y1457583D02*
X88382Y1457833D01*
X88674Y1457958D01*
X89007Y1458000D01*
X89424Y1457917D01*
X89716Y1457708D01*
X89799Y1457458D01*
X89757Y1457208D01*
X89591Y1457000D01*
X88757Y1456583D01*
X88382Y1456292D01*
X88132Y1455875D01*
X88049Y1455500D01*
X89799D01*
G01X92524D02*
Y1458000D01*
X90982Y1456208D01*
X93066D01*
G01X75674Y1453083D02*
X77466D01*
X77841Y1453250D01*
X78091Y1453583D01*
X78174Y1454000D01*
X78091Y1454417D01*
X77841Y1454750D01*
X77466Y1454917D01*
X75674D01*
G01X78174Y1457600D02*
X75674D01*
X77466Y1456058D01*
Y1458142D01*
G01X77882Y1459492D02*
X78091Y1459783D01*
X78174Y1460117D01*
X78091Y1460450D01*
X77841Y1460742D01*
X77466Y1460950D01*
X77091Y1461033D01*
X76632D01*
X76257Y1460950D01*
X75924Y1460742D01*
X75757Y1460492D01*
X75674Y1460200D01*
X75757Y1459867D01*
X75924Y1459617D01*
X76174Y1459450D01*
X76507Y1459367D01*
X76799Y1459450D01*
X77091Y1459658D01*
X77257Y1459908D01*
X77299Y1460200D01*
X77216Y1460533D01*
X77007Y1460783D01*
X76632Y1461033D01*
G01X69991Y1466100D02*
Y1468600D01*
X71032D01*
X71366Y1468475D01*
X71574Y1468308D01*
X71657Y1467975D01*
X71574Y1467642D01*
X71324Y1467433D01*
X71032Y1467308D01*
X69991D01*
G01X71032D02*
X71657Y1466100D01*
G01X73216Y1466392D02*
X73507Y1466183D01*
X73841Y1466100D01*
X74174Y1466183D01*
X74466Y1466433D01*
X74674Y1466808D01*
X74757Y1467183D01*
Y1467642D01*
X74674Y1468017D01*
X74466Y1468350D01*
X74216Y1468517D01*
X73924Y1468600D01*
X73591Y1468517D01*
X73341Y1468350D01*
X73174Y1468100D01*
X73091Y1467767D01*
X73174Y1467475D01*
X73382Y1467183D01*
X73632Y1467017D01*
X73924Y1466975D01*
X74257Y1467058D01*
X74507Y1467267D01*
X74757Y1467642D01*
G01X76232Y1467142D02*
X76524Y1467433D01*
X76774Y1467600D01*
X77107Y1467683D01*
X77399Y1467600D01*
X77607Y1467433D01*
X77774Y1467183D01*
X77816Y1466892D01*
X77774Y1466642D01*
X77607Y1466392D01*
X77357Y1466183D01*
X77066Y1466100D01*
X76732Y1466183D01*
X76441Y1466433D01*
X76274Y1466808D01*
X76232Y1467225D01*
X76316Y1467767D01*
X76441Y1468058D01*
X76649Y1468350D01*
X76941Y1468558D01*
X77232Y1468600D01*
X77524Y1468517D01*
X77732Y1468308D01*
G01X79332Y1468183D02*
X79582Y1468433D01*
X79874Y1468558D01*
X80207Y1468600D01*
X80624Y1468517D01*
X80916Y1468308D01*
X80999Y1468058D01*
X80957Y1467808D01*
X80791Y1467600D01*
X79957Y1467183D01*
X79582Y1466892D01*
X79332Y1466475D01*
X79249Y1466100D01*
X80999D01*
G01X97124Y1462350D02*
X91924D01*
G01X97124Y1469350D02*
X89324D01*
G01X97124Y1462350D02*
Y1469350D01*
G01X83724Y1462350D02*
X92424D01*
G01X83724Y1469350D02*
Y1462350D01*
G01X90124Y1469350D02*
X83724D01*
G01X69991Y1469700D02*
Y1472200D01*
X71032D01*
X71366Y1472075D01*
X71574Y1471908D01*
X71657Y1471575D01*
X71574Y1471242D01*
X71324Y1471033D01*
X71032Y1470908D01*
X69991D01*
G01X71032D02*
X71657Y1469700D01*
G01X73216Y1469992D02*
X73507Y1469783D01*
X73841Y1469700D01*
X74174Y1469783D01*
X74466Y1470033D01*
X74674Y1470408D01*
X74757Y1470783D01*
Y1471242D01*
X74674Y1471617D01*
X74466Y1471950D01*
X74216Y1472117D01*
X73924Y1472200D01*
X73591Y1472117D01*
X73341Y1471950D01*
X73174Y1471700D01*
X73091Y1471367D01*
X73174Y1471075D01*
X73382Y1470783D01*
X73632Y1470617D01*
X73924Y1470575D01*
X74257Y1470658D01*
X74507Y1470867D01*
X74757Y1471242D01*
G01X76232Y1470742D02*
X76524Y1471033D01*
X76774Y1471200D01*
X77107Y1471283D01*
X77399Y1471200D01*
X77607Y1471033D01*
X77774Y1470783D01*
X77816Y1470492D01*
X77774Y1470242D01*
X77607Y1469992D01*
X77357Y1469783D01*
X77066Y1469700D01*
X76732Y1469783D01*
X76441Y1470033D01*
X76274Y1470408D01*
X76232Y1470825D01*
X76316Y1471367D01*
X76441Y1471658D01*
X76649Y1471950D01*
X76941Y1472158D01*
X77232Y1472200D01*
X77524Y1472117D01*
X77732Y1471908D01*
G01X79207Y1470075D02*
X79457Y1469867D01*
X79749Y1469742D01*
X80124Y1469700D01*
X80499Y1469783D01*
X80791Y1469950D01*
X80999Y1470242D01*
X81041Y1470575D01*
X80957Y1470908D01*
X80749Y1471117D01*
X80457Y1471283D01*
X80166Y1471325D01*
X79874Y1471283D01*
X79499Y1471117D01*
X79624Y1472200D01*
X80749D01*
G01X83824Y1477150D02*
X89024D01*
G01X83824Y1470150D02*
X91624D01*
G01X83824Y1477150D02*
Y1470150D01*
G01X97224Y1477150D02*
X88524D01*
G01X97224Y1470150D02*
Y1477150D01*
G01X90824Y1470150D02*
X97224D01*
G01X65532Y1474350D02*
Y1476850D01*
X67116D01*
G01X66532Y1475642D02*
X65532D01*
G01X68591Y1476850D02*
Y1474350D01*
X70257D01*
G01X73357D02*
X71691D01*
Y1476850D01*
X73357D01*
G01X72691Y1475642D02*
X71691D01*
G01X74707Y1474350D02*
Y1476850D01*
X75541D01*
X75874Y1476725D01*
X76124Y1476558D01*
X76332Y1476308D01*
X76499Y1476017D01*
X76541Y1475600D01*
X76499Y1475183D01*
X76332Y1474892D01*
X76124Y1474642D01*
X75874Y1474475D01*
X75541Y1474350D01*
X74707D01*
G01X78724D02*
Y1476850D01*
X78224Y1476350D01*
G01Y1474350D02*
X79224D01*
G01X95509Y1479118D02*
X65909D01*
Y1516718D01*
X95509D01*
Y1479118D01*
G01X87614Y1494328D02*
X94314D01*
G01X82514D02*
X78414D01*
G01X87614Y1499428D02*
X82514Y1494328D01*
G01X87614Y1489228D02*
Y1499428D01*
G01X82514Y1494328D02*
X87614Y1489228D01*
G01X73314Y1499428D02*
X78414Y1494328D01*
G01X73314Y1489228D02*
Y1499428D01*
G01X78414Y1494328D02*
X73314Y1489228D01*
G01Y1494328D02*
X69614D01*
G01X82514Y1497128D02*
Y1490728D01*
G01X78414Y1497128D02*
Y1490728D01*
G01X133767Y70792D02*
X133517Y70917D01*
X133225Y71000D01*
X132892D01*
X132517Y70875D01*
X132225Y70667D01*
X132017Y70417D01*
X131850Y70000D01*
X131808Y69625D01*
X131892Y69250D01*
X132017Y69000D01*
X132267Y68750D01*
X132558Y68583D01*
X132850Y68500D01*
X133142D01*
X133433Y68583D01*
X133683Y68708D01*
X133892Y68875D01*
G01X135033Y69000D02*
X135283Y68708D01*
X135617Y68542D01*
X135992Y68500D01*
X136325Y68542D01*
X136658Y68750D01*
X136867Y69000D01*
X136908Y69250D01*
X136825Y69542D01*
X136533Y69750D01*
X136242Y69833D01*
X135867D01*
G01X136242D02*
X136492Y69958D01*
X136700Y70167D01*
X136783Y70417D01*
X136700Y70667D01*
X136492Y70875D01*
X136117Y71000D01*
X135742Y70958D01*
X135367Y70792D01*
G01X139550Y68500D02*
Y71000D01*
X138008Y69208D01*
X140092D01*
G01X142150Y68500D02*
Y71000D01*
X141650Y70500D01*
G01Y68500D02*
X142650D01*
G01X133767Y74792D02*
X133517Y74917D01*
X133225Y75000D01*
X132892D01*
X132517Y74875D01*
X132225Y74667D01*
X132017Y74417D01*
X131850Y74000D01*
X131808Y73625D01*
X131892Y73250D01*
X132017Y73000D01*
X132267Y72750D01*
X132558Y72583D01*
X132850Y72500D01*
X133142D01*
X133433Y72583D01*
X133683Y72708D01*
X133892Y72875D01*
G01X135033Y73000D02*
X135283Y72708D01*
X135617Y72542D01*
X135992Y72500D01*
X136325Y72542D01*
X136658Y72750D01*
X136867Y73000D01*
X136908Y73250D01*
X136825Y73542D01*
X136533Y73750D01*
X136242Y73833D01*
X135867D01*
G01X136242D02*
X136492Y73958D01*
X136700Y74167D01*
X136783Y74417D01*
X136700Y74667D01*
X136492Y74875D01*
X136117Y75000D01*
X135742Y74958D01*
X135367Y74792D01*
G01X139550Y72500D02*
Y75000D01*
X138008Y73208D01*
X140092D01*
G01X142150Y75000D02*
X141817Y74917D01*
X141567Y74708D01*
X141400Y74458D01*
X141275Y74125D01*
X141233Y73750D01*
X141275Y73375D01*
X141400Y73042D01*
X141567Y72792D01*
X141817Y72583D01*
X142150Y72500D01*
X142483Y72583D01*
X142733Y72792D01*
X142900Y73042D01*
X143025Y73375D01*
X143067Y73750D01*
X143025Y74125D01*
X142900Y74458D01*
X142733Y74708D01*
X142483Y74917D01*
X142150Y75000D01*
G01X144767Y84953D02*
X144517Y85078D01*
X144225Y85161D01*
X143892D01*
X143517Y85036D01*
X143225Y84828D01*
X143017Y84578D01*
X142850Y84161D01*
X142808Y83786D01*
X142892Y83411D01*
X143017Y83161D01*
X143267Y82911D01*
X143558Y82744D01*
X143850Y82661D01*
X144142D01*
X144433Y82744D01*
X144683Y82869D01*
X144892Y83036D01*
G01X146033Y83161D02*
X146283Y82869D01*
X146617Y82703D01*
X146992Y82661D01*
X147325Y82703D01*
X147658Y82911D01*
X147867Y83161D01*
X147908Y83411D01*
X147825Y83703D01*
X147533Y83911D01*
X147242Y83994D01*
X146867D01*
G01X147242D02*
X147492Y84119D01*
X147700Y84328D01*
X147783Y84578D01*
X147700Y84828D01*
X147492Y85036D01*
X147117Y85161D01*
X146742Y85119D01*
X146367Y84953D01*
G01X149258Y83703D02*
X149550Y83994D01*
X149800Y84161D01*
X150133Y84244D01*
X150425Y84161D01*
X150633Y83994D01*
X150800Y83744D01*
X150842Y83453D01*
X150800Y83203D01*
X150633Y82953D01*
X150383Y82744D01*
X150092Y82661D01*
X149758Y82744D01*
X149467Y82994D01*
X149300Y83369D01*
X149258Y83786D01*
X149342Y84328D01*
X149467Y84619D01*
X149675Y84911D01*
X149967Y85119D01*
X150258Y85161D01*
X150550Y85078D01*
X150758Y84869D01*
G01X152233Y83161D02*
X152483Y82869D01*
X152817Y82703D01*
X153192Y82661D01*
X153525Y82703D01*
X153858Y82911D01*
X154067Y83161D01*
X154108Y83411D01*
X154025Y83703D01*
X153733Y83911D01*
X153442Y83994D01*
X153067D01*
G01X153442D02*
X153692Y84119D01*
X153900Y84328D01*
X153983Y84578D01*
X153900Y84828D01*
X153692Y85036D01*
X153317Y85161D01*
X152942Y85119D01*
X152567Y84953D01*
G01X143317Y13292D02*
X143067Y13417D01*
X142775Y13500D01*
X142442D01*
X142067Y13375D01*
X141775Y13167D01*
X141567Y12917D01*
X141400Y12500D01*
X141358Y12125D01*
X141442Y11750D01*
X141567Y11500D01*
X141817Y11250D01*
X142108Y11083D01*
X142400Y11000D01*
X142692D01*
X142983Y11083D01*
X143233Y11208D01*
X143442Y11375D01*
G01X144708Y13083D02*
X144958Y13333D01*
X145250Y13458D01*
X145583Y13500D01*
X146000Y13417D01*
X146292Y13208D01*
X146375Y12958D01*
X146333Y12708D01*
X146167Y12500D01*
X145333Y12083D01*
X144958Y11792D01*
X144708Y11375D01*
X144625Y11000D01*
X146375D01*
G01X148517D02*
X148600Y11542D01*
X148725Y12000D01*
X148892Y12417D01*
X149100Y12875D01*
X149433Y13500D01*
X147767D01*
G01X143017Y78661D02*
Y81161D01*
X144058D01*
X144392Y81036D01*
X144600Y80869D01*
X144683Y80536D01*
X144600Y80203D01*
X144350Y79994D01*
X144058Y79869D01*
X143017D01*
G01X144058D02*
X144683Y78661D01*
G01X146158Y79703D02*
X146450Y79994D01*
X146700Y80161D01*
X147033Y80244D01*
X147325Y80161D01*
X147533Y79994D01*
X147700Y79744D01*
X147742Y79453D01*
X147700Y79203D01*
X147533Y78953D01*
X147283Y78744D01*
X146992Y78661D01*
X146658Y78744D01*
X146367Y78994D01*
X146200Y79369D01*
X146158Y79786D01*
X146242Y80328D01*
X146367Y80619D01*
X146575Y80911D01*
X146867Y81119D01*
X147158Y81161D01*
X147450Y81078D01*
X147658Y80869D01*
G01X149133Y79036D02*
X149383Y78828D01*
X149675Y78703D01*
X150050Y78661D01*
X150425Y78744D01*
X150717Y78911D01*
X150925Y79203D01*
X150967Y79536D01*
X150883Y79869D01*
X150675Y80078D01*
X150383Y80244D01*
X150092Y80286D01*
X149800Y80244D01*
X149425Y80078D01*
X149550Y81161D01*
X150675D01*
G01X152358Y80744D02*
X152608Y80994D01*
X152900Y81119D01*
X153233Y81161D01*
X153650Y81078D01*
X153942Y80869D01*
X154025Y80619D01*
X153983Y80369D01*
X153817Y80161D01*
X152983Y79744D01*
X152608Y79453D01*
X152358Y79036D01*
X152275Y78661D01*
X154025D01*
G01X200700Y76500D02*
Y80500D01*
X193300D01*
G01X162033Y75374D02*
X159533D01*
Y76415D01*
X159658Y76749D01*
X159825Y76957D01*
X160158Y77040D01*
X160491Y76957D01*
X160700Y76707D01*
X160825Y76415D01*
Y75374D01*
G01Y76415D02*
X162033Y77040D01*
G01X160991Y78515D02*
X160700Y78807D01*
X160533Y79057D01*
X160450Y79390D01*
X160533Y79682D01*
X160700Y79890D01*
X160950Y80057D01*
X161241Y80099D01*
X161491Y80057D01*
X161741Y79890D01*
X161950Y79640D01*
X162033Y79349D01*
X161950Y79015D01*
X161700Y78724D01*
X161325Y78557D01*
X160908Y78515D01*
X160366Y78599D01*
X160075Y78724D01*
X159783Y78932D01*
X159575Y79224D01*
X159533Y79515D01*
X159616Y79807D01*
X159825Y80015D01*
G01X161658Y81490D02*
X161866Y81740D01*
X161991Y82032D01*
X162033Y82407D01*
X161950Y82782D01*
X161783Y83074D01*
X161491Y83282D01*
X161158Y83324D01*
X160825Y83240D01*
X160616Y83032D01*
X160450Y82740D01*
X160408Y82449D01*
X160450Y82157D01*
X160616Y81782D01*
X159533Y81907D01*
Y83032D01*
G01X161533Y84590D02*
X161825Y84840D01*
X161991Y85174D01*
X162033Y85549D01*
X161991Y85882D01*
X161783Y86215D01*
X161533Y86424D01*
X161283Y86465D01*
X160991Y86382D01*
X160783Y86090D01*
X160700Y85799D01*
Y85424D01*
G01Y85799D02*
X160575Y86049D01*
X160366Y86257D01*
X160116Y86340D01*
X159866Y86257D01*
X159658Y86049D01*
X159533Y85674D01*
X159575Y85299D01*
X159741Y84924D01*
G01X166000Y75517D02*
X163500D01*
Y76558D01*
X163625Y76892D01*
X163792Y77100D01*
X164125Y77183D01*
X164458Y77100D01*
X164667Y76850D01*
X164792Y76558D01*
Y75517D01*
G01Y76558D02*
X166000Y77183D01*
G01X164958Y78658D02*
X164667Y78950D01*
X164500Y79200D01*
X164417Y79533D01*
X164500Y79825D01*
X164667Y80033D01*
X164917Y80200D01*
X165208Y80242D01*
X165458Y80200D01*
X165708Y80033D01*
X165917Y79783D01*
X166000Y79492D01*
X165917Y79158D01*
X165667Y78867D01*
X165292Y78700D01*
X164875Y78658D01*
X164333Y78742D01*
X164042Y78867D01*
X163750Y79075D01*
X163542Y79367D01*
X163500Y79658D01*
X163583Y79950D01*
X163792Y80158D01*
G01X165625Y81633D02*
X165833Y81883D01*
X165958Y82175D01*
X166000Y82550D01*
X165917Y82925D01*
X165750Y83217D01*
X165458Y83425D01*
X165125Y83467D01*
X164792Y83383D01*
X164583Y83175D01*
X164417Y82883D01*
X164375Y82592D01*
X164417Y82300D01*
X164583Y81925D01*
X163500Y82050D01*
Y83175D01*
G01X164958Y84858D02*
X164667Y85150D01*
X164500Y85400D01*
X164417Y85733D01*
X164500Y86025D01*
X164667Y86233D01*
X164917Y86400D01*
X165208Y86442D01*
X165458Y86400D01*
X165708Y86233D01*
X165917Y85983D01*
X166000Y85692D01*
X165917Y85358D01*
X165667Y85067D01*
X165292Y84900D01*
X164875Y84858D01*
X164333Y84942D01*
X164042Y85067D01*
X163750Y85275D01*
X163542Y85567D01*
X163500Y85858D01*
X163583Y86150D01*
X163792Y86358D01*
G01X158194Y75374D02*
X155694D01*
Y76415D01*
X155819Y76749D01*
X155986Y76957D01*
X156319Y77040D01*
X156652Y76957D01*
X156861Y76707D01*
X156986Y76415D01*
Y75374D01*
G01Y76415D02*
X158194Y77040D01*
G01X157152Y78515D02*
X156861Y78807D01*
X156694Y79057D01*
X156611Y79390D01*
X156694Y79682D01*
X156861Y79890D01*
X157111Y80057D01*
X157402Y80099D01*
X157652Y80057D01*
X157902Y79890D01*
X158111Y79640D01*
X158194Y79349D01*
X158111Y79015D01*
X157861Y78724D01*
X157486Y78557D01*
X157069Y78515D01*
X156527Y78599D01*
X156236Y78724D01*
X155944Y78932D01*
X155736Y79224D01*
X155694Y79515D01*
X155777Y79807D01*
X155986Y80015D01*
G01X157819Y81490D02*
X158027Y81740D01*
X158152Y82032D01*
X158194Y82407D01*
X158111Y82782D01*
X157944Y83074D01*
X157652Y83282D01*
X157319Y83324D01*
X156986Y83240D01*
X156777Y83032D01*
X156611Y82740D01*
X156569Y82449D01*
X156611Y82157D01*
X156777Y81782D01*
X155694Y81907D01*
Y83032D01*
G01X158194Y85424D02*
X157652Y85507D01*
X157194Y85632D01*
X156777Y85799D01*
X156319Y86007D01*
X155694Y86340D01*
Y84674D01*
G01X160211Y14889D02*
Y17389D01*
X161252D01*
X161586Y17264D01*
X161794Y17097D01*
X161877Y16764D01*
X161794Y16431D01*
X161544Y16222D01*
X161252Y16097D01*
X160211D01*
G01X161252D02*
X161877Y14889D01*
G01X164144D02*
Y17389D01*
X163644Y16889D01*
G01Y14889D02*
X164644D01*
G01X166452Y16972D02*
X166702Y17222D01*
X166994Y17347D01*
X167327Y17389D01*
X167744Y17306D01*
X168036Y17097D01*
X168119Y16847D01*
X168077Y16597D01*
X167911Y16389D01*
X167077Y15972D01*
X166702Y15681D01*
X166452Y15264D01*
X166369Y14889D01*
X168119D01*
G01X169427Y15264D02*
X169677Y15056D01*
X169969Y14931D01*
X170344Y14889D01*
X170719Y14972D01*
X171011Y15139D01*
X171219Y15431D01*
X171261Y15764D01*
X171177Y16097D01*
X170969Y16306D01*
X170677Y16472D01*
X170386Y16514D01*
X170094Y16472D01*
X169719Y16306D01*
X169844Y17389D01*
X170969D01*
G01X166200Y23100D02*
Y27100D01*
X158800D01*
G01X164217Y32200D02*
Y34700D01*
X165258D01*
X165592Y34575D01*
X165800Y34408D01*
X165883Y34075D01*
X165800Y33742D01*
X165550Y33533D01*
X165258Y33408D01*
X164217D01*
G01X165258D02*
X165883Y32200D01*
G01X168150D02*
Y34700D01*
X167650Y34200D01*
G01Y32200D02*
X168650D01*
G01X170333Y32700D02*
X170583Y32408D01*
X170917Y32242D01*
X171292Y32200D01*
X171625Y32242D01*
X171958Y32450D01*
X172167Y32700D01*
X172208Y32950D01*
X172125Y33242D01*
X171833Y33450D01*
X171542Y33533D01*
X171167D01*
G01X171542D02*
X171792Y33658D01*
X172000Y33867D01*
X172083Y34117D01*
X172000Y34367D01*
X171792Y34575D01*
X171417Y34700D01*
X171042Y34658D01*
X170667Y34492D01*
G01X174350Y32200D02*
Y34700D01*
X173850Y34200D01*
G01Y32200D02*
X174850D01*
G01X162500Y30100D02*
Y34100D01*
X155100D01*
G01X179517Y24300D02*
Y26800D01*
X180558D01*
X180892Y26675D01*
X181100Y26508D01*
X181183Y26175D01*
X181100Y25842D01*
X180850Y25633D01*
X180558Y25508D01*
X179517D01*
G01X180558D02*
X181183Y24300D01*
G01X183450D02*
Y26800D01*
X182950Y26300D01*
G01Y24300D02*
X183950D01*
G01X185633Y24800D02*
X185883Y24508D01*
X186217Y24342D01*
X186592Y24300D01*
X186925Y24342D01*
X187258Y24550D01*
X187467Y24800D01*
X187508Y25050D01*
X187425Y25342D01*
X187133Y25550D01*
X186842Y25633D01*
X186467D01*
G01X186842D02*
X187092Y25758D01*
X187300Y25967D01*
X187383Y26217D01*
X187300Y26467D01*
X187092Y26675D01*
X186717Y26800D01*
X186342Y26758D01*
X185967Y26592D01*
G01X189650Y26800D02*
X189317Y26717D01*
X189067Y26508D01*
X188900Y26258D01*
X188775Y25925D01*
X188733Y25550D01*
X188775Y25175D01*
X188900Y24842D01*
X189067Y24592D01*
X189317Y24383D01*
X189650Y24300D01*
X189983Y24383D01*
X190233Y24592D01*
X190400Y24842D01*
X190525Y25175D01*
X190567Y25550D01*
X190525Y25925D01*
X190400Y26258D01*
X190233Y26508D01*
X189983Y26717D01*
X189650Y26800D01*
G01X177600Y23100D02*
Y27100D01*
X170200D01*
G01X160411Y11089D02*
Y13589D01*
X161452D01*
X161786Y13464D01*
X161994Y13297D01*
X162077Y12964D01*
X161994Y12631D01*
X161744Y12422D01*
X161452Y12297D01*
X160411D01*
G01X161452D02*
X162077Y11089D01*
G01X164344D02*
Y13589D01*
X163844Y13089D01*
G01Y11089D02*
X164844D01*
G01X166652Y13172D02*
X166902Y13422D01*
X167194Y13547D01*
X167527Y13589D01*
X167944Y13506D01*
X168236Y13297D01*
X168319Y13047D01*
X168277Y12797D01*
X168111Y12589D01*
X167277Y12172D01*
X166902Y11881D01*
X166652Y11464D01*
X166569Y11089D01*
X168319D01*
G01X169836Y11381D02*
X170127Y11172D01*
X170461Y11089D01*
X170794Y11172D01*
X171086Y11422D01*
X171294Y11797D01*
X171377Y12172D01*
Y12631D01*
X171294Y13006D01*
X171086Y13339D01*
X170836Y13506D01*
X170544Y13589D01*
X170211Y13506D01*
X169961Y13339D01*
X169794Y13089D01*
X169711Y12756D01*
X169794Y12464D01*
X170002Y12172D01*
X170252Y12006D01*
X170544Y11964D01*
X170877Y12047D01*
X171127Y12256D01*
X171377Y12631D01*
G01X166200Y19100D02*
Y23100D01*
X158800D01*
G01X181317Y17400D02*
Y19900D01*
X182358D01*
X182692Y19775D01*
X182900Y19608D01*
X182983Y19275D01*
X182900Y18942D01*
X182650Y18733D01*
X182358Y18608D01*
X181317D01*
G01X182358D02*
X182983Y17400D01*
G01X185250D02*
Y19900D01*
X184750Y19400D01*
G01Y17400D02*
X185750D01*
G01X187558Y19483D02*
X187808Y19733D01*
X188100Y19858D01*
X188433Y19900D01*
X188850Y19817D01*
X189142Y19608D01*
X189225Y19358D01*
X189183Y19108D01*
X189017Y18900D01*
X188183Y18483D01*
X187808Y18192D01*
X187558Y17775D01*
X187475Y17400D01*
X189225D01*
G01X191950D02*
Y19900D01*
X190408Y18108D01*
X192492D01*
G01X177600Y18900D02*
Y22900D01*
X170200D01*
G01X178717Y28300D02*
Y30800D01*
X179758D01*
X180092Y30675D01*
X180300Y30508D01*
X180383Y30175D01*
X180300Y29842D01*
X180050Y29633D01*
X179758Y29508D01*
X178717D01*
G01X179758D02*
X180383Y28300D01*
G01X182650D02*
Y30800D01*
X182150Y30300D01*
G01Y28300D02*
X183150D01*
G01X184958Y30383D02*
X185208Y30633D01*
X185500Y30758D01*
X185833Y30800D01*
X186250Y30717D01*
X186542Y30508D01*
X186625Y30258D01*
X186583Y30008D01*
X186417Y29800D01*
X185583Y29383D01*
X185208Y29092D01*
X184958Y28675D01*
X184875Y28300D01*
X186625D01*
G01X188850D02*
Y30800D01*
X188350Y30300D01*
G01Y28300D02*
X189350D01*
G01X173800Y27200D02*
Y31200D01*
X166400D01*
G01X138117Y52800D02*
Y55300D01*
X139158D01*
X139492Y55175D01*
X139700Y55008D01*
X139783Y54675D01*
X139700Y54342D01*
X139450Y54133D01*
X139158Y54008D01*
X138117D01*
G01X139158D02*
X139783Y52800D01*
G01X142050D02*
Y55300D01*
X141550Y54800D01*
G01Y52800D02*
X142550D01*
G01X144358Y54883D02*
X144608Y55133D01*
X144900Y55258D01*
X145233Y55300D01*
X145650Y55217D01*
X145942Y55008D01*
X146025Y54758D01*
X145983Y54508D01*
X145817Y54300D01*
X144983Y53883D01*
X144608Y53592D01*
X144358Y53175D01*
X144275Y52800D01*
X146025D01*
G01X148250D02*
X148542Y52842D01*
X148875Y52967D01*
X149083Y53175D01*
X149167Y53467D01*
X149083Y53758D01*
X148833Y54008D01*
X148458Y54133D01*
X148042D01*
X147792Y54217D01*
X147583Y54425D01*
X147500Y54717D01*
X147625Y55008D01*
X147917Y55217D01*
X148250Y55300D01*
X148583Y55217D01*
X148875Y55008D01*
X149000Y54717D01*
X148917Y54425D01*
X148708Y54217D01*
X148458Y54133D01*
X148042D01*
X147667Y54008D01*
X147417Y53758D01*
X147333Y53467D01*
X147417Y53175D01*
X147625Y52967D01*
X147958Y52842D01*
X148250Y52800D01*
G01X149500Y42400D02*
Y46400D01*
X142100D01*
G01X138217Y56000D02*
Y58500D01*
X139258D01*
X139592Y58375D01*
X139800Y58208D01*
X139883Y57875D01*
X139800Y57542D01*
X139550Y57333D01*
X139258Y57208D01*
X138217D01*
G01X139258D02*
X139883Y56000D01*
G01X142150D02*
Y58500D01*
X141650Y58000D01*
G01Y56000D02*
X142650D01*
G01X144458Y58083D02*
X144708Y58333D01*
X145000Y58458D01*
X145333Y58500D01*
X145750Y58417D01*
X146042Y58208D01*
X146125Y57958D01*
X146083Y57708D01*
X145917Y57500D01*
X145083Y57083D01*
X144708Y56792D01*
X144458Y56375D01*
X144375Y56000D01*
X146125D01*
G01X148267D02*
X148350Y56542D01*
X148475Y57000D01*
X148642Y57417D01*
X148850Y57875D01*
X149183Y58500D01*
X147517D01*
G01X149500Y46500D02*
Y50500D01*
X142100D01*
G01X143317Y17292D02*
X143067Y17417D01*
X142775Y17500D01*
X142442D01*
X142067Y17375D01*
X141775Y17167D01*
X141567Y16917D01*
X141400Y16500D01*
X141358Y16125D01*
X141442Y15750D01*
X141567Y15500D01*
X141817Y15250D01*
X142108Y15083D01*
X142400Y15000D01*
X142692D01*
X142983Y15083D01*
X143233Y15208D01*
X143442Y15375D01*
G01X144708Y17083D02*
X144958Y17333D01*
X145250Y17458D01*
X145583Y17500D01*
X146000Y17417D01*
X146292Y17208D01*
X146375Y16958D01*
X146333Y16708D01*
X146167Y16500D01*
X145333Y16083D01*
X144958Y15792D01*
X144708Y15375D01*
X144625Y15000D01*
X146375D01*
G01X147892Y15292D02*
X148183Y15083D01*
X148517Y15000D01*
X148850Y15083D01*
X149142Y15333D01*
X149350Y15708D01*
X149433Y16083D01*
Y16542D01*
X149350Y16917D01*
X149142Y17250D01*
X148892Y17417D01*
X148600Y17500D01*
X148267Y17417D01*
X148017Y17250D01*
X147850Y17000D01*
X147767Y16667D01*
X147850Y16375D01*
X148058Y16083D01*
X148308Y15917D01*
X148600Y15875D01*
X148933Y15958D01*
X149183Y16167D01*
X149433Y16542D01*
G01X153500Y38600D02*
Y36100D01*
G01X152542Y38600D02*
X154458D01*
G01X155767Y36100D02*
Y38600D01*
X156767D01*
X157100Y38475D01*
X157350Y38183D01*
X157433Y37850D01*
X157350Y37517D01*
X157142Y37267D01*
X156767Y37142D01*
X155767D01*
G01X158908Y38183D02*
X159158Y38433D01*
X159450Y38558D01*
X159783Y38600D01*
X160200Y38517D01*
X160492Y38308D01*
X160575Y38058D01*
X160533Y37808D01*
X160367Y37600D01*
X159533Y37183D01*
X159158Y36892D01*
X158908Y36475D01*
X158825Y36100D01*
X160575D01*
G01X170200Y90400D02*
X189400D01*
Y101600D01*
X170200D01*
Y90400D01*
X170600D01*
G01X194983Y49000D02*
Y51500D01*
X195817D01*
X196150Y51375D01*
X196400Y51208D01*
X196608Y50958D01*
X196775Y50667D01*
X196817Y50250D01*
X196775Y49833D01*
X196608Y49542D01*
X196400Y49292D01*
X196150Y49125D01*
X195817Y49000D01*
X194983D01*
G01X198208Y51083D02*
X198458Y51333D01*
X198750Y51458D01*
X199083Y51500D01*
X199500Y51417D01*
X199792Y51208D01*
X199875Y50958D01*
X199833Y50708D01*
X199667Y50500D01*
X198833Y50083D01*
X198458Y49792D01*
X198208Y49375D01*
X198125Y49000D01*
X199875D01*
G01X201183Y49375D02*
X201433Y49167D01*
X201725Y49042D01*
X202100Y49000D01*
X202475Y49083D01*
X202767Y49250D01*
X202975Y49542D01*
X203017Y49875D01*
X202933Y50208D01*
X202725Y50417D01*
X202433Y50583D01*
X202142Y50625D01*
X201850Y50583D01*
X201475Y50417D01*
X201600Y51500D01*
X202725D01*
G01X129983Y49300D02*
Y47508D01*
X130150Y47133D01*
X130483Y46883D01*
X130900Y46800D01*
X131317Y46883D01*
X131650Y47133D01*
X131817Y47508D01*
Y49300D01*
G01X134000Y46800D02*
Y49300D01*
X133500Y48800D01*
G01Y46800D02*
X134500D01*
G01X136183Y47175D02*
X136433Y46967D01*
X136725Y46842D01*
X137100Y46800D01*
X137475Y46883D01*
X137767Y47050D01*
X137975Y47342D01*
X138017Y47675D01*
X137933Y48008D01*
X137725Y48217D01*
X137433Y48383D01*
X137142Y48425D01*
X136850Y48383D01*
X136475Y48217D01*
X136600Y49300D01*
X137725D01*
G01X129411Y36796D02*
Y28796D01*
X141361D01*
Y36796D01*
X129411D01*
G01X141361Y30646D02*
X139361Y32646D01*
X141361Y34646D01*
G01X126635Y132167D02*
X126510Y131917D01*
X126427Y131625D01*
Y131292D01*
X126552Y130917D01*
X126760Y130625D01*
X127010Y130417D01*
X127427Y130250D01*
X127802Y130208D01*
X128177Y130292D01*
X128427Y130417D01*
X128677Y130667D01*
X128844Y130958D01*
X128927Y131250D01*
Y131542D01*
X128844Y131833D01*
X128719Y132083D01*
X128552Y132292D01*
G01X128427Y133433D02*
X128719Y133683D01*
X128885Y134017D01*
X128927Y134392D01*
X128885Y134725D01*
X128677Y135058D01*
X128427Y135267D01*
X128177Y135308D01*
X127885Y135225D01*
X127677Y134933D01*
X127594Y134642D01*
Y134267D01*
G01Y134642D02*
X127469Y134892D01*
X127260Y135100D01*
X127010Y135183D01*
X126760Y135100D01*
X126552Y134892D01*
X126427Y134517D01*
X126469Y134142D01*
X126635Y133767D01*
G01X128927Y137950D02*
X126427D01*
X128219Y136408D01*
Y138492D01*
G01X128635Y139842D02*
X128844Y140133D01*
X128927Y140467D01*
X128844Y140800D01*
X128594Y141092D01*
X128219Y141300D01*
X127844Y141383D01*
X127385D01*
X127010Y141300D01*
X126677Y141092D01*
X126510Y140842D01*
X126427Y140550D01*
X126510Y140217D01*
X126677Y139967D01*
X126927Y139800D01*
X127260Y139717D01*
X127552Y139800D01*
X127844Y140008D01*
X128010Y140258D01*
X128052Y140550D01*
X127969Y140883D01*
X127760Y141133D01*
X127385Y141383D01*
G01X132927Y130417D02*
X130427D01*
Y131458D01*
X130552Y131792D01*
X130719Y132000D01*
X131052Y132083D01*
X131385Y132000D01*
X131594Y131750D01*
X131719Y131458D01*
Y130417D01*
G01Y131458D02*
X132927Y132083D01*
G01X131885Y133558D02*
X131594Y133850D01*
X131427Y134100D01*
X131344Y134433D01*
X131427Y134725D01*
X131594Y134933D01*
X131844Y135100D01*
X132135Y135142D01*
X132385Y135100D01*
X132635Y134933D01*
X132844Y134683D01*
X132927Y134392D01*
X132844Y134058D01*
X132594Y133767D01*
X132219Y133600D01*
X131802Y133558D01*
X131260Y133642D01*
X130969Y133767D01*
X130677Y133975D01*
X130469Y134267D01*
X130427Y134558D01*
X130510Y134850D01*
X130719Y135058D01*
G01X130844Y136658D02*
X130594Y136908D01*
X130469Y137200D01*
X130427Y137533D01*
X130510Y137950D01*
X130719Y138242D01*
X130969Y138325D01*
X131219Y138283D01*
X131427Y138117D01*
X131844Y137283D01*
X132135Y136908D01*
X132552Y136658D01*
X132927Y136575D01*
Y138325D01*
G01X130844Y139758D02*
X130594Y140008D01*
X130469Y140300D01*
X130427Y140633D01*
X130510Y141050D01*
X130719Y141342D01*
X130969Y141425D01*
X131219Y141383D01*
X131427Y141217D01*
X131844Y140383D01*
X132135Y140008D01*
X132552Y139758D01*
X132927Y139675D01*
Y141425D01*
G01X129600Y120700D02*
X133600D01*
Y128100D01*
G01X130800Y163000D02*
Y160500D01*
G01X129842Y163000D02*
X131758D01*
G01X133067Y160500D02*
Y163000D01*
X134067D01*
X134400Y162875D01*
X134650Y162583D01*
X134733Y162250D01*
X134650Y161917D01*
X134442Y161667D01*
X134067Y161542D01*
X133067D01*
G01X137000Y160500D02*
Y163000D01*
X136500Y162500D01*
G01Y160500D02*
X137500D01*
G01X140600D02*
Y163000D01*
X139058Y161208D01*
X141142D01*
G01X143200Y160500D02*
Y163000D01*
X142700Y162500D01*
G01Y160500D02*
X143700D01*
G01X177850Y111500D02*
X177517Y111542D01*
X177225Y111708D01*
X176975Y111958D01*
X176808Y112250D01*
X176725Y112583D01*
Y112917D01*
X176808Y113250D01*
X176975Y113542D01*
X177225Y113792D01*
X177517Y113958D01*
X177850Y114000D01*
X178183Y113958D01*
X178475Y113792D01*
X178725Y113542D01*
X178892Y113250D01*
X178975Y112917D01*
Y112583D01*
X178892Y112250D01*
X178725Y111958D01*
X178475Y111708D01*
X178183Y111542D01*
X177850Y111500D01*
G01X178183Y112167D02*
X178683Y111500D01*
G01X180950D02*
Y114000D01*
X180450Y113500D01*
G01Y111500D02*
X181450D01*
G01X183258Y113583D02*
X183508Y113833D01*
X183800Y113958D01*
X184133Y114000D01*
X184550Y113917D01*
X184842Y113708D01*
X184925Y113458D01*
X184883Y113208D01*
X184717Y113000D01*
X183883Y112583D01*
X183508Y112292D01*
X183258Y111875D01*
X183175Y111500D01*
X184925D01*
G01X186358Y112542D02*
X186650Y112833D01*
X186900Y113000D01*
X187233Y113083D01*
X187525Y113000D01*
X187733Y112833D01*
X187900Y112583D01*
X187942Y112292D01*
X187900Y112042D01*
X187733Y111792D01*
X187483Y111583D01*
X187192Y111500D01*
X186858Y111583D01*
X186567Y111833D01*
X186400Y112208D01*
X186358Y112625D01*
X186442Y113167D01*
X186567Y113458D01*
X186775Y113750D01*
X187067Y113958D01*
X187358Y114000D01*
X187650Y113917D01*
X187858Y113708D01*
G01X170300Y98000D02*
X172400Y96200D01*
X170300Y94000D01*
G01X142000Y135517D02*
X139500D01*
Y136558D01*
X139625Y136892D01*
X139792Y137100D01*
X140125Y137183D01*
X140458Y137100D01*
X140667Y136850D01*
X140792Y136558D01*
Y135517D01*
G01Y136558D02*
X142000Y137183D01*
G01X140958Y138658D02*
X140667Y138950D01*
X140500Y139200D01*
X140417Y139533D01*
X140500Y139825D01*
X140667Y140033D01*
X140917Y140200D01*
X141208Y140242D01*
X141458Y140200D01*
X141708Y140033D01*
X141917Y139783D01*
X142000Y139492D01*
X141917Y139158D01*
X141667Y138867D01*
X141292Y138700D01*
X140875Y138658D01*
X140333Y138742D01*
X140042Y138867D01*
X139750Y139075D01*
X139542Y139367D01*
X139500Y139658D01*
X139583Y139950D01*
X139792Y140158D01*
G01X139917Y141758D02*
X139667Y142008D01*
X139542Y142300D01*
X139500Y142633D01*
X139583Y143050D01*
X139792Y143342D01*
X140042Y143425D01*
X140292Y143383D01*
X140500Y143217D01*
X140917Y142383D01*
X141208Y142008D01*
X141625Y141758D01*
X142000Y141675D01*
Y143425D01*
G01X140958Y144858D02*
X140667Y145150D01*
X140500Y145400D01*
X140417Y145733D01*
X140500Y146025D01*
X140667Y146233D01*
X140917Y146400D01*
X141208Y146442D01*
X141458Y146400D01*
X141708Y146233D01*
X141917Y145983D01*
X142000Y145692D01*
X141917Y145358D01*
X141667Y145067D01*
X141292Y144900D01*
X140875Y144858D01*
X140333Y144942D01*
X140042Y145067D01*
X139750Y145275D01*
X139542Y145567D01*
X139500Y145858D01*
X139583Y146150D01*
X139792Y146358D01*
G01X196767Y151953D02*
X196517Y152078D01*
X196225Y152161D01*
X195892D01*
X195517Y152036D01*
X195225Y151828D01*
X195017Y151578D01*
X194850Y151161D01*
X194808Y150786D01*
X194892Y150411D01*
X195017Y150161D01*
X195267Y149911D01*
X195558Y149744D01*
X195850Y149661D01*
X196142D01*
X196433Y149744D01*
X196683Y149869D01*
X196892Y150036D01*
G01X198033Y150161D02*
X198283Y149869D01*
X198617Y149703D01*
X198992Y149661D01*
X199325Y149703D01*
X199658Y149911D01*
X199867Y150161D01*
X199908Y150411D01*
X199825Y150703D01*
X199533Y150911D01*
X199242Y150994D01*
X198867D01*
G01X199242D02*
X199492Y151119D01*
X199700Y151328D01*
X199783Y151578D01*
X199700Y151828D01*
X199492Y152036D01*
X199117Y152161D01*
X198742Y152119D01*
X198367Y151953D01*
G01X201133Y150036D02*
X201383Y149828D01*
X201675Y149703D01*
X202050Y149661D01*
X202425Y149744D01*
X202717Y149911D01*
X202925Y150203D01*
X202967Y150536D01*
X202883Y150869D01*
X202675Y151078D01*
X202383Y151244D01*
X202092Y151286D01*
X201800Y151244D01*
X201425Y151078D01*
X201550Y152161D01*
X202675D01*
G01X204358Y150703D02*
X204650Y150994D01*
X204900Y151161D01*
X205233Y151244D01*
X205525Y151161D01*
X205733Y150994D01*
X205900Y150744D01*
X205942Y150453D01*
X205900Y150203D01*
X205733Y149953D01*
X205483Y149744D01*
X205192Y149661D01*
X204858Y149744D01*
X204567Y149994D01*
X204400Y150369D01*
X204358Y150786D01*
X204442Y151328D01*
X204567Y151619D01*
X204775Y151911D01*
X205067Y152119D01*
X205358Y152161D01*
X205650Y152078D01*
X205858Y151869D01*
G01X194200Y130000D02*
X199700D01*
G01X194200Y122000D02*
Y130000D01*
G01X199700Y122000D02*
X194200D01*
G01X189700Y136500D02*
Y144500D01*
X207300D01*
Y136500D01*
X189700D01*
G01X178767Y147792D02*
X178517Y147917D01*
X178225Y148000D01*
X177892D01*
X177517Y147875D01*
X177225Y147667D01*
X177017Y147417D01*
X176850Y147000D01*
X176808Y146625D01*
X176892Y146250D01*
X177017Y146000D01*
X177267Y145750D01*
X177558Y145583D01*
X177850Y145500D01*
X178142D01*
X178433Y145583D01*
X178683Y145708D01*
X178892Y145875D01*
G01X180033Y146000D02*
X180283Y145708D01*
X180617Y145542D01*
X180992Y145500D01*
X181325Y145542D01*
X181658Y145750D01*
X181867Y146000D01*
X181908Y146250D01*
X181825Y146542D01*
X181533Y146750D01*
X181242Y146833D01*
X180867D01*
G01X181242D02*
X181492Y146958D01*
X181700Y147167D01*
X181783Y147417D01*
X181700Y147667D01*
X181492Y147875D01*
X181117Y148000D01*
X180742Y147958D01*
X180367Y147792D01*
G01X183133Y145875D02*
X183383Y145667D01*
X183675Y145542D01*
X184050Y145500D01*
X184425Y145583D01*
X184717Y145750D01*
X184925Y146042D01*
X184967Y146375D01*
X184883Y146708D01*
X184675Y146917D01*
X184383Y147083D01*
X184092Y147125D01*
X183800Y147083D01*
X183425Y146917D01*
X183550Y148000D01*
X184675D01*
G01X186442Y145792D02*
X186733Y145583D01*
X187067Y145500D01*
X187400Y145583D01*
X187692Y145833D01*
X187900Y146208D01*
X187983Y146583D01*
Y147042D01*
X187900Y147417D01*
X187692Y147750D01*
X187442Y147917D01*
X187150Y148000D01*
X186817Y147917D01*
X186567Y147750D01*
X186400Y147500D01*
X186317Y147167D01*
X186400Y146875D01*
X186608Y146583D01*
X186858Y146417D01*
X187150Y146375D01*
X187483Y146458D01*
X187733Y146667D01*
X187983Y147042D01*
G01X100275Y209000D02*
Y211500D01*
G01X102025D02*
Y209000D01*
G01Y210250D02*
X100275D01*
G01X103333Y209000D02*
Y211500D01*
X104167D01*
X104500Y211375D01*
X104750Y211208D01*
X104958Y210958D01*
X105125Y210667D01*
X105167Y210250D01*
X105125Y209833D01*
X104958Y209542D01*
X104750Y209292D01*
X104500Y209125D01*
X104167Y209000D01*
X103333D01*
G01X106433D02*
Y211500D01*
X107267D01*
X107600Y211375D01*
X107850Y211208D01*
X108058Y210958D01*
X108225Y210667D01*
X108267Y210250D01*
X108225Y209833D01*
X108058Y209542D01*
X107850Y209292D01*
X107600Y209125D01*
X107267Y209000D01*
X106433D01*
G01X109575Y209333D02*
X109908Y209125D01*
X110283Y209000D01*
X110617D01*
X110950Y209125D01*
X111200Y209333D01*
X111325Y209625D01*
X111242Y209917D01*
X111033Y210167D01*
X110658Y210333D01*
X110158Y210417D01*
X109867Y210583D01*
X109742Y210875D01*
X109825Y211167D01*
X110033Y211375D01*
X110325Y211500D01*
X110617D01*
X110908Y211417D01*
X111158Y211208D01*
G01X112508Y209000D02*
X113550Y211500D01*
X114592Y209000D01*
G01X114217Y209875D02*
X112883D01*
G01X115775Y209333D02*
X116108Y209125D01*
X116483Y209000D01*
X116817D01*
X117150Y209125D01*
X117400Y209333D01*
X117525Y209625D01*
X117442Y209917D01*
X117233Y210167D01*
X116858Y210333D01*
X116358Y210417D01*
X116067Y210583D01*
X115942Y210875D01*
X116025Y211167D01*
X116233Y211375D01*
X116525Y211500D01*
X116817D01*
X117108Y211417D01*
X117358Y211208D01*
G01X118958Y211083D02*
X119208Y211333D01*
X119500Y211458D01*
X119833Y211500D01*
X120250Y211417D01*
X120542Y211208D01*
X120625Y210958D01*
X120583Y210708D01*
X120417Y210500D01*
X119583Y210083D01*
X119208Y209792D01*
X118958Y209375D01*
X118875Y209000D01*
X120625D01*
G01X123350D02*
Y211500D01*
X121808Y209708D01*
X123892D01*
G01X188467Y269000D02*
Y266500D01*
X190133D01*
G01X193233D02*
X191567D01*
Y269000D01*
X193233D01*
G01X192567Y267792D02*
X191567D01*
G01X194583Y266500D02*
Y269000D01*
X195417D01*
X195750Y268875D01*
X196000Y268708D01*
X196208Y268458D01*
X196375Y268167D01*
X196417Y267750D01*
X196375Y267333D01*
X196208Y267042D01*
X196000Y266792D01*
X195750Y266625D01*
X195417Y266500D01*
X194583D01*
G01X198600D02*
Y269000D01*
X198100Y268500D01*
G01Y266500D02*
X199100D01*
G01X202200D02*
Y269000D01*
X200658Y267208D01*
X202742D01*
G01X189891Y251880D02*
Y263080D01*
X198691D01*
Y251880D01*
X189891D01*
G01X197790Y468289D02*
Y472289D01*
X190390D01*
G01X196882Y459287D02*
Y463287D01*
X189482D01*
G01X189424Y461565D02*
Y465565D01*
X182024D01*
G01X182022Y469631D02*
Y465631D01*
X189422D01*
G01X150894Y474864D02*
Y477364D01*
X151935D01*
X152269Y477239D01*
X152477Y477072D01*
X152560Y476739D01*
X152477Y476406D01*
X152227Y476197D01*
X151935Y476072D01*
X150894D01*
G01X151935D02*
X152560Y474864D01*
G01X154827D02*
Y477364D01*
X154327Y476864D01*
G01Y474864D02*
X155327D01*
G01X157927D02*
Y477364D01*
X157427Y476864D01*
G01Y474864D02*
X158427D01*
G01X160110Y475364D02*
X160360Y475072D01*
X160694Y474906D01*
X161069Y474864D01*
X161402Y474906D01*
X161735Y475114D01*
X161944Y475364D01*
X161985Y475614D01*
X161902Y475906D01*
X161610Y476114D01*
X161319Y476197D01*
X160944D01*
G01X161319D02*
X161569Y476322D01*
X161777Y476531D01*
X161860Y476781D01*
X161777Y477031D01*
X161569Y477239D01*
X161194Y477364D01*
X160819Y477322D01*
X160444Y477156D01*
G01X164127Y474864D02*
Y477364D01*
X163627Y476864D01*
G01Y474864D02*
X164627D01*
G01X174590Y469589D02*
Y473589D01*
X167190D01*
G01X164366Y458811D02*
X161866D01*
Y459852D01*
X161991Y460186D01*
X162158Y460394D01*
X162491Y460477D01*
X162824Y460394D01*
X163033Y460144D01*
X163158Y459852D01*
Y458811D01*
G01Y459852D02*
X164366Y460477D01*
G01Y462744D02*
X161866D01*
X162366Y462244D01*
G01X164366D02*
Y463244D01*
G01Y465844D02*
X161866D01*
X162366Y465344D01*
G01X164366D02*
Y466344D01*
G01X163866Y468027D02*
X164158Y468277D01*
X164324Y468611D01*
X164366Y468986D01*
X164324Y469319D01*
X164116Y469652D01*
X163866Y469861D01*
X163616Y469902D01*
X163324Y469819D01*
X163116Y469527D01*
X163033Y469236D01*
Y468861D01*
G01Y469236D02*
X162908Y469486D01*
X162699Y469694D01*
X162449Y469777D01*
X162199Y469694D01*
X161991Y469486D01*
X161866Y469111D01*
X161908Y468736D01*
X162074Y468361D01*
G01X162283Y471252D02*
X162033Y471502D01*
X161908Y471794D01*
X161866Y472127D01*
X161949Y472544D01*
X162158Y472836D01*
X162408Y472919D01*
X162658Y472877D01*
X162866Y472711D01*
X163283Y471877D01*
X163574Y471502D01*
X163991Y471252D01*
X164366Y471169D01*
Y472919D01*
G01X177527Y462144D02*
X181527D01*
Y469544D01*
G01X150394Y453364D02*
Y455864D01*
X151435D01*
X151769Y455739D01*
X151977Y455572D01*
X152060Y455239D01*
X151977Y454906D01*
X151727Y454697D01*
X151435Y454572D01*
X150394D01*
G01X151435D02*
X152060Y453364D01*
G01X154327D02*
Y455864D01*
X153827Y455364D01*
G01Y453364D02*
X154827D01*
G01X157427D02*
Y455864D01*
X156927Y455364D01*
G01Y453364D02*
X157927D01*
G01X159610Y453864D02*
X159860Y453572D01*
X160194Y453406D01*
X160569Y453364D01*
X160902Y453406D01*
X161235Y453614D01*
X161444Y453864D01*
X161485Y454114D01*
X161402Y454406D01*
X161110Y454614D01*
X160819Y454697D01*
X160444D01*
G01X160819D02*
X161069Y454822D01*
X161277Y455031D01*
X161360Y455281D01*
X161277Y455531D01*
X161069Y455739D01*
X160694Y455864D01*
X160319Y455822D01*
X159944Y455656D01*
G01X162710Y453864D02*
X162960Y453572D01*
X163294Y453406D01*
X163669Y453364D01*
X164002Y453406D01*
X164335Y453614D01*
X164544Y453864D01*
X164585Y454114D01*
X164502Y454406D01*
X164210Y454614D01*
X163919Y454697D01*
X163544D01*
G01X163919D02*
X164169Y454822D01*
X164377Y455031D01*
X164460Y455281D01*
X164377Y455531D01*
X164169Y455739D01*
X163794Y455864D01*
X163419Y455822D01*
X163044Y455656D01*
G01X173290Y452289D02*
Y456289D01*
X165890D01*
G01X160229Y458756D02*
X157729D01*
Y459797D01*
X157854Y460131D01*
X158021Y460339D01*
X158354Y460422D01*
X158687Y460339D01*
X158896Y460089D01*
X159021Y459797D01*
Y458756D01*
G01Y459797D02*
X160229Y460422D01*
G01Y462689D02*
X157729D01*
X158229Y462189D01*
G01X160229D02*
Y463189D01*
G01Y465789D02*
X157729D01*
X158229Y465289D01*
G01X160229D02*
Y466289D01*
G01X159729Y467972D02*
X160021Y468222D01*
X160187Y468556D01*
X160229Y468931D01*
X160187Y469264D01*
X159979Y469597D01*
X159729Y469806D01*
X159479Y469847D01*
X159187Y469764D01*
X158979Y469472D01*
X158896Y469181D01*
Y468806D01*
G01Y469181D02*
X158771Y469431D01*
X158562Y469639D01*
X158312Y469722D01*
X158062Y469639D01*
X157854Y469431D01*
X157729Y469056D01*
X157771Y468681D01*
X157937Y468306D01*
G01X160229Y472489D02*
X157729D01*
X159521Y470947D01*
Y473031D01*
G01X173390Y462089D02*
X177390D01*
Y469489D01*
G01X174435Y382097D02*
Y384597D01*
X175476D01*
X175810Y384472D01*
X176018Y384305D01*
X176101Y383972D01*
X176018Y383639D01*
X175768Y383430D01*
X175476Y383305D01*
X174435D01*
G01X175476D02*
X176101Y382097D01*
G01X177451Y382597D02*
X177701Y382305D01*
X178035Y382139D01*
X178410Y382097D01*
X178743Y382139D01*
X179076Y382347D01*
X179285Y382597D01*
X179326Y382847D01*
X179243Y383139D01*
X178951Y383347D01*
X178660Y383430D01*
X178285D01*
G01X178660D02*
X178910Y383555D01*
X179118Y383764D01*
X179201Y384014D01*
X179118Y384264D01*
X178910Y384472D01*
X178535Y384597D01*
X178160Y384555D01*
X177785Y384389D01*
G01X180676Y383139D02*
X180968Y383430D01*
X181218Y383597D01*
X181551Y383680D01*
X181843Y383597D01*
X182051Y383430D01*
X182218Y383180D01*
X182260Y382889D01*
X182218Y382639D01*
X182051Y382389D01*
X181801Y382180D01*
X181510Y382097D01*
X181176Y382180D01*
X180885Y382430D01*
X180718Y382805D01*
X180676Y383222D01*
X180760Y383764D01*
X180885Y384055D01*
X181093Y384347D01*
X181385Y384555D01*
X181676Y384597D01*
X181968Y384514D01*
X182176Y384305D01*
G01X183776Y383139D02*
X184068Y383430D01*
X184318Y383597D01*
X184651Y383680D01*
X184943Y383597D01*
X185151Y383430D01*
X185318Y383180D01*
X185360Y382889D01*
X185318Y382639D01*
X185151Y382389D01*
X184901Y382180D01*
X184610Y382097D01*
X184276Y382180D01*
X183985Y382430D01*
X183818Y382805D01*
X183776Y383222D01*
X183860Y383764D01*
X183985Y384055D01*
X184193Y384347D01*
X184485Y384555D01*
X184776Y384597D01*
X185068Y384514D01*
X185276Y384305D01*
G01X194792Y381182D02*
Y385182D01*
X187392D01*
G01X151694Y445656D02*
X151444Y445781D01*
X151152Y445864D01*
X150819D01*
X150444Y445739D01*
X150152Y445531D01*
X149944Y445281D01*
X149777Y444864D01*
X149735Y444489D01*
X149819Y444114D01*
X149944Y443864D01*
X150194Y443614D01*
X150485Y443447D01*
X150777Y443364D01*
X151069D01*
X151360Y443447D01*
X151610Y443572D01*
X151819Y443739D01*
G01X153085Y444406D02*
X153377Y444697D01*
X153627Y444864D01*
X153960Y444947D01*
X154252Y444864D01*
X154460Y444697D01*
X154627Y444447D01*
X154669Y444156D01*
X154627Y443906D01*
X154460Y443656D01*
X154210Y443447D01*
X153919Y443364D01*
X153585Y443447D01*
X153294Y443697D01*
X153127Y444072D01*
X153085Y444489D01*
X153169Y445031D01*
X153294Y445322D01*
X153502Y445614D01*
X153794Y445822D01*
X154085Y445864D01*
X154377Y445781D01*
X154585Y445572D01*
G01X156060Y443864D02*
X156310Y443572D01*
X156644Y443406D01*
X157019Y443364D01*
X157352Y443406D01*
X157685Y443614D01*
X157894Y443864D01*
X157935Y444114D01*
X157852Y444406D01*
X157560Y444614D01*
X157269Y444697D01*
X156894D01*
G01X157269D02*
X157519Y444822D01*
X157727Y445031D01*
X157810Y445281D01*
X157727Y445531D01*
X157519Y445739D01*
X157144Y445864D01*
X156769Y445822D01*
X156394Y445656D01*
G01X159369Y443656D02*
X159660Y443447D01*
X159994Y443364D01*
X160327Y443447D01*
X160619Y443697D01*
X160827Y444072D01*
X160910Y444447D01*
Y444906D01*
X160827Y445281D01*
X160619Y445614D01*
X160369Y445781D01*
X160077Y445864D01*
X159744Y445781D01*
X159494Y445614D01*
X159327Y445364D01*
X159244Y445031D01*
X159327Y444739D01*
X159535Y444447D01*
X159785Y444281D01*
X160077Y444239D01*
X160410Y444322D01*
X160660Y444531D01*
X160910Y444906D01*
G01X151694Y441656D02*
X151444Y441781D01*
X151152Y441864D01*
X150819D01*
X150444Y441739D01*
X150152Y441531D01*
X149944Y441281D01*
X149777Y440864D01*
X149735Y440489D01*
X149819Y440114D01*
X149944Y439864D01*
X150194Y439614D01*
X150485Y439447D01*
X150777Y439364D01*
X151069D01*
X151360Y439447D01*
X151610Y439572D01*
X151819Y439739D01*
G01X153085Y440406D02*
X153377Y440697D01*
X153627Y440864D01*
X153960Y440947D01*
X154252Y440864D01*
X154460Y440697D01*
X154627Y440447D01*
X154669Y440156D01*
X154627Y439906D01*
X154460Y439656D01*
X154210Y439447D01*
X153919Y439364D01*
X153585Y439447D01*
X153294Y439697D01*
X153127Y440072D01*
X153085Y440489D01*
X153169Y441031D01*
X153294Y441322D01*
X153502Y441614D01*
X153794Y441822D01*
X154085Y441864D01*
X154377Y441781D01*
X154585Y441572D01*
G01X157477Y439364D02*
Y441864D01*
X155935Y440072D01*
X158019D01*
G01X160077Y441864D02*
X159744Y441781D01*
X159494Y441572D01*
X159327Y441322D01*
X159202Y440989D01*
X159160Y440614D01*
X159202Y440239D01*
X159327Y439906D01*
X159494Y439656D01*
X159744Y439447D01*
X160077Y439364D01*
X160410Y439447D01*
X160660Y439656D01*
X160827Y439906D01*
X160952Y440239D01*
X160994Y440614D01*
X160952Y440989D01*
X160827Y441322D01*
X160660Y441572D01*
X160410Y441781D01*
X160077Y441864D01*
G01X180350Y401500D02*
X180017Y401542D01*
X179725Y401708D01*
X179475Y401958D01*
X179308Y402250D01*
X179225Y402583D01*
Y402917D01*
X179308Y403250D01*
X179475Y403542D01*
X179725Y403792D01*
X180017Y403958D01*
X180350Y404000D01*
X180683Y403958D01*
X180975Y403792D01*
X181225Y403542D01*
X181392Y403250D01*
X181475Y402917D01*
Y402583D01*
X181392Y402250D01*
X181225Y401958D01*
X180975Y401708D01*
X180683Y401542D01*
X180350Y401500D01*
G01X180683Y402167D02*
X181183Y401500D01*
G01X182658Y403583D02*
X182908Y403833D01*
X183200Y403958D01*
X183533Y404000D01*
X183950Y403917D01*
X184242Y403708D01*
X184325Y403458D01*
X184283Y403208D01*
X184117Y403000D01*
X183283Y402583D01*
X182908Y402292D01*
X182658Y401875D01*
X182575Y401500D01*
X184325D01*
G01X185633Y401875D02*
X185883Y401667D01*
X186175Y401542D01*
X186550Y401500D01*
X186925Y401583D01*
X187217Y401750D01*
X187425Y402042D01*
X187467Y402375D01*
X187383Y402708D01*
X187175Y402917D01*
X186883Y403083D01*
X186592Y403125D01*
X186300Y403083D01*
X185925Y402917D01*
X186050Y404000D01*
X187175D01*
G01X188858Y402542D02*
X189150Y402833D01*
X189400Y403000D01*
X189733Y403083D01*
X190025Y403000D01*
X190233Y402833D01*
X190400Y402583D01*
X190442Y402292D01*
X190400Y402042D01*
X190233Y401792D01*
X189983Y401583D01*
X189692Y401500D01*
X189358Y401583D01*
X189067Y401833D01*
X188900Y402208D01*
X188858Y402625D01*
X188942Y403167D01*
X189067Y403458D01*
X189275Y403750D01*
X189567Y403958D01*
X189858Y404000D01*
X190150Y403917D01*
X190358Y403708D01*
G01X182092Y386407D02*
X196092D01*
G01X182092Y399407D02*
Y386407D01*
G01X196092Y399407D02*
X182092D01*
G01X181844Y426864D02*
Y429364D01*
X182885D01*
X183219Y429239D01*
X183427Y429072D01*
X183510Y428739D01*
X183427Y428406D01*
X183177Y428197D01*
X182885Y428072D01*
X181844D01*
G01X182885D02*
X183510Y426864D01*
G01X185777D02*
Y429364D01*
X185277Y428864D01*
G01Y426864D02*
X186277D01*
G01X188877D02*
Y429364D01*
X188377Y428864D01*
G01Y426864D02*
X189377D01*
G01X191185Y428947D02*
X191435Y429197D01*
X191727Y429322D01*
X192060Y429364D01*
X192477Y429281D01*
X192769Y429072D01*
X192852Y428822D01*
X192810Y428572D01*
X192644Y428364D01*
X191810Y427947D01*
X191435Y427656D01*
X191185Y427239D01*
X191102Y426864D01*
X192852D01*
G01X194160Y427364D02*
X194410Y427072D01*
X194744Y426906D01*
X195119Y426864D01*
X195452Y426906D01*
X195785Y427114D01*
X195994Y427364D01*
X196035Y427614D01*
X195952Y427906D01*
X195660Y428114D01*
X195369Y428197D01*
X194994D01*
G01X195369D02*
X195619Y428322D01*
X195827Y428531D01*
X195910Y428781D01*
X195827Y429031D01*
X195619Y429239D01*
X195244Y429364D01*
X194869Y429322D01*
X194494Y429156D01*
G01X195521Y431139D02*
X190321D01*
G01X195521Y438139D02*
X187721D01*
G01X182121Y431139D02*
X190821D01*
G01X182121Y438139D02*
Y431139D01*
G01X188521Y438139D02*
X182121D01*
G01X140067Y510892D02*
X139817Y511017D01*
X139525Y511100D01*
X139192D01*
X138817Y510975D01*
X138525Y510767D01*
X138317Y510517D01*
X138150Y510100D01*
X138108Y509725D01*
X138192Y509350D01*
X138317Y509100D01*
X138567Y508850D01*
X138858Y508683D01*
X139150Y508600D01*
X139442D01*
X139733Y508683D01*
X139983Y508808D01*
X140192Y508975D01*
G01X142250Y508600D02*
Y511100D01*
X141750Y510600D01*
G01Y508600D02*
X142750D01*
G01X145350D02*
X145642Y508642D01*
X145975Y508767D01*
X146183Y508975D01*
X146267Y509267D01*
X146183Y509558D01*
X145933Y509808D01*
X145558Y509933D01*
X145142D01*
X144892Y510017D01*
X144683Y510225D01*
X144600Y510517D01*
X144725Y510808D01*
X145017Y511017D01*
X145350Y511100D01*
X145683Y511017D01*
X145975Y510808D01*
X146100Y510517D01*
X146017Y510225D01*
X145808Y510017D01*
X145558Y509933D01*
X145142D01*
X144767Y509808D01*
X144517Y509558D01*
X144433Y509267D01*
X144517Y508975D01*
X144725Y508767D01*
X145058Y508642D01*
X145350Y508600D01*
G01X147533Y508975D02*
X147783Y508767D01*
X148075Y508642D01*
X148450Y508600D01*
X148825Y508683D01*
X149117Y508850D01*
X149325Y509142D01*
X149367Y509475D01*
X149283Y509808D01*
X149075Y510017D01*
X148783Y510183D01*
X148492Y510225D01*
X148200Y510183D01*
X147825Y510017D01*
X147950Y511100D01*
X149075D01*
G01X139876Y514728D02*
X139626Y514853D01*
X139334Y514936D01*
X139001D01*
X138626Y514811D01*
X138334Y514603D01*
X138126Y514353D01*
X137959Y513936D01*
X137917Y513561D01*
X138001Y513186D01*
X138126Y512936D01*
X138376Y512686D01*
X138667Y512519D01*
X138959Y512436D01*
X139251D01*
X139542Y512519D01*
X139792Y512644D01*
X140001Y512811D01*
G01X142059Y512436D02*
Y514936D01*
X141559Y514436D01*
G01Y512436D02*
X142559D01*
G01X145159D02*
X145451Y512478D01*
X145784Y512603D01*
X145992Y512811D01*
X146076Y513103D01*
X145992Y513394D01*
X145742Y513644D01*
X145367Y513769D01*
X144951D01*
X144701Y513853D01*
X144492Y514061D01*
X144409Y514353D01*
X144534Y514644D01*
X144826Y514853D01*
X145159Y514936D01*
X145492Y514853D01*
X145784Y514644D01*
X145909Y514353D01*
X145826Y514061D01*
X145617Y513853D01*
X145367Y513769D01*
X144951D01*
X144576Y513644D01*
X144326Y513394D01*
X144242Y513103D01*
X144326Y512811D01*
X144534Y512603D01*
X144867Y512478D01*
X145159Y512436D01*
G01X148759D02*
Y514936D01*
X147217Y513144D01*
X149301D01*
G01X175267Y544953D02*
X175017Y545078D01*
X174725Y545161D01*
X174392D01*
X174017Y545036D01*
X173725Y544828D01*
X173517Y544578D01*
X173350Y544161D01*
X173308Y543786D01*
X173392Y543411D01*
X173517Y543161D01*
X173767Y542911D01*
X174058Y542744D01*
X174350Y542661D01*
X174642D01*
X174933Y542744D01*
X175183Y542869D01*
X175392Y543036D01*
G01X176658Y544744D02*
X176908Y544994D01*
X177200Y545119D01*
X177533Y545161D01*
X177950Y545078D01*
X178242Y544869D01*
X178325Y544619D01*
X178283Y544369D01*
X178117Y544161D01*
X177283Y543744D01*
X176908Y543453D01*
X176658Y543036D01*
X176575Y542661D01*
X178325D01*
G01X180550Y545161D02*
X180217Y545078D01*
X179967Y544869D01*
X179800Y544619D01*
X179675Y544286D01*
X179633Y543911D01*
X179675Y543536D01*
X179800Y543203D01*
X179967Y542953D01*
X180217Y542744D01*
X180550Y542661D01*
X180883Y542744D01*
X181133Y542953D01*
X181300Y543203D01*
X181425Y543536D01*
X181467Y543911D01*
X181425Y544286D01*
X181300Y544619D01*
X181133Y544869D01*
X180883Y545078D01*
X180550Y545161D01*
G01X183567Y542661D02*
X183650Y543203D01*
X183775Y543661D01*
X183942Y544078D01*
X184150Y544536D01*
X184483Y545161D01*
X182817D01*
G01X161267Y554453D02*
X161017Y554578D01*
X160725Y554661D01*
X160392D01*
X160017Y554536D01*
X159725Y554328D01*
X159517Y554078D01*
X159350Y553661D01*
X159308Y553286D01*
X159392Y552911D01*
X159517Y552661D01*
X159767Y552411D01*
X160058Y552244D01*
X160350Y552161D01*
X160642D01*
X160933Y552244D01*
X161183Y552369D01*
X161392Y552536D01*
G01X162658Y554244D02*
X162908Y554494D01*
X163200Y554619D01*
X163533Y554661D01*
X163950Y554578D01*
X164242Y554369D01*
X164325Y554119D01*
X164283Y553869D01*
X164117Y553661D01*
X163283Y553244D01*
X162908Y552953D01*
X162658Y552536D01*
X162575Y552161D01*
X164325D01*
G01X166550Y554661D02*
X166217Y554578D01*
X165967Y554369D01*
X165800Y554119D01*
X165675Y553786D01*
X165633Y553411D01*
X165675Y553036D01*
X165800Y552703D01*
X165967Y552453D01*
X166217Y552244D01*
X166550Y552161D01*
X166883Y552244D01*
X167133Y552453D01*
X167300Y552703D01*
X167425Y553036D01*
X167467Y553411D01*
X167425Y553786D01*
X167300Y554119D01*
X167133Y554369D01*
X166883Y554578D01*
X166550Y554661D01*
G01X169650Y552161D02*
X169942Y552203D01*
X170275Y552328D01*
X170483Y552536D01*
X170567Y552828D01*
X170483Y553119D01*
X170233Y553369D01*
X169858Y553494D01*
X169442D01*
X169192Y553578D01*
X168983Y553786D01*
X168900Y554078D01*
X169025Y554369D01*
X169317Y554578D01*
X169650Y554661D01*
X169983Y554578D01*
X170275Y554369D01*
X170400Y554078D01*
X170317Y553786D01*
X170108Y553578D01*
X169858Y553494D01*
X169442D01*
X169067Y553369D01*
X168817Y553119D01*
X168733Y552828D01*
X168817Y552536D01*
X169025Y552328D01*
X169358Y552203D01*
X169650Y552161D01*
G01X173517Y538661D02*
Y541161D01*
X174558D01*
X174892Y541036D01*
X175100Y540869D01*
X175183Y540536D01*
X175100Y540203D01*
X174850Y539994D01*
X174558Y539869D01*
X173517D01*
G01X174558D02*
X175183Y538661D01*
G01X176533Y539161D02*
X176783Y538869D01*
X177117Y538703D01*
X177492Y538661D01*
X177825Y538703D01*
X178158Y538911D01*
X178367Y539161D01*
X178408Y539411D01*
X178325Y539703D01*
X178033Y539911D01*
X177742Y539994D01*
X177367D01*
G01X177742D02*
X177992Y540119D01*
X178200Y540328D01*
X178283Y540578D01*
X178200Y540828D01*
X177992Y541036D01*
X177617Y541161D01*
X177242Y541119D01*
X176867Y540953D01*
G01X180467Y538661D02*
X180550Y539203D01*
X180675Y539661D01*
X180842Y540078D01*
X181050Y540536D01*
X181383Y541161D01*
X179717D01*
G01X182858Y539703D02*
X183150Y539994D01*
X183400Y540161D01*
X183733Y540244D01*
X184025Y540161D01*
X184233Y539994D01*
X184400Y539744D01*
X184442Y539453D01*
X184400Y539203D01*
X184233Y538953D01*
X183983Y538744D01*
X183692Y538661D01*
X183358Y538744D01*
X183067Y538994D01*
X182900Y539369D01*
X182858Y539786D01*
X182942Y540328D01*
X183067Y540619D01*
X183275Y540911D01*
X183567Y541119D01*
X183858Y541161D01*
X184150Y541078D01*
X184358Y540869D01*
G01X186300Y545500D02*
Y541500D01*
X193700D01*
G01X174517Y511000D02*
Y513500D01*
X175558D01*
X175892Y513375D01*
X176100Y513208D01*
X176183Y512875D01*
X176100Y512542D01*
X175850Y512333D01*
X175558Y512208D01*
X174517D01*
G01X175558D02*
X176183Y511000D01*
G01X177533Y511500D02*
X177783Y511208D01*
X178117Y511042D01*
X178492Y511000D01*
X178825Y511042D01*
X179158Y511250D01*
X179367Y511500D01*
X179408Y511750D01*
X179325Y512042D01*
X179033Y512250D01*
X178742Y512333D01*
X178367D01*
G01X178742D02*
X178992Y512458D01*
X179200Y512667D01*
X179283Y512917D01*
X179200Y513167D01*
X178992Y513375D01*
X178617Y513500D01*
X178242Y513458D01*
X177867Y513292D01*
G01X181550Y511000D02*
X181842Y511042D01*
X182175Y511167D01*
X182383Y511375D01*
X182467Y511667D01*
X182383Y511958D01*
X182133Y512208D01*
X181758Y512333D01*
X181342D01*
X181092Y512417D01*
X180883Y512625D01*
X180800Y512917D01*
X180925Y513208D01*
X181217Y513417D01*
X181550Y513500D01*
X181883Y513417D01*
X182175Y513208D01*
X182300Y512917D01*
X182217Y512625D01*
X182008Y512417D01*
X181758Y512333D01*
X181342D01*
X180967Y512208D01*
X180717Y511958D01*
X180633Y511667D01*
X180717Y511375D01*
X180925Y511167D01*
X181258Y511042D01*
X181550Y511000D01*
G01X183733Y511500D02*
X183983Y511208D01*
X184317Y511042D01*
X184692Y511000D01*
X185025Y511042D01*
X185358Y511250D01*
X185567Y511500D01*
X185608Y511750D01*
X185525Y512042D01*
X185233Y512250D01*
X184942Y512333D01*
X184567D01*
G01X184942D02*
X185192Y512458D01*
X185400Y512667D01*
X185483Y512917D01*
X185400Y513167D01*
X185192Y513375D01*
X184817Y513500D01*
X184442Y513458D01*
X184067Y513292D01*
G01X178800Y520000D02*
Y516000D01*
X186200D01*
G01X159517Y548161D02*
Y550661D01*
X160558D01*
X160892Y550536D01*
X161100Y550369D01*
X161183Y550036D01*
X161100Y549703D01*
X160850Y549494D01*
X160558Y549369D01*
X159517D01*
G01X160558D02*
X161183Y548161D01*
G01X162533Y548661D02*
X162783Y548369D01*
X163117Y548203D01*
X163492Y548161D01*
X163825Y548203D01*
X164158Y548411D01*
X164367Y548661D01*
X164408Y548911D01*
X164325Y549203D01*
X164033Y549411D01*
X163742Y549494D01*
X163367D01*
G01X163742D02*
X163992Y549619D01*
X164200Y549828D01*
X164283Y550078D01*
X164200Y550328D01*
X163992Y550536D01*
X163617Y550661D01*
X163242Y550619D01*
X162867Y550453D01*
G01X166550Y548161D02*
X166842Y548203D01*
X167175Y548328D01*
X167383Y548536D01*
X167467Y548828D01*
X167383Y549119D01*
X167133Y549369D01*
X166758Y549494D01*
X166342D01*
X166092Y549578D01*
X165883Y549786D01*
X165800Y550078D01*
X165925Y550369D01*
X166217Y550578D01*
X166550Y550661D01*
X166883Y550578D01*
X167175Y550369D01*
X167300Y550078D01*
X167217Y549786D01*
X167008Y549578D01*
X166758Y549494D01*
X166342D01*
X165967Y549369D01*
X165717Y549119D01*
X165633Y548828D01*
X165717Y548536D01*
X165925Y548328D01*
X166258Y548203D01*
X166550Y548161D01*
G01X170150D02*
Y550661D01*
X168608Y548869D01*
X170692D01*
G01X186200Y547000D02*
Y551000D01*
X178800D01*
G01X180500Y522017D02*
X178000D01*
Y523058D01*
X178125Y523392D01*
X178292Y523600D01*
X178625Y523683D01*
X178958Y523600D01*
X179167Y523350D01*
X179292Y523058D01*
Y522017D01*
G01Y523058D02*
X180500Y523683D01*
G01X180000Y525033D02*
X180292Y525283D01*
X180458Y525617D01*
X180500Y525992D01*
X180458Y526325D01*
X180250Y526658D01*
X180000Y526867D01*
X179750Y526908D01*
X179458Y526825D01*
X179250Y526533D01*
X179167Y526242D01*
Y525867D01*
G01Y526242D02*
X179042Y526492D01*
X178833Y526700D01*
X178583Y526783D01*
X178333Y526700D01*
X178125Y526492D01*
X178000Y526117D01*
X178042Y525742D01*
X178208Y525367D01*
G01X180500Y529050D02*
X180458Y529342D01*
X180333Y529675D01*
X180125Y529883D01*
X179833Y529967D01*
X179542Y529883D01*
X179292Y529633D01*
X179167Y529258D01*
Y528842D01*
X179083Y528592D01*
X178875Y528383D01*
X178583Y528300D01*
X178292Y528425D01*
X178083Y528717D01*
X178000Y529050D01*
X178083Y529383D01*
X178292Y529675D01*
X178583Y529800D01*
X178875Y529717D01*
X179083Y529508D01*
X179167Y529258D01*
Y528842D01*
X179292Y528467D01*
X179542Y528217D01*
X179833Y528133D01*
X180125Y528217D01*
X180333Y528425D01*
X180458Y528758D01*
X180500Y529050D01*
G01X180125Y531233D02*
X180333Y531483D01*
X180458Y531775D01*
X180500Y532150D01*
X180417Y532525D01*
X180250Y532817D01*
X179958Y533025D01*
X179625Y533067D01*
X179292Y532983D01*
X179083Y532775D01*
X178917Y532483D01*
X178875Y532192D01*
X178917Y531900D01*
X179083Y531525D01*
X178000Y531650D01*
Y532775D01*
G01X182000Y520300D02*
X186000D01*
Y527700D01*
G01X198500Y521700D02*
X194500D01*
Y514300D01*
G01X182394Y486364D02*
Y488864D01*
X183435D01*
X183769Y488739D01*
X183977Y488572D01*
X184060Y488239D01*
X183977Y487906D01*
X183727Y487697D01*
X183435Y487572D01*
X182394D01*
G01X183435D02*
X184060Y486364D01*
G01X186327D02*
Y488864D01*
X185827Y488364D01*
G01Y486364D02*
X186827D01*
G01X189427D02*
Y488864D01*
X188927Y488364D01*
G01Y486364D02*
X189927D01*
G01X192527D02*
Y488864D01*
X192027Y488364D01*
G01Y486364D02*
X193027D01*
G01X194919Y486656D02*
X195210Y486447D01*
X195544Y486364D01*
X195877Y486447D01*
X196169Y486697D01*
X196377Y487072D01*
X196460Y487447D01*
Y487906D01*
X196377Y488281D01*
X196169Y488614D01*
X195919Y488781D01*
X195627Y488864D01*
X195294Y488781D01*
X195044Y488614D01*
X194877Y488364D01*
X194794Y488031D01*
X194877Y487739D01*
X195085Y487447D01*
X195335Y487281D01*
X195627Y487239D01*
X195960Y487322D01*
X196210Y487531D01*
X196460Y487906D01*
G01X182394Y477864D02*
Y480364D01*
X183435D01*
X183769Y480239D01*
X183977Y480072D01*
X184060Y479739D01*
X183977Y479406D01*
X183727Y479197D01*
X183435Y479072D01*
X182394D01*
G01X183435D02*
X184060Y477864D01*
G01X186327D02*
Y480364D01*
X185827Y479864D01*
G01Y477864D02*
X186827D01*
G01X189427D02*
Y480364D01*
X188927Y479864D01*
G01Y477864D02*
X189927D01*
G01X191735Y479947D02*
X191985Y480197D01*
X192277Y480322D01*
X192610Y480364D01*
X193027Y480281D01*
X193319Y480072D01*
X193402Y479822D01*
X193360Y479572D01*
X193194Y479364D01*
X192360Y478947D01*
X191985Y478656D01*
X191735Y478239D01*
X191652Y477864D01*
X193402D01*
G01X196127D02*
Y480364D01*
X194585Y478572D01*
X196669D01*
G01X165478Y479827D02*
Y482327D01*
X166519D01*
X166853Y482202D01*
X167061Y482035D01*
X167144Y481702D01*
X167061Y481369D01*
X166811Y481160D01*
X166519Y481035D01*
X165478D01*
G01X166519D02*
X167144Y479827D01*
G01X169411D02*
Y482327D01*
X168911Y481827D01*
G01Y479827D02*
X169911D01*
G01X172511D02*
Y482327D01*
X172011Y481827D01*
G01Y479827D02*
X173011D01*
G01X174819Y481910D02*
X175069Y482160D01*
X175361Y482285D01*
X175694Y482327D01*
X176111Y482244D01*
X176403Y482035D01*
X176486Y481785D01*
X176444Y481535D01*
X176278Y481327D01*
X175444Y480910D01*
X175069Y480619D01*
X174819Y480202D01*
X174736Y479827D01*
X176486D01*
G01X177919Y480869D02*
X178211Y481160D01*
X178461Y481327D01*
X178794Y481410D01*
X179086Y481327D01*
X179294Y481160D01*
X179461Y480910D01*
X179503Y480619D01*
X179461Y480369D01*
X179294Y480119D01*
X179044Y479910D01*
X178753Y479827D01*
X178419Y479910D01*
X178128Y480160D01*
X177961Y480535D01*
X177919Y480952D01*
X178003Y481494D01*
X178128Y481785D01*
X178336Y482077D01*
X178628Y482285D01*
X178919Y482327D01*
X179211Y482244D01*
X179419Y482035D01*
G01X165476Y483893D02*
Y486393D01*
X166517D01*
X166851Y486268D01*
X167059Y486101D01*
X167142Y485768D01*
X167059Y485435D01*
X166809Y485226D01*
X166517Y485101D01*
X165476D01*
G01X166517D02*
X167142Y483893D01*
G01X169409D02*
Y486393D01*
X168909Y485893D01*
G01Y483893D02*
X169909D01*
G01X172509D02*
Y486393D01*
X172009Y485893D01*
G01Y483893D02*
X173009D01*
G01X174817Y485976D02*
X175067Y486226D01*
X175359Y486351D01*
X175692Y486393D01*
X176109Y486310D01*
X176401Y486101D01*
X176484Y485851D01*
X176442Y485601D01*
X176276Y485393D01*
X175442Y484976D01*
X175067Y484685D01*
X174817Y484268D01*
X174734Y483893D01*
X176484D01*
G01X178709D02*
X179001Y483935D01*
X179334Y484060D01*
X179542Y484268D01*
X179626Y484560D01*
X179542Y484851D01*
X179292Y485101D01*
X178917Y485226D01*
X178501D01*
X178251Y485310D01*
X178042Y485518D01*
X177959Y485810D01*
X178084Y486101D01*
X178376Y486310D01*
X178709Y486393D01*
X179042Y486310D01*
X179334Y486101D01*
X179459Y485810D01*
X179376Y485518D01*
X179167Y485310D01*
X178917Y485226D01*
X178501D01*
X178126Y485101D01*
X177876Y484851D01*
X177792Y484560D01*
X177876Y484268D01*
X178084Y484060D01*
X178417Y483935D01*
X178709Y483893D01*
G01X184194Y484656D02*
X183944Y484781D01*
X183652Y484864D01*
X183319D01*
X182944Y484739D01*
X182652Y484531D01*
X182444Y484281D01*
X182277Y483864D01*
X182235Y483489D01*
X182319Y483114D01*
X182444Y482864D01*
X182694Y482614D01*
X182985Y482447D01*
X183277Y482364D01*
X183569D01*
X183860Y482447D01*
X184110Y482572D01*
X184319Y482739D01*
G01X185585Y483406D02*
X185877Y483697D01*
X186127Y483864D01*
X186460Y483947D01*
X186752Y483864D01*
X186960Y483697D01*
X187127Y483447D01*
X187169Y483156D01*
X187127Y482906D01*
X186960Y482656D01*
X186710Y482447D01*
X186419Y482364D01*
X186085Y482447D01*
X185794Y482697D01*
X185627Y483072D01*
X185585Y483489D01*
X185669Y484031D01*
X185794Y484322D01*
X186002Y484614D01*
X186294Y484822D01*
X186585Y484864D01*
X186877Y484781D01*
X187085Y484572D01*
G01X189977Y482364D02*
Y484864D01*
X188435Y483072D01*
X190519D01*
G01X192577Y482364D02*
Y484864D01*
X192077Y484364D01*
G01Y482364D02*
X193077D01*
G01X171700Y568400D02*
X190900D01*
Y579600D01*
X171700D01*
Y568400D01*
X172100D01*
G01X192000Y503983D02*
X189500D01*
Y504817D01*
X189625Y505150D01*
X189792Y505400D01*
X190042Y505608D01*
X190333Y505775D01*
X190750Y505817D01*
X191167Y505775D01*
X191458Y505608D01*
X191708Y505400D01*
X191875Y505150D01*
X192000Y504817D01*
Y503983D01*
G01Y508000D02*
X189500D01*
X190000Y507500D01*
G01X192000D02*
Y508500D01*
G01X191500Y510183D02*
X191792Y510433D01*
X191958Y510767D01*
X192000Y511142D01*
X191958Y511475D01*
X191750Y511808D01*
X191500Y512017D01*
X191250Y512058D01*
X190958Y511975D01*
X190750Y511683D01*
X190667Y511392D01*
Y511017D01*
G01Y511392D02*
X190542Y511642D01*
X190333Y511850D01*
X190083Y511933D01*
X189833Y511850D01*
X189625Y511642D01*
X189500Y511267D01*
X189542Y510892D01*
X189708Y510517D01*
G01X194000Y530500D02*
Y514400D01*
G01X187000Y530500D02*
X194000D01*
G01X187000Y514400D02*
Y530500D01*
G01X194000Y514400D02*
X187000D01*
G01X146267Y580453D02*
X146017Y580578D01*
X145725Y580661D01*
X145392D01*
X145017Y580536D01*
X144725Y580328D01*
X144517Y580078D01*
X144350Y579661D01*
X144308Y579286D01*
X144392Y578911D01*
X144517Y578661D01*
X144767Y578411D01*
X145058Y578244D01*
X145350Y578161D01*
X145642D01*
X145933Y578244D01*
X146183Y578369D01*
X146392Y578536D01*
G01X148450Y578161D02*
Y580661D01*
X147950Y580161D01*
G01Y578161D02*
X148950D01*
G01X151550D02*
X151842Y578203D01*
X152175Y578328D01*
X152383Y578536D01*
X152467Y578828D01*
X152383Y579119D01*
X152133Y579369D01*
X151758Y579494D01*
X151342D01*
X151092Y579578D01*
X150883Y579786D01*
X150800Y580078D01*
X150925Y580369D01*
X151217Y580578D01*
X151550Y580661D01*
X151883Y580578D01*
X152175Y580369D01*
X152300Y580078D01*
X152217Y579786D01*
X152008Y579578D01*
X151758Y579494D01*
X151342D01*
X150967Y579369D01*
X150717Y579119D01*
X150633Y578828D01*
X150717Y578536D01*
X150925Y578328D01*
X151258Y578203D01*
X151550Y578161D01*
G01X154650D02*
X154942Y578203D01*
X155275Y578328D01*
X155483Y578536D01*
X155567Y578828D01*
X155483Y579119D01*
X155233Y579369D01*
X154858Y579494D01*
X154442D01*
X154192Y579578D01*
X153983Y579786D01*
X153900Y580078D01*
X154025Y580369D01*
X154317Y580578D01*
X154650Y580661D01*
X154983Y580578D01*
X155275Y580369D01*
X155400Y580078D01*
X155317Y579786D01*
X155108Y579578D01*
X154858Y579494D01*
X154442D01*
X154067Y579369D01*
X153817Y579119D01*
X153733Y578828D01*
X153817Y578536D01*
X154025Y578328D01*
X154358Y578203D01*
X154650Y578161D01*
G01X144517Y582161D02*
Y584661D01*
X145558D01*
X145892Y584536D01*
X146100Y584369D01*
X146183Y584036D01*
X146100Y583703D01*
X145850Y583494D01*
X145558Y583369D01*
X144517D01*
G01X145558D02*
X146183Y582161D01*
G01X147533Y582661D02*
X147783Y582369D01*
X148117Y582203D01*
X148492Y582161D01*
X148825Y582203D01*
X149158Y582411D01*
X149367Y582661D01*
X149408Y582911D01*
X149325Y583203D01*
X149033Y583411D01*
X148742Y583494D01*
X148367D01*
G01X148742D02*
X148992Y583619D01*
X149200Y583828D01*
X149283Y584078D01*
X149200Y584328D01*
X148992Y584536D01*
X148617Y584661D01*
X148242Y584619D01*
X147867Y584453D01*
G01X150633Y582536D02*
X150883Y582328D01*
X151175Y582203D01*
X151550Y582161D01*
X151925Y582244D01*
X152217Y582411D01*
X152425Y582703D01*
X152467Y583036D01*
X152383Y583369D01*
X152175Y583578D01*
X151883Y583744D01*
X151592Y583786D01*
X151300Y583744D01*
X150925Y583578D01*
X151050Y584661D01*
X152175D01*
G01X154650Y582161D02*
Y584661D01*
X154150Y584161D01*
G01Y582161D02*
X155150D01*
G01X142700Y581000D02*
Y585000D01*
X135300D01*
G01X196067Y609292D02*
X195817Y609417D01*
X195525Y609500D01*
X195192D01*
X194817Y609375D01*
X194525Y609167D01*
X194317Y608917D01*
X194150Y608500D01*
X194108Y608125D01*
X194192Y607750D01*
X194317Y607500D01*
X194567Y607250D01*
X194858Y607083D01*
X195150Y607000D01*
X195442D01*
X195733Y607083D01*
X195983Y607208D01*
X196192Y607375D01*
G01X198250Y607000D02*
Y609500D01*
X197750Y609000D01*
G01Y607000D02*
X198750D01*
G01X200642Y607292D02*
X200933Y607083D01*
X201267Y607000D01*
X201600Y607083D01*
X201892Y607333D01*
X202100Y607708D01*
X202183Y608083D01*
Y608542D01*
X202100Y608917D01*
X201892Y609250D01*
X201642Y609417D01*
X201350Y609500D01*
X201017Y609417D01*
X200767Y609250D01*
X200600Y609000D01*
X200517Y608667D01*
X200600Y608375D01*
X200808Y608083D01*
X201058Y607917D01*
X201350Y607875D01*
X201683Y607958D01*
X201933Y608167D01*
X202183Y608542D01*
G01X203742Y607292D02*
X204033Y607083D01*
X204367Y607000D01*
X204700Y607083D01*
X204992Y607333D01*
X205200Y607708D01*
X205283Y608083D01*
Y608542D01*
X205200Y608917D01*
X204992Y609250D01*
X204742Y609417D01*
X204450Y609500D01*
X204117Y609417D01*
X203867Y609250D01*
X203700Y609000D01*
X203617Y608667D01*
X203700Y608375D01*
X203908Y608083D01*
X204158Y607917D01*
X204450Y607875D01*
X204783Y607958D01*
X205033Y608167D01*
X205283Y608542D01*
G01X132350Y615500D02*
Y613000D01*
G01X131392Y615500D02*
X133308D01*
G01X134617Y613000D02*
Y615500D01*
X135617D01*
X135950Y615375D01*
X136200Y615083D01*
X136283Y614750D01*
X136200Y614417D01*
X135992Y614167D01*
X135617Y614042D01*
X134617D01*
G01X138550Y613000D02*
X138842Y613042D01*
X139175Y613167D01*
X139383Y613375D01*
X139467Y613667D01*
X139383Y613958D01*
X139133Y614208D01*
X138758Y614333D01*
X138342D01*
X138092Y614417D01*
X137883Y614625D01*
X137800Y614917D01*
X137925Y615208D01*
X138217Y615417D01*
X138550Y615500D01*
X138883Y615417D01*
X139175Y615208D01*
X139300Y614917D01*
X139217Y614625D01*
X139008Y614417D01*
X138758Y614333D01*
X138342D01*
X137967Y614208D01*
X137717Y613958D01*
X137633Y613667D01*
X137717Y613375D01*
X137925Y613167D01*
X138258Y613042D01*
X138550Y613000D01*
G01X141650D02*
Y615500D01*
X141150Y615000D01*
G01Y613000D02*
X142150D01*
G01X163400Y571500D02*
X163067Y571542D01*
X162775Y571708D01*
X162525Y571958D01*
X162358Y572250D01*
X162275Y572583D01*
Y572917D01*
X162358Y573250D01*
X162525Y573542D01*
X162775Y573792D01*
X163067Y573958D01*
X163400Y574000D01*
X163733Y573958D01*
X164025Y573792D01*
X164275Y573542D01*
X164442Y573250D01*
X164525Y572917D01*
Y572583D01*
X164442Y572250D01*
X164275Y571958D01*
X164025Y571708D01*
X163733Y571542D01*
X163400Y571500D01*
G01X163733Y572167D02*
X164233Y571500D01*
G01X165583Y571875D02*
X165833Y571667D01*
X166125Y571542D01*
X166500Y571500D01*
X166875Y571583D01*
X167167Y571750D01*
X167375Y572042D01*
X167417Y572375D01*
X167333Y572708D01*
X167125Y572917D01*
X166833Y573083D01*
X166542Y573125D01*
X166250Y573083D01*
X165875Y572917D01*
X166000Y574000D01*
X167125D01*
G01X170100Y571500D02*
Y574000D01*
X168558Y572208D01*
X170642D01*
G01X171800Y576000D02*
X173900Y574200D01*
X171800Y572000D01*
G01X135517Y598500D02*
Y601000D01*
X136558D01*
X136892Y600875D01*
X137100Y600708D01*
X137183Y600375D01*
X137100Y600042D01*
X136850Y599833D01*
X136558Y599708D01*
X135517D01*
G01X136558D02*
X137183Y598500D01*
G01X138533Y599000D02*
X138783Y598708D01*
X139117Y598542D01*
X139492Y598500D01*
X139825Y598542D01*
X140158Y598750D01*
X140367Y599000D01*
X140408Y599250D01*
X140325Y599542D01*
X140033Y599750D01*
X139742Y599833D01*
X139367D01*
G01X139742D02*
X139992Y599958D01*
X140200Y600167D01*
X140283Y600417D01*
X140200Y600667D01*
X139992Y600875D01*
X139617Y601000D01*
X139242Y600958D01*
X138867Y600792D01*
G01X141633Y598875D02*
X141883Y598667D01*
X142175Y598542D01*
X142550Y598500D01*
X142925Y598583D01*
X143217Y598750D01*
X143425Y599042D01*
X143467Y599375D01*
X143383Y599708D01*
X143175Y599917D01*
X142883Y600083D01*
X142592Y600125D01*
X142300Y600083D01*
X141925Y599917D01*
X142050Y601000D01*
X143175D01*
G01X144733Y599000D02*
X144983Y598708D01*
X145317Y598542D01*
X145692Y598500D01*
X146025Y598542D01*
X146358Y598750D01*
X146567Y599000D01*
X146608Y599250D01*
X146525Y599542D01*
X146233Y599750D01*
X145942Y599833D01*
X145567D01*
G01X145942D02*
X146192Y599958D01*
X146400Y600167D01*
X146483Y600417D01*
X146400Y600667D01*
X146192Y600875D01*
X145817Y601000D01*
X145442Y600958D01*
X145067Y600792D01*
G01X196267Y604953D02*
X196017Y605078D01*
X195725Y605161D01*
X195392D01*
X195017Y605036D01*
X194725Y604828D01*
X194517Y604578D01*
X194350Y604161D01*
X194308Y603786D01*
X194392Y603411D01*
X194517Y603161D01*
X194767Y602911D01*
X195058Y602744D01*
X195350Y602661D01*
X195642D01*
X195933Y602744D01*
X196183Y602869D01*
X196392Y603036D01*
G01X197658Y604744D02*
X197908Y604994D01*
X198200Y605119D01*
X198533Y605161D01*
X198950Y605078D01*
X199242Y604869D01*
X199325Y604619D01*
X199283Y604369D01*
X199117Y604161D01*
X198283Y603744D01*
X197908Y603453D01*
X197658Y603036D01*
X197575Y602661D01*
X199325D01*
G01X201550Y605161D02*
X201217Y605078D01*
X200967Y604869D01*
X200800Y604619D01*
X200675Y604286D01*
X200633Y603911D01*
X200675Y603536D01*
X200800Y603203D01*
X200967Y602953D01*
X201217Y602744D01*
X201550Y602661D01*
X201883Y602744D01*
X202133Y602953D01*
X202300Y603203D01*
X202425Y603536D01*
X202467Y603911D01*
X202425Y604286D01*
X202300Y604619D01*
X202133Y604869D01*
X201883Y605078D01*
X201550Y605161D01*
G01X204650D02*
X204317Y605078D01*
X204067Y604869D01*
X203900Y604619D01*
X203775Y604286D01*
X203733Y603911D01*
X203775Y603536D01*
X203900Y603203D01*
X204067Y602953D01*
X204317Y602744D01*
X204650Y602661D01*
X204983Y602744D01*
X205233Y602953D01*
X205400Y603203D01*
X205525Y603536D01*
X205567Y603911D01*
X205525Y604286D01*
X205400Y604619D01*
X205233Y604869D01*
X204983Y605078D01*
X204650Y605161D01*
G01X194200Y582500D02*
X199700D01*
G01X194200Y574500D02*
Y582500D01*
G01X199700Y574500D02*
X194200D01*
G01X194517Y611000D02*
Y613500D01*
X195558D01*
X195892Y613375D01*
X196100Y613208D01*
X196183Y612875D01*
X196100Y612542D01*
X195850Y612333D01*
X195558Y612208D01*
X194517D01*
G01X195558D02*
X196183Y611000D01*
G01X197533Y611500D02*
X197783Y611208D01*
X198117Y611042D01*
X198492Y611000D01*
X198825Y611042D01*
X199158Y611250D01*
X199367Y611500D01*
X199408Y611750D01*
X199325Y612042D01*
X199033Y612250D01*
X198742Y612333D01*
X198367D01*
G01X198742D02*
X198992Y612458D01*
X199200Y612667D01*
X199283Y612917D01*
X199200Y613167D01*
X198992Y613375D01*
X198617Y613500D01*
X198242Y613458D01*
X197867Y613292D01*
G01X201467Y611000D02*
X201550Y611542D01*
X201675Y612000D01*
X201842Y612417D01*
X202050Y612875D01*
X202383Y613500D01*
X200717D01*
G01X204650D02*
X204317Y613417D01*
X204067Y613208D01*
X203900Y612958D01*
X203775Y612625D01*
X203733Y612250D01*
X203775Y611875D01*
X203900Y611542D01*
X204067Y611292D01*
X204317Y611083D01*
X204650Y611000D01*
X204983Y611083D01*
X205233Y611292D01*
X205400Y611542D01*
X205525Y611875D01*
X205567Y612250D01*
X205525Y612625D01*
X205400Y612958D01*
X205233Y613208D01*
X204983Y613417D01*
X204650Y613500D01*
G01X189700Y589000D02*
Y597000D01*
X207300D01*
Y589000D01*
X189700D01*
G01X177267Y601292D02*
X177017Y601417D01*
X176725Y601500D01*
X176392D01*
X176017Y601375D01*
X175725Y601167D01*
X175517Y600917D01*
X175350Y600500D01*
X175308Y600125D01*
X175392Y599750D01*
X175517Y599500D01*
X175767Y599250D01*
X176058Y599083D01*
X176350Y599000D01*
X176642D01*
X176933Y599083D01*
X177183Y599208D01*
X177392Y599375D01*
G01X178658Y601083D02*
X178908Y601333D01*
X179200Y601458D01*
X179533Y601500D01*
X179950Y601417D01*
X180242Y601208D01*
X180325Y600958D01*
X180283Y600708D01*
X180117Y600500D01*
X179283Y600083D01*
X178908Y599792D01*
X178658Y599375D01*
X178575Y599000D01*
X180325D01*
G01X182550Y601500D02*
X182217Y601417D01*
X181967Y601208D01*
X181800Y600958D01*
X181675Y600625D01*
X181633Y600250D01*
X181675Y599875D01*
X181800Y599542D01*
X181967Y599292D01*
X182217Y599083D01*
X182550Y599000D01*
X182883Y599083D01*
X183133Y599292D01*
X183300Y599542D01*
X183425Y599875D01*
X183467Y600250D01*
X183425Y600625D01*
X183300Y600958D01*
X183133Y601208D01*
X182883Y601417D01*
X182550Y601500D01*
G01X184733Y599500D02*
X184983Y599208D01*
X185317Y599042D01*
X185692Y599000D01*
X186025Y599042D01*
X186358Y599250D01*
X186567Y599500D01*
X186608Y599750D01*
X186525Y600042D01*
X186233Y600250D01*
X185942Y600333D01*
X185567D01*
G01X185942D02*
X186192Y600458D01*
X186400Y600667D01*
X186483Y600917D01*
X186400Y601167D01*
X186192Y601375D01*
X185817Y601500D01*
X185442Y601458D01*
X185067Y601292D01*
G01X189017Y721000D02*
Y718500D01*
X190683D01*
G01X193783D02*
X192117D01*
Y721000D01*
X193783D01*
G01X193117Y719792D02*
X192117D01*
G01X195133Y718500D02*
Y721000D01*
X195967D01*
X196300Y720875D01*
X196550Y720708D01*
X196758Y720458D01*
X196925Y720167D01*
X196967Y719750D01*
X196925Y719333D01*
X196758Y719042D01*
X196550Y718792D01*
X196300Y718625D01*
X195967Y718500D01*
X195133D01*
G01X198358Y720583D02*
X198608Y720833D01*
X198900Y720958D01*
X199233Y721000D01*
X199650Y720917D01*
X199942Y720708D01*
X200025Y720458D01*
X199983Y720208D01*
X199817Y720000D01*
X198983Y719583D01*
X198608Y719292D01*
X198358Y718875D01*
X198275Y718500D01*
X200025D01*
G01X189891Y704636D02*
Y715836D01*
X198691D01*
Y704636D01*
X189891D01*
G01X175474Y825691D02*
Y828191D01*
X176515D01*
X176849Y828066D01*
X177057Y827899D01*
X177140Y827566D01*
X177057Y827233D01*
X176807Y827024D01*
X176515Y826899D01*
X175474D01*
G01X176515D02*
X177140Y825691D01*
G01X179407D02*
Y828191D01*
X178907Y827691D01*
G01Y825691D02*
X179907D01*
G01X181590Y826066D02*
X181840Y825858D01*
X182132Y825733D01*
X182507Y825691D01*
X182882Y825774D01*
X183174Y825941D01*
X183382Y826233D01*
X183424Y826566D01*
X183340Y826899D01*
X183132Y827108D01*
X182840Y827274D01*
X182549Y827316D01*
X182257Y827274D01*
X181882Y827108D01*
X182007Y828191D01*
X183132D01*
G01X185524Y825691D02*
X185607Y826233D01*
X185732Y826691D01*
X185899Y827108D01*
X186107Y827566D01*
X186440Y828191D01*
X184774D01*
G01X171608Y837918D02*
Y833918D01*
X179008D01*
G01X186125Y853659D02*
Y857659D01*
X178725D01*
G01X192500Y852617D02*
X190000D01*
Y853658D01*
X190125Y853992D01*
X190292Y854200D01*
X190625Y854283D01*
X190958Y854200D01*
X191167Y853950D01*
X191292Y853658D01*
Y852617D01*
G01Y853658D02*
X192500Y854283D01*
G01X190417Y855758D02*
X190167Y856008D01*
X190042Y856300D01*
X190000Y856633D01*
X190083Y857050D01*
X190292Y857342D01*
X190542Y857425D01*
X190792Y857383D01*
X191000Y857217D01*
X191417Y856383D01*
X191708Y856008D01*
X192125Y855758D01*
X192500Y855675D01*
Y857425D01*
G01X190417Y858858D02*
X190167Y859108D01*
X190042Y859400D01*
X190000Y859733D01*
X190083Y860150D01*
X190292Y860442D01*
X190542Y860525D01*
X190792Y860483D01*
X191000Y860317D01*
X191417Y859483D01*
X191708Y859108D01*
X192125Y858858D01*
X192500Y858775D01*
Y860525D01*
G01X190000Y862750D02*
X190083Y862417D01*
X190292Y862167D01*
X190542Y862000D01*
X190875Y861875D01*
X191250Y861833D01*
X191625Y861875D01*
X191958Y862000D01*
X192208Y862167D01*
X192417Y862417D01*
X192500Y862750D01*
X192417Y863083D01*
X192208Y863333D01*
X191958Y863500D01*
X191625Y863625D01*
X191250Y863667D01*
X190875Y863625D01*
X190542Y863500D01*
X190292Y863333D01*
X190083Y863083D01*
X190000Y862750D01*
G01X196500Y852617D02*
X194000D01*
Y853658D01*
X194125Y853992D01*
X194292Y854200D01*
X194625Y854283D01*
X194958Y854200D01*
X195167Y853950D01*
X195292Y853658D01*
Y852617D01*
G01Y853658D02*
X196500Y854283D01*
G01X194417Y855758D02*
X194167Y856008D01*
X194042Y856300D01*
X194000Y856633D01*
X194083Y857050D01*
X194292Y857342D01*
X194542Y857425D01*
X194792Y857383D01*
X195000Y857217D01*
X195417Y856383D01*
X195708Y856008D01*
X196125Y855758D01*
X196500Y855675D01*
Y857425D01*
G01X194417Y858858D02*
X194167Y859108D01*
X194042Y859400D01*
X194000Y859733D01*
X194083Y860150D01*
X194292Y860442D01*
X194542Y860525D01*
X194792Y860483D01*
X195000Y860317D01*
X195417Y859483D01*
X195708Y859108D01*
X196125Y858858D01*
X196500Y858775D01*
Y860525D01*
G01Y862750D02*
X194000D01*
X194500Y862250D01*
G01X196500D02*
Y863250D01*
G01X183039Y833947D02*
X182706Y833989D01*
X182414Y834155D01*
X182164Y834405D01*
X181997Y834697D01*
X181914Y835030D01*
Y835364D01*
X181997Y835697D01*
X182164Y835989D01*
X182414Y836239D01*
X182706Y836405D01*
X183039Y836447D01*
X183372Y836405D01*
X183664Y836239D01*
X183914Y835989D01*
X184081Y835697D01*
X184164Y835364D01*
Y835030D01*
X184081Y834697D01*
X183914Y834405D01*
X183664Y834155D01*
X183372Y833989D01*
X183039Y833947D01*
G01X183372Y834614D02*
X183872Y833947D01*
G01X185347Y836030D02*
X185597Y836280D01*
X185889Y836405D01*
X186222Y836447D01*
X186639Y836364D01*
X186931Y836155D01*
X187014Y835905D01*
X186972Y835655D01*
X186806Y835447D01*
X185972Y835030D01*
X185597Y834739D01*
X185347Y834322D01*
X185264Y833947D01*
X187014D01*
G01X188447Y836030D02*
X188697Y836280D01*
X188989Y836405D01*
X189322Y836447D01*
X189739Y836364D01*
X190031Y836155D01*
X190114Y835905D01*
X190072Y835655D01*
X189906Y835447D01*
X189072Y835030D01*
X188697Y834739D01*
X188447Y834322D01*
X188364Y833947D01*
X190114D01*
G01X192339Y836447D02*
X192006Y836364D01*
X191756Y836155D01*
X191589Y835905D01*
X191464Y835572D01*
X191422Y835197D01*
X191464Y834822D01*
X191589Y834489D01*
X191756Y834239D01*
X192006Y834030D01*
X192339Y833947D01*
X192672Y834030D01*
X192922Y834239D01*
X193089Y834489D01*
X193214Y834822D01*
X193256Y835197D01*
X193214Y835572D01*
X193089Y835905D01*
X192922Y836155D01*
X192672Y836364D01*
X192339Y836447D01*
G01X186800Y838500D02*
Y852500D01*
G01X173800Y838500D02*
X186800D01*
G01X173800Y852500D02*
Y838500D01*
G01X186800Y852500D02*
X173800D01*
G01X155750Y849800D02*
X155417Y849842D01*
X155125Y850008D01*
X154875Y850258D01*
X154708Y850550D01*
X154625Y850883D01*
Y851217D01*
X154708Y851550D01*
X154875Y851842D01*
X155125Y852092D01*
X155417Y852258D01*
X155750Y852300D01*
X156083Y852258D01*
X156375Y852092D01*
X156625Y851842D01*
X156792Y851550D01*
X156875Y851217D01*
Y850883D01*
X156792Y850550D01*
X156625Y850258D01*
X156375Y850008D01*
X156083Y849842D01*
X155750Y849800D01*
G01X156083Y850467D02*
X156583Y849800D01*
G01X158058Y851883D02*
X158308Y852133D01*
X158600Y852258D01*
X158933Y852300D01*
X159350Y852217D01*
X159642Y852008D01*
X159725Y851758D01*
X159683Y851508D01*
X159517Y851300D01*
X158683Y850883D01*
X158308Y850592D01*
X158058Y850175D01*
X157975Y849800D01*
X159725D01*
G01X162450D02*
Y852300D01*
X160908Y850508D01*
X162992D01*
G01X165550Y849800D02*
Y852300D01*
X164008Y850508D01*
X166092D01*
G01X157092Y834407D02*
X171092D01*
G01X157092Y847407D02*
Y834407D01*
G01X171092Y847407D02*
X157092D01*
G01X171092Y834407D02*
Y847407D01*
G01X117223Y878515D02*
X116973Y878640D01*
X116681Y878723D01*
X116348D01*
X115973Y878598D01*
X115681Y878390D01*
X115473Y878140D01*
X115306Y877723D01*
X115264Y877348D01*
X115348Y876973D01*
X115473Y876723D01*
X115723Y876473D01*
X116014Y876306D01*
X116306Y876223D01*
X116598D01*
X116889Y876306D01*
X117139Y876431D01*
X117348Y876598D01*
G01X118614Y877265D02*
X118906Y877556D01*
X119156Y877723D01*
X119489Y877806D01*
X119781Y877723D01*
X119989Y877556D01*
X120156Y877306D01*
X120198Y877015D01*
X120156Y876765D01*
X119989Y876515D01*
X119739Y876306D01*
X119448Y876223D01*
X119114Y876306D01*
X118823Y876556D01*
X118656Y876931D01*
X118614Y877348D01*
X118698Y877890D01*
X118823Y878181D01*
X119031Y878473D01*
X119323Y878681D01*
X119614Y878723D01*
X119906Y878640D01*
X120114Y878431D01*
G01X121714Y878306D02*
X121964Y878556D01*
X122256Y878681D01*
X122589Y878723D01*
X123006Y878640D01*
X123298Y878431D01*
X123381Y878181D01*
X123339Y877931D01*
X123173Y877723D01*
X122339Y877306D01*
X121964Y877015D01*
X121714Y876598D01*
X121631Y876223D01*
X123381D01*
G01X124689Y876598D02*
X124939Y876390D01*
X125231Y876265D01*
X125606Y876223D01*
X125981Y876306D01*
X126273Y876473D01*
X126481Y876765D01*
X126523Y877098D01*
X126439Y877431D01*
X126231Y877640D01*
X125939Y877806D01*
X125648Y877848D01*
X125356Y877806D01*
X124981Y877640D01*
X125106Y878723D01*
X126231D01*
G01X117195Y873488D02*
X116945Y873613D01*
X116653Y873696D01*
X116320D01*
X115945Y873571D01*
X115653Y873363D01*
X115445Y873113D01*
X115278Y872696D01*
X115236Y872321D01*
X115320Y871946D01*
X115445Y871696D01*
X115695Y871446D01*
X115986Y871279D01*
X116278Y871196D01*
X116570D01*
X116861Y871279D01*
X117111Y871404D01*
X117320Y871571D01*
G01X118586Y872238D02*
X118878Y872529D01*
X119128Y872696D01*
X119461Y872779D01*
X119753Y872696D01*
X119961Y872529D01*
X120128Y872279D01*
X120170Y871988D01*
X120128Y871738D01*
X119961Y871488D01*
X119711Y871279D01*
X119420Y871196D01*
X119086Y871279D01*
X118795Y871529D01*
X118628Y871904D01*
X118586Y872321D01*
X118670Y872863D01*
X118795Y873154D01*
X119003Y873446D01*
X119295Y873654D01*
X119586Y873696D01*
X119878Y873613D01*
X120086Y873404D01*
G01X121686Y873279D02*
X121936Y873529D01*
X122228Y873654D01*
X122561Y873696D01*
X122978Y873613D01*
X123270Y873404D01*
X123353Y873154D01*
X123311Y872904D01*
X123145Y872696D01*
X122311Y872279D01*
X121936Y871988D01*
X121686Y871571D01*
X121603Y871196D01*
X123353D01*
G01X124786Y872238D02*
X125078Y872529D01*
X125328Y872696D01*
X125661Y872779D01*
X125953Y872696D01*
X126161Y872529D01*
X126328Y872279D01*
X126370Y871988D01*
X126328Y871738D01*
X126161Y871488D01*
X125911Y871279D01*
X125620Y871196D01*
X125286Y871279D01*
X124995Y871529D01*
X124828Y871904D01*
X124786Y872321D01*
X124870Y872863D01*
X124995Y873154D01*
X125203Y873446D01*
X125495Y873654D01*
X125786Y873696D01*
X126078Y873613D01*
X126286Y873404D01*
G01X100467Y921500D02*
Y924000D01*
X101508D01*
X101842Y923875D01*
X102050Y923708D01*
X102133Y923375D01*
X102050Y923042D01*
X101800Y922833D01*
X101508Y922708D01*
X100467D01*
G01X101508D02*
X102133Y921500D01*
G01X104400D02*
Y924000D01*
X103900Y923500D01*
G01Y921500D02*
X104900D01*
G01X107500Y924000D02*
X107167Y923917D01*
X106917Y923708D01*
X106750Y923458D01*
X106625Y923125D01*
X106583Y922750D01*
X106625Y922375D01*
X106750Y922042D01*
X106917Y921792D01*
X107167Y921583D01*
X107500Y921500D01*
X107833Y921583D01*
X108083Y921792D01*
X108250Y922042D01*
X108375Y922375D01*
X108417Y922750D01*
X108375Y923125D01*
X108250Y923458D01*
X108083Y923708D01*
X107833Y923917D01*
X107500Y924000D01*
G01X109892Y921792D02*
X110183Y921583D01*
X110517Y921500D01*
X110850Y921583D01*
X111142Y921833D01*
X111350Y922208D01*
X111433Y922583D01*
Y923042D01*
X111350Y923417D01*
X111142Y923750D01*
X110892Y923917D01*
X110600Y924000D01*
X110267Y923917D01*
X110017Y923750D01*
X109850Y923500D01*
X109767Y923167D01*
X109850Y922875D01*
X110058Y922583D01*
X110308Y922417D01*
X110600Y922375D01*
X110933Y922458D01*
X111183Y922667D01*
X111433Y923042D01*
G01X113617Y921500D02*
X113700Y922042D01*
X113825Y922500D01*
X113992Y922917D01*
X114200Y923375D01*
X114533Y924000D01*
X112867D01*
G01X104263Y917725D02*
X100263D01*
Y910325D01*
G01X105967Y915500D02*
Y918000D01*
X107008D01*
X107342Y917875D01*
X107550Y917708D01*
X107633Y917375D01*
X107550Y917042D01*
X107300Y916833D01*
X107008Y916708D01*
X105967D01*
G01X107008D02*
X107633Y915500D01*
G01X109900D02*
Y918000D01*
X109400Y917500D01*
G01Y915500D02*
X110400D01*
G01X113000Y918000D02*
X112667Y917917D01*
X112417Y917708D01*
X112250Y917458D01*
X112125Y917125D01*
X112083Y916750D01*
X112125Y916375D01*
X112250Y916042D01*
X112417Y915792D01*
X112667Y915583D01*
X113000Y915500D01*
X113333Y915583D01*
X113583Y915792D01*
X113750Y916042D01*
X113875Y916375D01*
X113917Y916750D01*
X113875Y917125D01*
X113750Y917458D01*
X113583Y917708D01*
X113333Y917917D01*
X113000Y918000D01*
G01X115392Y915792D02*
X115683Y915583D01*
X116017Y915500D01*
X116350Y915583D01*
X116642Y915833D01*
X116850Y916208D01*
X116933Y916583D01*
Y917042D01*
X116850Y917417D01*
X116642Y917750D01*
X116392Y917917D01*
X116100Y918000D01*
X115767Y917917D01*
X115517Y917750D01*
X115350Y917500D01*
X115267Y917167D01*
X115350Y916875D01*
X115558Y916583D01*
X115808Y916417D01*
X116100Y916375D01*
X116433Y916458D01*
X116683Y916667D01*
X116933Y917042D01*
G01X118492Y915792D02*
X118783Y915583D01*
X119117Y915500D01*
X119450Y915583D01*
X119742Y915833D01*
X119950Y916208D01*
X120033Y916583D01*
Y917042D01*
X119950Y917417D01*
X119742Y917750D01*
X119492Y917917D01*
X119200Y918000D01*
X118867Y917917D01*
X118617Y917750D01*
X118450Y917500D01*
X118367Y917167D01*
X118450Y916875D01*
X118658Y916583D01*
X118908Y916417D01*
X119200Y916375D01*
X119533Y916458D01*
X119783Y916667D01*
X120033Y917042D01*
G01X111763Y909925D02*
Y913925D01*
X104363D01*
G01X118967Y902500D02*
Y905000D01*
X120008D01*
X120342Y904875D01*
X120550Y904708D01*
X120633Y904375D01*
X120550Y904042D01*
X120300Y903833D01*
X120008Y903708D01*
X118967D01*
G01X120008D02*
X120633Y902500D01*
G01X122900D02*
Y905000D01*
X122400Y904500D01*
G01Y902500D02*
X123400D01*
G01X126000D02*
Y905000D01*
X125500Y904500D01*
G01Y902500D02*
X126500D01*
G01X129100Y905000D02*
X128767Y904917D01*
X128517Y904708D01*
X128350Y904458D01*
X128225Y904125D01*
X128183Y903750D01*
X128225Y903375D01*
X128350Y903042D01*
X128517Y902792D01*
X128767Y902583D01*
X129100Y902500D01*
X129433Y902583D01*
X129683Y902792D01*
X129850Y903042D01*
X129975Y903375D01*
X130017Y903750D01*
X129975Y904125D01*
X129850Y904458D01*
X129683Y904708D01*
X129433Y904917D01*
X129100Y905000D01*
G01X131408Y904583D02*
X131658Y904833D01*
X131950Y904958D01*
X132283Y905000D01*
X132700Y904917D01*
X132992Y904708D01*
X133075Y904458D01*
X133033Y904208D01*
X132867Y904000D01*
X132033Y903583D01*
X131658Y903292D01*
X131408Y902875D01*
X131325Y902500D01*
X133075D01*
G01X111722Y901550D02*
Y905550D01*
X104322D01*
G01X177017Y859000D02*
Y861500D01*
X178058D01*
X178392Y861375D01*
X178600Y861208D01*
X178683Y860875D01*
X178600Y860542D01*
X178350Y860333D01*
X178058Y860208D01*
X177017D01*
G01X178058D02*
X178683Y859000D01*
G01X180950D02*
Y861500D01*
X180450Y861000D01*
G01Y859000D02*
X181450D01*
G01X183133Y859375D02*
X183383Y859167D01*
X183675Y859042D01*
X184050Y859000D01*
X184425Y859083D01*
X184717Y859250D01*
X184925Y859542D01*
X184967Y859875D01*
X184883Y860208D01*
X184675Y860417D01*
X184383Y860583D01*
X184092Y860625D01*
X183800Y860583D01*
X183425Y860417D01*
X183550Y861500D01*
X184675D01*
G01X186358Y860042D02*
X186650Y860333D01*
X186900Y860500D01*
X187233Y860583D01*
X187525Y860500D01*
X187733Y860333D01*
X187900Y860083D01*
X187942Y859792D01*
X187900Y859542D01*
X187733Y859292D01*
X187483Y859083D01*
X187192Y859000D01*
X186858Y859083D01*
X186567Y859333D01*
X186400Y859708D01*
X186358Y860125D01*
X186442Y860667D01*
X186567Y860958D01*
X186775Y861250D01*
X187067Y861458D01*
X187358Y861500D01*
X187650Y861417D01*
X187858Y861208D01*
G01X120300Y913000D02*
Y910500D01*
G01X119342Y913000D02*
X121258D01*
G01X122567Y910500D02*
Y913000D01*
X123567D01*
X123900Y912875D01*
X124150Y912583D01*
X124233Y912250D01*
X124150Y911917D01*
X123942Y911667D01*
X123567Y911542D01*
X122567D01*
G01X125708Y912583D02*
X125958Y912833D01*
X126250Y912958D01*
X126583Y913000D01*
X127000Y912917D01*
X127292Y912708D01*
X127375Y912458D01*
X127333Y912208D01*
X127167Y912000D01*
X126333Y911583D01*
X125958Y911292D01*
X125708Y910875D01*
X125625Y910500D01*
X127375D01*
G01X129600Y913000D02*
X129267Y912917D01*
X129017Y912708D01*
X128850Y912458D01*
X128725Y912125D01*
X128683Y911750D01*
X128725Y911375D01*
X128850Y911042D01*
X129017Y910792D01*
X129267Y910583D01*
X129600Y910500D01*
X129933Y910583D01*
X130183Y910792D01*
X130350Y911042D01*
X130475Y911375D01*
X130517Y911750D01*
X130475Y912125D01*
X130350Y912458D01*
X130183Y912708D01*
X129933Y912917D01*
X129600Y913000D01*
G01X131908Y912583D02*
X132158Y912833D01*
X132450Y912958D01*
X132783Y913000D01*
X133200Y912917D01*
X133492Y912708D01*
X133575Y912458D01*
X133533Y912208D01*
X133367Y912000D01*
X132533Y911583D01*
X132158Y911292D01*
X131908Y910875D01*
X131825Y910500D01*
X133575D01*
G01X139667Y962692D02*
X139417Y962817D01*
X139125Y962900D01*
X138792D01*
X138417Y962775D01*
X138125Y962567D01*
X137917Y962317D01*
X137750Y961900D01*
X137708Y961525D01*
X137792Y961150D01*
X137917Y960900D01*
X138167Y960650D01*
X138458Y960483D01*
X138750Y960400D01*
X139042D01*
X139333Y960483D01*
X139583Y960608D01*
X139792Y960775D01*
G01X142350Y960400D02*
Y962900D01*
X140808Y961108D01*
X142892D01*
G01X144242Y960692D02*
X144533Y960483D01*
X144867Y960400D01*
X145200Y960483D01*
X145492Y960733D01*
X145700Y961108D01*
X145783Y961483D01*
Y961942D01*
X145700Y962317D01*
X145492Y962650D01*
X145242Y962817D01*
X144950Y962900D01*
X144617Y962817D01*
X144367Y962650D01*
X144200Y962400D01*
X144117Y962067D01*
X144200Y961775D01*
X144408Y961483D01*
X144658Y961317D01*
X144950Y961275D01*
X145283Y961358D01*
X145533Y961567D01*
X145783Y961942D01*
G01X147967Y960400D02*
X148050Y960942D01*
X148175Y961400D01*
X148342Y961817D01*
X148550Y962275D01*
X148883Y962900D01*
X147217D01*
G01X139667Y966692D02*
X139417Y966817D01*
X139125Y966900D01*
X138792D01*
X138417Y966775D01*
X138125Y966567D01*
X137917Y966317D01*
X137750Y965900D01*
X137708Y965525D01*
X137792Y965150D01*
X137917Y964900D01*
X138167Y964650D01*
X138458Y964483D01*
X138750Y964400D01*
X139042D01*
X139333Y964483D01*
X139583Y964608D01*
X139792Y964775D01*
G01X142350Y964400D02*
Y966900D01*
X140808Y965108D01*
X142892D01*
G01X144242Y964692D02*
X144533Y964483D01*
X144867Y964400D01*
X145200Y964483D01*
X145492Y964733D01*
X145700Y965108D01*
X145783Y965483D01*
Y965942D01*
X145700Y966317D01*
X145492Y966650D01*
X145242Y966817D01*
X144950Y966900D01*
X144617Y966817D01*
X144367Y966650D01*
X144200Y966400D01*
X144117Y966067D01*
X144200Y965775D01*
X144408Y965483D01*
X144658Y965317D01*
X144950Y965275D01*
X145283Y965358D01*
X145533Y965567D01*
X145783Y965942D01*
G01X147258Y965442D02*
X147550Y965733D01*
X147800Y965900D01*
X148133Y965983D01*
X148425Y965900D01*
X148633Y965733D01*
X148800Y965483D01*
X148842Y965192D01*
X148800Y964942D01*
X148633Y964692D01*
X148383Y964483D01*
X148092Y964400D01*
X147758Y964483D01*
X147467Y964733D01*
X147300Y965108D01*
X147258Y965525D01*
X147342Y966067D01*
X147467Y966358D01*
X147675Y966650D01*
X147967Y966858D01*
X148258Y966900D01*
X148550Y966817D01*
X148758Y966608D01*
G01X145767Y1032792D02*
X145517Y1032917D01*
X145225Y1033000D01*
X144892D01*
X144517Y1032875D01*
X144225Y1032667D01*
X144017Y1032417D01*
X143850Y1032000D01*
X143808Y1031625D01*
X143892Y1031250D01*
X144017Y1031000D01*
X144267Y1030750D01*
X144558Y1030583D01*
X144850Y1030500D01*
X145142D01*
X145433Y1030583D01*
X145683Y1030708D01*
X145892Y1030875D01*
G01X147033D02*
X147283Y1030667D01*
X147575Y1030542D01*
X147950Y1030500D01*
X148325Y1030583D01*
X148617Y1030750D01*
X148825Y1031042D01*
X148867Y1031375D01*
X148783Y1031708D01*
X148575Y1031917D01*
X148283Y1032083D01*
X147992Y1032125D01*
X147700Y1032083D01*
X147325Y1031917D01*
X147450Y1033000D01*
X148575D01*
G01X151050D02*
X150717Y1032917D01*
X150467Y1032708D01*
X150300Y1032458D01*
X150175Y1032125D01*
X150133Y1031750D01*
X150175Y1031375D01*
X150300Y1031042D01*
X150467Y1030792D01*
X150717Y1030583D01*
X151050Y1030500D01*
X151383Y1030583D01*
X151633Y1030792D01*
X151800Y1031042D01*
X151925Y1031375D01*
X151967Y1031750D01*
X151925Y1032125D01*
X151800Y1032458D01*
X151633Y1032708D01*
X151383Y1032917D01*
X151050Y1033000D01*
G01X153233Y1030875D02*
X153483Y1030667D01*
X153775Y1030542D01*
X154150Y1030500D01*
X154525Y1030583D01*
X154817Y1030750D01*
X155025Y1031042D01*
X155067Y1031375D01*
X154983Y1031708D01*
X154775Y1031917D01*
X154483Y1032083D01*
X154192Y1032125D01*
X153900Y1032083D01*
X153525Y1031917D01*
X153650Y1033000D01*
X154775D01*
G01X167817Y1007792D02*
X167567Y1007917D01*
X167275Y1008000D01*
X166942D01*
X166567Y1007875D01*
X166275Y1007667D01*
X166067Y1007417D01*
X165900Y1007000D01*
X165858Y1006625D01*
X165942Y1006250D01*
X166067Y1006000D01*
X166317Y1005750D01*
X166608Y1005583D01*
X166900Y1005500D01*
X167192D01*
X167483Y1005583D01*
X167733Y1005708D01*
X167942Y1005875D01*
G01X169083D02*
X169333Y1005667D01*
X169625Y1005542D01*
X170000Y1005500D01*
X170375Y1005583D01*
X170667Y1005750D01*
X170875Y1006042D01*
X170917Y1006375D01*
X170833Y1006708D01*
X170625Y1006917D01*
X170333Y1007083D01*
X170042Y1007125D01*
X169750Y1007083D01*
X169375Y1006917D01*
X169500Y1008000D01*
X170625D01*
G01X172308Y1007583D02*
X172558Y1007833D01*
X172850Y1007958D01*
X173183Y1008000D01*
X173600Y1007917D01*
X173892Y1007708D01*
X173975Y1007458D01*
X173933Y1007208D01*
X173767Y1007000D01*
X172933Y1006583D01*
X172558Y1006292D01*
X172308Y1005875D01*
X172225Y1005500D01*
X173975D01*
G01X175317Y998792D02*
X175067Y998917D01*
X174775Y999000D01*
X174442D01*
X174067Y998875D01*
X173775Y998667D01*
X173567Y998417D01*
X173400Y998000D01*
X173358Y997625D01*
X173442Y997250D01*
X173567Y997000D01*
X173817Y996750D01*
X174108Y996583D01*
X174400Y996500D01*
X174692D01*
X174983Y996583D01*
X175233Y996708D01*
X175442Y996875D01*
G01X176583D02*
X176833Y996667D01*
X177125Y996542D01*
X177500Y996500D01*
X177875Y996583D01*
X178167Y996750D01*
X178375Y997042D01*
X178417Y997375D01*
X178333Y997708D01*
X178125Y997917D01*
X177833Y998083D01*
X177542Y998125D01*
X177250Y998083D01*
X176875Y997917D01*
X177000Y999000D01*
X178125D01*
G01X180600Y996500D02*
Y999000D01*
X180100Y998500D01*
G01Y996500D02*
X181100D01*
G01X144017Y1034500D02*
Y1037000D01*
X145058D01*
X145392Y1036875D01*
X145600Y1036708D01*
X145683Y1036375D01*
X145600Y1036042D01*
X145350Y1035833D01*
X145058Y1035708D01*
X144017D01*
G01X145058D02*
X145683Y1034500D01*
G01X147950D02*
X148242Y1034542D01*
X148575Y1034667D01*
X148783Y1034875D01*
X148867Y1035167D01*
X148783Y1035458D01*
X148533Y1035708D01*
X148158Y1035833D01*
X147742D01*
X147492Y1035917D01*
X147283Y1036125D01*
X147200Y1036417D01*
X147325Y1036708D01*
X147617Y1036917D01*
X147950Y1037000D01*
X148283Y1036917D01*
X148575Y1036708D01*
X148700Y1036417D01*
X148617Y1036125D01*
X148408Y1035917D01*
X148158Y1035833D01*
X147742D01*
X147367Y1035708D01*
X147117Y1035458D01*
X147033Y1035167D01*
X147117Y1034875D01*
X147325Y1034667D01*
X147658Y1034542D01*
X147950Y1034500D01*
G01X150342Y1034792D02*
X150633Y1034583D01*
X150967Y1034500D01*
X151300Y1034583D01*
X151592Y1034833D01*
X151800Y1035208D01*
X151883Y1035583D01*
Y1036042D01*
X151800Y1036417D01*
X151592Y1036750D01*
X151342Y1036917D01*
X151050Y1037000D01*
X150717Y1036917D01*
X150467Y1036750D01*
X150300Y1036500D01*
X150217Y1036167D01*
X150300Y1035875D01*
X150508Y1035583D01*
X150758Y1035417D01*
X151050Y1035375D01*
X151383Y1035458D01*
X151633Y1035667D01*
X151883Y1036042D01*
G01X154150Y1034500D02*
X154442Y1034542D01*
X154775Y1034667D01*
X154983Y1034875D01*
X155067Y1035167D01*
X154983Y1035458D01*
X154733Y1035708D01*
X154358Y1035833D01*
X153942D01*
X153692Y1035917D01*
X153483Y1036125D01*
X153400Y1036417D01*
X153525Y1036708D01*
X153817Y1036917D01*
X154150Y1037000D01*
X154483Y1036917D01*
X154775Y1036708D01*
X154900Y1036417D01*
X154817Y1036125D01*
X154608Y1035917D01*
X154358Y1035833D01*
X153942D01*
X153567Y1035708D01*
X153317Y1035458D01*
X153233Y1035167D01*
X153317Y1034875D01*
X153525Y1034667D01*
X153858Y1034542D01*
X154150Y1034500D01*
G01X142700Y1034000D02*
Y1038000D01*
X135300D01*
G01X175517Y964500D02*
Y967000D01*
X176558D01*
X176892Y966875D01*
X177100Y966708D01*
X177183Y966375D01*
X177100Y966042D01*
X176850Y965833D01*
X176558Y965708D01*
X175517D01*
G01X176558D02*
X177183Y964500D01*
G01X179450D02*
Y967000D01*
X178950Y966500D01*
G01Y964500D02*
X179950D01*
G01X182550D02*
X182842Y964542D01*
X183175Y964667D01*
X183383Y964875D01*
X183467Y965167D01*
X183383Y965458D01*
X183133Y965708D01*
X182758Y965833D01*
X182342D01*
X182092Y965917D01*
X181883Y966125D01*
X181800Y966417D01*
X181925Y966708D01*
X182217Y966917D01*
X182550Y967000D01*
X182883Y966917D01*
X183175Y966708D01*
X183300Y966417D01*
X183217Y966125D01*
X183008Y965917D01*
X182758Y965833D01*
X182342D01*
X181967Y965708D01*
X181717Y965458D01*
X181633Y965167D01*
X181717Y964875D01*
X181925Y964667D01*
X182258Y964542D01*
X182550Y964500D01*
G01X186150D02*
Y967000D01*
X184608Y965208D01*
X186692D01*
G01X179300Y973000D02*
Y969000D01*
X186700D01*
G01X166017Y1001161D02*
Y1003661D01*
X167058D01*
X167392Y1003536D01*
X167600Y1003369D01*
X167683Y1003036D01*
X167600Y1002703D01*
X167350Y1002494D01*
X167058Y1002369D01*
X166017D01*
G01X167058D02*
X167683Y1001161D01*
G01X169950D02*
Y1003661D01*
X169450Y1003161D01*
G01Y1001161D02*
X170450D01*
G01X173050D02*
X173342Y1001203D01*
X173675Y1001328D01*
X173883Y1001536D01*
X173967Y1001828D01*
X173883Y1002119D01*
X173633Y1002369D01*
X173258Y1002494D01*
X172842D01*
X172592Y1002578D01*
X172383Y1002786D01*
X172300Y1003078D01*
X172425Y1003369D01*
X172717Y1003578D01*
X173050Y1003661D01*
X173383Y1003578D01*
X173675Y1003369D01*
X173800Y1003078D01*
X173717Y1002786D01*
X173508Y1002578D01*
X173258Y1002494D01*
X172842D01*
X172467Y1002369D01*
X172217Y1002119D01*
X172133Y1001828D01*
X172217Y1001536D01*
X172425Y1001328D01*
X172758Y1001203D01*
X173050Y1001161D01*
G01X175233Y1001536D02*
X175483Y1001328D01*
X175775Y1001203D01*
X176150Y1001161D01*
X176525Y1001244D01*
X176817Y1001411D01*
X177025Y1001703D01*
X177067Y1002036D01*
X176983Y1002369D01*
X176775Y1002578D01*
X176483Y1002744D01*
X176192Y1002786D01*
X175900Y1002744D01*
X175525Y1002578D01*
X175650Y1003661D01*
X176775D01*
G01X186700Y1000000D02*
Y1004000D01*
X179300D01*
G01X176000Y974017D02*
X173500D01*
Y975058D01*
X173625Y975392D01*
X173792Y975600D01*
X174125Y975683D01*
X174458Y975600D01*
X174667Y975350D01*
X174792Y975058D01*
Y974017D01*
G01Y975058D02*
X176000Y975683D01*
G01Y977950D02*
X173500D01*
X174000Y977450D01*
G01X176000D02*
Y978450D01*
G01Y981050D02*
X175958Y981342D01*
X175833Y981675D01*
X175625Y981883D01*
X175333Y981967D01*
X175042Y981883D01*
X174792Y981633D01*
X174667Y981258D01*
Y980842D01*
X174583Y980592D01*
X174375Y980383D01*
X174083Y980300D01*
X173792Y980425D01*
X173583Y980717D01*
X173500Y981050D01*
X173583Y981383D01*
X173792Y981675D01*
X174083Y981800D01*
X174375Y981717D01*
X174583Y981508D01*
X174667Y981258D01*
Y980842D01*
X174792Y980467D01*
X175042Y980217D01*
X175333Y980133D01*
X175625Y980217D01*
X175833Y980425D01*
X175958Y980758D01*
X176000Y981050D01*
G01X174958Y983358D02*
X174667Y983650D01*
X174500Y983900D01*
X174417Y984233D01*
X174500Y984525D01*
X174667Y984733D01*
X174917Y984900D01*
X175208Y984942D01*
X175458Y984900D01*
X175708Y984733D01*
X175917Y984483D01*
X176000Y984192D01*
X175917Y983858D01*
X175667Y983567D01*
X175292Y983400D01*
X174875Y983358D01*
X174333Y983442D01*
X174042Y983567D01*
X173750Y983775D01*
X173542Y984067D01*
X173500Y984358D01*
X173583Y984650D01*
X173792Y984858D01*
G01X182500Y973300D02*
X186500D01*
Y980700D01*
G01X174017Y992161D02*
Y994661D01*
X175058D01*
X175392Y994536D01*
X175600Y994369D01*
X175683Y994036D01*
X175600Y993703D01*
X175350Y993494D01*
X175058Y993369D01*
X174017D01*
G01X175058D02*
X175683Y992161D01*
G01X177950D02*
Y994661D01*
X177450Y994161D01*
G01Y992161D02*
X178450D01*
G01X180967D02*
X181050Y992703D01*
X181175Y993161D01*
X181342Y993578D01*
X181550Y994036D01*
X181883Y994661D01*
X180217D01*
G01X183442Y992453D02*
X183733Y992244D01*
X184067Y992161D01*
X184400Y992244D01*
X184692Y992494D01*
X184900Y992869D01*
X184983Y993244D01*
Y993703D01*
X184900Y994078D01*
X184692Y994411D01*
X184442Y994578D01*
X184150Y994661D01*
X183817Y994578D01*
X183567Y994411D01*
X183400Y994161D01*
X183317Y993828D01*
X183400Y993536D01*
X183608Y993244D01*
X183858Y993078D01*
X184150Y993036D01*
X184483Y993119D01*
X184733Y993328D01*
X184983Y993703D01*
G01X186800Y998500D02*
Y994500D01*
X194200D01*
G01X166450Y1026000D02*
X166117Y1026042D01*
X165825Y1026208D01*
X165575Y1026458D01*
X165408Y1026750D01*
X165325Y1027083D01*
Y1027417D01*
X165408Y1027750D01*
X165575Y1028042D01*
X165825Y1028292D01*
X166117Y1028458D01*
X166450Y1028500D01*
X166783Y1028458D01*
X167075Y1028292D01*
X167325Y1028042D01*
X167492Y1027750D01*
X167575Y1027417D01*
Y1027083D01*
X167492Y1026750D01*
X167325Y1026458D01*
X167075Y1026208D01*
X166783Y1026042D01*
X166450Y1026000D01*
G01X166783Y1026667D02*
X167283Y1026000D01*
G01X170050D02*
Y1028500D01*
X168508Y1026708D01*
X170592D01*
G01X172300Y1029000D02*
X174400Y1027200D01*
X172300Y1025000D01*
G01X172200Y1021400D02*
X191400D01*
Y1032600D01*
X172200D01*
Y1021400D01*
X172600D01*
G01X194700Y1035500D02*
X200200D01*
G01X194700Y1027500D02*
Y1035500D01*
G01X200200Y1027500D02*
X194700D01*
G01X192500Y961033D02*
X190000D01*
Y961867D01*
X190125Y962200D01*
X190292Y962450D01*
X190542Y962658D01*
X190833Y962825D01*
X191250Y962867D01*
X191667Y962825D01*
X191958Y962658D01*
X192208Y962450D01*
X192375Y962200D01*
X192500Y961867D01*
Y961033D01*
G01Y965050D02*
X190000D01*
X190500Y964550D01*
G01X192500D02*
Y965550D01*
G01X194500Y983500D02*
Y967400D01*
G01X187500Y983500D02*
X194500D01*
G01X187500Y967400D02*
Y983500D01*
G01X194500Y967400D02*
X187500D01*
G01X190200Y1042000D02*
Y1050000D01*
X207800D01*
Y1042000D01*
X190200D01*
G01X101825Y1115000D02*
Y1117500D01*
G01X103575D02*
Y1115000D01*
G01Y1116250D02*
X101825D01*
G01X104883Y1115000D02*
Y1117500D01*
X105717D01*
X106050Y1117375D01*
X106300Y1117208D01*
X106508Y1116958D01*
X106675Y1116667D01*
X106717Y1116250D01*
X106675Y1115833D01*
X106508Y1115542D01*
X106300Y1115292D01*
X106050Y1115125D01*
X105717Y1115000D01*
X104883D01*
G01X107983D02*
Y1117500D01*
X108817D01*
X109150Y1117375D01*
X109400Y1117208D01*
X109608Y1116958D01*
X109775Y1116667D01*
X109817Y1116250D01*
X109775Y1115833D01*
X109608Y1115542D01*
X109400Y1115292D01*
X109150Y1115125D01*
X108817Y1115000D01*
X107983D01*
G01X111125Y1115333D02*
X111458Y1115125D01*
X111833Y1115000D01*
X112167D01*
X112500Y1115125D01*
X112750Y1115333D01*
X112875Y1115625D01*
X112792Y1115917D01*
X112583Y1116167D01*
X112208Y1116333D01*
X111708Y1116417D01*
X111417Y1116583D01*
X111292Y1116875D01*
X111375Y1117167D01*
X111583Y1117375D01*
X111875Y1117500D01*
X112167D01*
X112458Y1117417D01*
X112708Y1117208D01*
G01X114058Y1115000D02*
X115100Y1117500D01*
X116142Y1115000D01*
G01X115767Y1115875D02*
X114433D01*
G01X117325Y1115333D02*
X117658Y1115125D01*
X118033Y1115000D01*
X118367D01*
X118700Y1115125D01*
X118950Y1115333D01*
X119075Y1115625D01*
X118992Y1115917D01*
X118783Y1116167D01*
X118408Y1116333D01*
X117908Y1116417D01*
X117617Y1116583D01*
X117492Y1116875D01*
X117575Y1117167D01*
X117783Y1117375D01*
X118075Y1117500D01*
X118367D01*
X118658Y1117417D01*
X118908Y1117208D01*
G01X121300Y1117500D02*
X120967Y1117417D01*
X120717Y1117208D01*
X120550Y1116958D01*
X120425Y1116625D01*
X120383Y1116250D01*
X120425Y1115875D01*
X120550Y1115542D01*
X120717Y1115292D01*
X120967Y1115083D01*
X121300Y1115000D01*
X121633Y1115083D01*
X121883Y1115292D01*
X122050Y1115542D01*
X122175Y1115875D01*
X122217Y1116250D01*
X122175Y1116625D01*
X122050Y1116958D01*
X121883Y1117208D01*
X121633Y1117417D01*
X121300Y1117500D01*
G01X131800Y1068500D02*
Y1066000D01*
G01X130842Y1068500D02*
X132758D01*
G01X134067Y1066000D02*
Y1068500D01*
X135067D01*
X135400Y1068375D01*
X135650Y1068083D01*
X135733Y1067750D01*
X135650Y1067417D01*
X135442Y1067167D01*
X135067Y1067042D01*
X134067D01*
G01X137208Y1068083D02*
X137458Y1068333D01*
X137750Y1068458D01*
X138083Y1068500D01*
X138500Y1068417D01*
X138792Y1068208D01*
X138875Y1067958D01*
X138833Y1067708D01*
X138667Y1067500D01*
X137833Y1067083D01*
X137458Y1066792D01*
X137208Y1066375D01*
X137125Y1066000D01*
X138875D01*
G01X141100Y1068500D02*
X140767Y1068417D01*
X140517Y1068208D01*
X140350Y1067958D01*
X140225Y1067625D01*
X140183Y1067250D01*
X140225Y1066875D01*
X140350Y1066542D01*
X140517Y1066292D01*
X140767Y1066083D01*
X141100Y1066000D01*
X141433Y1066083D01*
X141683Y1066292D01*
X141850Y1066542D01*
X141975Y1066875D01*
X142017Y1067250D01*
X141975Y1067625D01*
X141850Y1067958D01*
X141683Y1068208D01*
X141433Y1068417D01*
X141100Y1068500D01*
G01X144200Y1066000D02*
Y1068500D01*
X143700Y1068000D01*
G01Y1066000D02*
X144700D01*
G01X135017Y1051500D02*
Y1054000D01*
X136058D01*
X136392Y1053875D01*
X136600Y1053708D01*
X136683Y1053375D01*
X136600Y1053042D01*
X136350Y1052833D01*
X136058Y1052708D01*
X135017D01*
G01X136058D02*
X136683Y1051500D01*
G01X138242Y1051792D02*
X138533Y1051583D01*
X138867Y1051500D01*
X139200Y1051583D01*
X139492Y1051833D01*
X139700Y1052208D01*
X139783Y1052583D01*
Y1053042D01*
X139700Y1053417D01*
X139492Y1053750D01*
X139242Y1053917D01*
X138950Y1054000D01*
X138617Y1053917D01*
X138367Y1053750D01*
X138200Y1053500D01*
X138117Y1053167D01*
X138200Y1052875D01*
X138408Y1052583D01*
X138658Y1052417D01*
X138950Y1052375D01*
X139283Y1052458D01*
X139533Y1052667D01*
X139783Y1053042D01*
G01X142050Y1054000D02*
X141717Y1053917D01*
X141467Y1053708D01*
X141300Y1053458D01*
X141175Y1053125D01*
X141133Y1052750D01*
X141175Y1052375D01*
X141300Y1052042D01*
X141467Y1051792D01*
X141717Y1051583D01*
X142050Y1051500D01*
X142383Y1051583D01*
X142633Y1051792D01*
X142800Y1052042D01*
X142925Y1052375D01*
X142967Y1052750D01*
X142925Y1053125D01*
X142800Y1053458D01*
X142633Y1053708D01*
X142383Y1053917D01*
X142050Y1054000D01*
G01X144358Y1053583D02*
X144608Y1053833D01*
X144900Y1053958D01*
X145233Y1054000D01*
X145650Y1053917D01*
X145942Y1053708D01*
X146025Y1053458D01*
X145983Y1053208D01*
X145817Y1053000D01*
X144983Y1052583D01*
X144608Y1052292D01*
X144358Y1051875D01*
X144275Y1051500D01*
X146025D01*
G01X181317Y1054792D02*
X181067Y1054917D01*
X180775Y1055000D01*
X180442D01*
X180067Y1054875D01*
X179775Y1054667D01*
X179567Y1054417D01*
X179400Y1054000D01*
X179358Y1053625D01*
X179442Y1053250D01*
X179567Y1053000D01*
X179817Y1052750D01*
X180108Y1052583D01*
X180400Y1052500D01*
X180692D01*
X180983Y1052583D01*
X181233Y1052708D01*
X181442Y1052875D01*
G01X184000Y1052500D02*
Y1055000D01*
X182458Y1053208D01*
X184542D01*
G01X186600Y1052500D02*
X186892Y1052542D01*
X187225Y1052667D01*
X187433Y1052875D01*
X187517Y1053167D01*
X187433Y1053458D01*
X187183Y1053708D01*
X186808Y1053833D01*
X186392D01*
X186142Y1053917D01*
X185933Y1054125D01*
X185850Y1054417D01*
X185975Y1054708D01*
X186267Y1054917D01*
X186600Y1055000D01*
X186933Y1054917D01*
X187225Y1054708D01*
X187350Y1054417D01*
X187267Y1054125D01*
X187058Y1053917D01*
X186808Y1053833D01*
X186392D01*
X186017Y1053708D01*
X185767Y1053458D01*
X185683Y1053167D01*
X185767Y1052875D01*
X185975Y1052667D01*
X186308Y1052542D01*
X186600Y1052500D01*
G01X125694Y1430267D02*
X125569Y1430017D01*
X125486Y1429725D01*
Y1429392D01*
X125611Y1429017D01*
X125819Y1428725D01*
X126069Y1428517D01*
X126486Y1428350D01*
X126861Y1428308D01*
X127236Y1428392D01*
X127486Y1428517D01*
X127736Y1428767D01*
X127903Y1429058D01*
X127986Y1429350D01*
Y1429642D01*
X127903Y1429933D01*
X127778Y1430183D01*
X127611Y1430392D01*
G01Y1431533D02*
X127819Y1431783D01*
X127944Y1432075D01*
X127986Y1432450D01*
X127903Y1432825D01*
X127736Y1433117D01*
X127444Y1433325D01*
X127111Y1433367D01*
X126778Y1433283D01*
X126569Y1433075D01*
X126403Y1432783D01*
X126361Y1432492D01*
X126403Y1432200D01*
X126569Y1431825D01*
X125486Y1431950D01*
Y1433075D01*
G01X125903Y1434758D02*
X125653Y1435008D01*
X125528Y1435300D01*
X125486Y1435633D01*
X125569Y1436050D01*
X125778Y1436342D01*
X126028Y1436425D01*
X126278Y1436383D01*
X126486Y1436217D01*
X126903Y1435383D01*
X127194Y1435008D01*
X127611Y1434758D01*
X127986Y1434675D01*
Y1436425D01*
G01X127486Y1437733D02*
X127778Y1437983D01*
X127944Y1438317D01*
X127986Y1438692D01*
X127944Y1439025D01*
X127736Y1439358D01*
X127486Y1439567D01*
X127236Y1439608D01*
X126944Y1439525D01*
X126736Y1439233D01*
X126653Y1438942D01*
Y1438567D01*
G01Y1438942D02*
X126528Y1439192D01*
X126319Y1439400D01*
X126069Y1439483D01*
X125819Y1439400D01*
X125611Y1439192D01*
X125486Y1438817D01*
X125528Y1438442D01*
X125694Y1438067D01*
G01X185082Y1395167D02*
X184957Y1394917D01*
X184874Y1394625D01*
Y1394292D01*
X184999Y1393917D01*
X185207Y1393625D01*
X185457Y1393417D01*
X185874Y1393250D01*
X186249Y1393208D01*
X186624Y1393292D01*
X186874Y1393417D01*
X187124Y1393667D01*
X187291Y1393958D01*
X187374Y1394250D01*
Y1394542D01*
X187291Y1394833D01*
X187166Y1395083D01*
X186999Y1395292D01*
G01X186874Y1396433D02*
X187166Y1396683D01*
X187332Y1397017D01*
X187374Y1397392D01*
X187332Y1397725D01*
X187124Y1398058D01*
X186874Y1398267D01*
X186624Y1398308D01*
X186332Y1398225D01*
X186124Y1397933D01*
X186041Y1397642D01*
Y1397267D01*
G01Y1397642D02*
X185916Y1397892D01*
X185707Y1398100D01*
X185457Y1398183D01*
X185207Y1398100D01*
X184999Y1397892D01*
X184874Y1397517D01*
X184916Y1397142D01*
X185082Y1396767D01*
G01X186332Y1399658D02*
X186041Y1399950D01*
X185874Y1400200D01*
X185791Y1400533D01*
X185874Y1400825D01*
X186041Y1401033D01*
X186291Y1401200D01*
X186582Y1401242D01*
X186832Y1401200D01*
X187082Y1401033D01*
X187291Y1400783D01*
X187374Y1400492D01*
X187291Y1400158D01*
X187041Y1399867D01*
X186666Y1399700D01*
X186249Y1399658D01*
X185707Y1399742D01*
X185416Y1399867D01*
X185124Y1400075D01*
X184916Y1400367D01*
X184874Y1400658D01*
X184957Y1400950D01*
X185166Y1401158D01*
G01X186999Y1402633D02*
X187207Y1402883D01*
X187332Y1403175D01*
X187374Y1403550D01*
X187291Y1403925D01*
X187124Y1404217D01*
X186832Y1404425D01*
X186499Y1404467D01*
X186166Y1404383D01*
X185957Y1404175D01*
X185791Y1403883D01*
X185749Y1403592D01*
X185791Y1403300D01*
X185957Y1402925D01*
X184874Y1403050D01*
Y1404175D01*
G01X155297Y1403672D02*
X155172Y1403422D01*
X155089Y1403130D01*
Y1402797D01*
X155214Y1402422D01*
X155422Y1402130D01*
X155672Y1401922D01*
X156089Y1401755D01*
X156464Y1401713D01*
X156839Y1401797D01*
X157089Y1401922D01*
X157339Y1402172D01*
X157506Y1402463D01*
X157589Y1402755D01*
Y1403047D01*
X157506Y1403338D01*
X157381Y1403588D01*
X157214Y1403797D01*
G01X156547Y1405063D02*
X156256Y1405355D01*
X156089Y1405605D01*
X156006Y1405938D01*
X156089Y1406230D01*
X156256Y1406438D01*
X156506Y1406605D01*
X156797Y1406647D01*
X157047Y1406605D01*
X157297Y1406438D01*
X157506Y1406188D01*
X157589Y1405897D01*
X157506Y1405563D01*
X157256Y1405272D01*
X156881Y1405105D01*
X156464Y1405063D01*
X155922Y1405147D01*
X155631Y1405272D01*
X155339Y1405480D01*
X155131Y1405772D01*
X155089Y1406063D01*
X155172Y1406355D01*
X155381Y1406563D01*
G01X156547Y1408163D02*
X156256Y1408455D01*
X156089Y1408705D01*
X156006Y1409038D01*
X156089Y1409330D01*
X156256Y1409538D01*
X156506Y1409705D01*
X156797Y1409747D01*
X157047Y1409705D01*
X157297Y1409538D01*
X157506Y1409288D01*
X157589Y1408997D01*
X157506Y1408663D01*
X157256Y1408372D01*
X156881Y1408205D01*
X156464Y1408163D01*
X155922Y1408247D01*
X155631Y1408372D01*
X155339Y1408580D01*
X155131Y1408872D01*
X155089Y1409163D01*
X155172Y1409455D01*
X155381Y1409663D01*
G01X122386Y1428417D02*
X119886D01*
Y1429458D01*
X120011Y1429792D01*
X120178Y1430000D01*
X120511Y1430083D01*
X120844Y1430000D01*
X121053Y1429750D01*
X121178Y1429458D01*
Y1428417D01*
G01Y1429458D02*
X122386Y1430083D01*
G01X122094Y1431642D02*
X122303Y1431933D01*
X122386Y1432267D01*
X122303Y1432600D01*
X122053Y1432892D01*
X121678Y1433100D01*
X121303Y1433183D01*
X120844D01*
X120469Y1433100D01*
X120136Y1432892D01*
X119969Y1432642D01*
X119886Y1432350D01*
X119969Y1432017D01*
X120136Y1431767D01*
X120386Y1431600D01*
X120719Y1431517D01*
X121011Y1431600D01*
X121303Y1431808D01*
X121469Y1432058D01*
X121511Y1432350D01*
X121428Y1432683D01*
X121219Y1432933D01*
X120844Y1433183D01*
G01X120303Y1434658D02*
X120053Y1434908D01*
X119928Y1435200D01*
X119886Y1435533D01*
X119969Y1435950D01*
X120178Y1436242D01*
X120428Y1436325D01*
X120678Y1436283D01*
X120886Y1436117D01*
X121303Y1435283D01*
X121594Y1434908D01*
X122011Y1434658D01*
X122386Y1434575D01*
Y1436325D01*
G01Y1438467D02*
X121844Y1438550D01*
X121386Y1438675D01*
X120969Y1438842D01*
X120511Y1439050D01*
X119886Y1439383D01*
Y1437717D01*
G01X153261Y1411737D02*
Y1414237D01*
X154302D01*
X154636Y1414112D01*
X154844Y1413945D01*
X154927Y1413612D01*
X154844Y1413279D01*
X154594Y1413070D01*
X154302Y1412945D01*
X153261D01*
G01X154302D02*
X154927Y1411737D01*
G01X156486Y1412029D02*
X156777Y1411820D01*
X157111Y1411737D01*
X157444Y1411820D01*
X157736Y1412070D01*
X157944Y1412445D01*
X158027Y1412820D01*
Y1413279D01*
X157944Y1413654D01*
X157736Y1413987D01*
X157486Y1414154D01*
X157194Y1414237D01*
X156861Y1414154D01*
X156611Y1413987D01*
X156444Y1413737D01*
X156361Y1413404D01*
X156444Y1413112D01*
X156652Y1412820D01*
X156902Y1412654D01*
X157194Y1412612D01*
X157527Y1412695D01*
X157777Y1412904D01*
X158027Y1413279D01*
G01X159502Y1413820D02*
X159752Y1414070D01*
X160044Y1414195D01*
X160377Y1414237D01*
X160794Y1414154D01*
X161086Y1413945D01*
X161169Y1413695D01*
X161127Y1413445D01*
X160961Y1413237D01*
X160127Y1412820D01*
X159752Y1412529D01*
X159502Y1412112D01*
X159419Y1411737D01*
X161169D01*
G01X163394D02*
X163686Y1411779D01*
X164019Y1411904D01*
X164227Y1412112D01*
X164311Y1412404D01*
X164227Y1412695D01*
X163977Y1412945D01*
X163602Y1413070D01*
X163186D01*
X162936Y1413154D01*
X162727Y1413362D01*
X162644Y1413654D01*
X162769Y1413945D01*
X163061Y1414154D01*
X163394Y1414237D01*
X163727Y1414154D01*
X164019Y1413945D01*
X164144Y1413654D01*
X164061Y1413362D01*
X163852Y1413154D01*
X163602Y1413070D01*
X163186D01*
X162811Y1412945D01*
X162561Y1412695D01*
X162477Y1412404D01*
X162561Y1412112D01*
X162769Y1411904D01*
X163102Y1411779D01*
X163394Y1411737D01*
G01X164374Y1433400D02*
X160374D01*
Y1426000D01*
G01X183374Y1393417D02*
X180874D01*
Y1394458D01*
X180999Y1394792D01*
X181166Y1395000D01*
X181499Y1395083D01*
X181832Y1395000D01*
X182041Y1394750D01*
X182166Y1394458D01*
Y1393417D01*
G01Y1394458D02*
X183374Y1395083D01*
G01X183082Y1396642D02*
X183291Y1396933D01*
X183374Y1397267D01*
X183291Y1397600D01*
X183041Y1397892D01*
X182666Y1398100D01*
X182291Y1398183D01*
X181832D01*
X181457Y1398100D01*
X181124Y1397892D01*
X180957Y1397642D01*
X180874Y1397350D01*
X180957Y1397017D01*
X181124Y1396767D01*
X181374Y1396600D01*
X181707Y1396517D01*
X181999Y1396600D01*
X182291Y1396808D01*
X182457Y1397058D01*
X182499Y1397350D01*
X182416Y1397683D01*
X182207Y1397933D01*
X181832Y1398183D01*
G01X182332Y1399658D02*
X182041Y1399950D01*
X181874Y1400200D01*
X181791Y1400533D01*
X181874Y1400825D01*
X182041Y1401033D01*
X182291Y1401200D01*
X182582Y1401242D01*
X182832Y1401200D01*
X183082Y1401033D01*
X183291Y1400783D01*
X183374Y1400492D01*
X183291Y1400158D01*
X183041Y1399867D01*
X182666Y1399700D01*
X182249Y1399658D01*
X181707Y1399742D01*
X181416Y1399867D01*
X181124Y1400075D01*
X180916Y1400367D01*
X180874Y1400658D01*
X180957Y1400950D01*
X181166Y1401158D01*
G01X182874Y1402633D02*
X183166Y1402883D01*
X183332Y1403217D01*
X183374Y1403592D01*
X183332Y1403925D01*
X183124Y1404258D01*
X182874Y1404467D01*
X182624Y1404508D01*
X182332Y1404425D01*
X182124Y1404133D01*
X182041Y1403842D01*
Y1403467D01*
G01Y1403842D02*
X181916Y1404092D01*
X181707Y1404300D01*
X181457Y1404383D01*
X181207Y1404300D01*
X180999Y1404092D01*
X180874Y1403717D01*
X180916Y1403342D01*
X181082Y1402967D01*
G01X182374Y1422200D02*
X178374D01*
Y1414800D01*
G01X161992Y1398656D02*
X159492D01*
Y1399697D01*
X159617Y1400031D01*
X159784Y1400239D01*
X160117Y1400322D01*
X160450Y1400239D01*
X160659Y1399989D01*
X160784Y1399697D01*
Y1398656D01*
G01Y1399697D02*
X161992Y1400322D01*
G01Y1402589D02*
X159492D01*
X159992Y1402089D01*
G01X161992D02*
Y1403089D01*
G01Y1406189D02*
X159492D01*
X161284Y1404647D01*
Y1406731D01*
G01X161492Y1407872D02*
X161784Y1408122D01*
X161950Y1408456D01*
X161992Y1408831D01*
X161950Y1409164D01*
X161742Y1409497D01*
X161492Y1409706D01*
X161242Y1409747D01*
X160950Y1409664D01*
X160742Y1409372D01*
X160659Y1409081D01*
Y1408706D01*
G01Y1409081D02*
X160534Y1409331D01*
X160325Y1409539D01*
X160075Y1409622D01*
X159825Y1409539D01*
X159617Y1409331D01*
X159492Y1408956D01*
X159534Y1408581D01*
X159700Y1408206D01*
G01X164274Y1424800D02*
X160274D01*
Y1417400D01*
G01X183674Y1379617D02*
X181174D01*
Y1380658D01*
X181299Y1380992D01*
X181466Y1381200D01*
X181799Y1381283D01*
X182132Y1381200D01*
X182341Y1380950D01*
X182466Y1380658D01*
Y1379617D01*
G01Y1380658D02*
X183674Y1381283D01*
G01Y1383550D02*
X181174D01*
X181674Y1383050D01*
G01X183674D02*
Y1384050D01*
G01Y1387150D02*
X181174D01*
X182966Y1385608D01*
Y1387692D01*
G01X183674Y1389667D02*
X183132Y1389750D01*
X182674Y1389875D01*
X182257Y1390042D01*
X181799Y1390250D01*
X181174Y1390583D01*
Y1388917D01*
G01X182374Y1414550D02*
X178374D01*
Y1407150D01*
G01X187674Y1379317D02*
X185174D01*
Y1380358D01*
X185299Y1380692D01*
X185466Y1380900D01*
X185799Y1380983D01*
X186132Y1380900D01*
X186341Y1380650D01*
X186466Y1380358D01*
Y1379317D01*
G01Y1380358D02*
X187674Y1380983D01*
G01Y1383250D02*
X185174D01*
X185674Y1382750D01*
G01X187674D02*
Y1383750D01*
G01X187299Y1385433D02*
X187507Y1385683D01*
X187632Y1385975D01*
X187674Y1386350D01*
X187591Y1386725D01*
X187424Y1387017D01*
X187132Y1387225D01*
X186799Y1387267D01*
X186466Y1387183D01*
X186257Y1386975D01*
X186091Y1386683D01*
X186049Y1386392D01*
X186091Y1386100D01*
X186257Y1385725D01*
X185174Y1385850D01*
Y1386975D01*
G01Y1389450D02*
X185257Y1389117D01*
X185466Y1388867D01*
X185716Y1388700D01*
X186049Y1388575D01*
X186424Y1388533D01*
X186799Y1388575D01*
X187132Y1388700D01*
X187382Y1388867D01*
X187591Y1389117D01*
X187674Y1389450D01*
X187591Y1389783D01*
X187382Y1390033D01*
X187132Y1390200D01*
X186799Y1390325D01*
X186424Y1390367D01*
X186049Y1390325D01*
X185716Y1390200D01*
X185466Y1390033D01*
X185257Y1389783D01*
X185174Y1389450D01*
G01X182924Y1410800D02*
Y1406800D01*
X190324D01*
G01X121491Y1423500D02*
Y1426000D01*
X122532D01*
X122866Y1425875D01*
X123074Y1425708D01*
X123157Y1425375D01*
X123074Y1425042D01*
X122824Y1424833D01*
X122532Y1424708D01*
X121491D01*
G01X122532D02*
X123157Y1423500D01*
G01X124716Y1423792D02*
X125007Y1423583D01*
X125341Y1423500D01*
X125674Y1423583D01*
X125966Y1423833D01*
X126174Y1424208D01*
X126257Y1424583D01*
Y1425042D01*
X126174Y1425417D01*
X125966Y1425750D01*
X125716Y1425917D01*
X125424Y1426000D01*
X125091Y1425917D01*
X124841Y1425750D01*
X124674Y1425500D01*
X124591Y1425167D01*
X124674Y1424875D01*
X124882Y1424583D01*
X125132Y1424417D01*
X125424Y1424375D01*
X125757Y1424458D01*
X126007Y1424667D01*
X126257Y1425042D01*
G01X127607Y1424000D02*
X127857Y1423708D01*
X128191Y1423542D01*
X128566Y1423500D01*
X128899Y1423542D01*
X129232Y1423750D01*
X129441Y1424000D01*
X129482Y1424250D01*
X129399Y1424542D01*
X129107Y1424750D01*
X128816Y1424833D01*
X128441D01*
G01X128816D02*
X129066Y1424958D01*
X129274Y1425167D01*
X129357Y1425417D01*
X129274Y1425667D01*
X129066Y1425875D01*
X128691Y1426000D01*
X128316Y1425958D01*
X127941Y1425792D01*
G01X130832Y1425583D02*
X131082Y1425833D01*
X131374Y1425958D01*
X131707Y1426000D01*
X132124Y1425917D01*
X132416Y1425708D01*
X132499Y1425458D01*
X132457Y1425208D01*
X132291Y1425000D01*
X131457Y1424583D01*
X131082Y1424292D01*
X130832Y1423875D01*
X130749Y1423500D01*
X132499D01*
G01X136974Y1423700D02*
X140974D01*
Y1431100D01*
G01X190974Y1422800D02*
X193074Y1421000D01*
X190974Y1418800D01*
G01X190874Y1415200D02*
X210074D01*
Y1426400D01*
X190874D01*
Y1415200D01*
X191274D01*
G01X169374Y1399983D02*
X166874D01*
Y1400817D01*
X166999Y1401150D01*
X167166Y1401400D01*
X167416Y1401608D01*
X167707Y1401775D01*
X168124Y1401817D01*
X168541Y1401775D01*
X168832Y1401608D01*
X169082Y1401400D01*
X169249Y1401150D01*
X169374Y1400817D01*
Y1399983D01*
G01Y1404500D02*
X166874D01*
X168666Y1402958D01*
Y1405042D01*
G01X169082Y1406392D02*
X169291Y1406683D01*
X169374Y1407017D01*
X169291Y1407350D01*
X169041Y1407642D01*
X168666Y1407850D01*
X168291Y1407933D01*
X167832D01*
X167457Y1407850D01*
X167124Y1407642D01*
X166957Y1407392D01*
X166874Y1407100D01*
X166957Y1406767D01*
X167124Y1406517D01*
X167374Y1406350D01*
X167707Y1406267D01*
X167999Y1406350D01*
X168291Y1406558D01*
X168457Y1406808D01*
X168499Y1407100D01*
X168416Y1407433D01*
X168207Y1407683D01*
X167832Y1407933D01*
G01X170874Y1397900D02*
Y1414000D01*
G01X177874Y1397900D02*
X170874D01*
G01X177874Y1414000D02*
Y1397900D01*
G01X170874Y1414000D02*
X177874D01*
G01Y1418500D02*
Y1432500D01*
G01X164874Y1418500D02*
X177874D01*
G01X164874Y1432500D02*
Y1418500D01*
G01X132938Y1422429D02*
Y1420637D01*
X133105Y1420262D01*
X133438Y1420012D01*
X133855Y1419929D01*
X134272Y1420012D01*
X134605Y1420262D01*
X134772Y1420637D01*
Y1422429D01*
G01X136163Y1422012D02*
X136413Y1422262D01*
X136705Y1422387D01*
X137038Y1422429D01*
X137455Y1422346D01*
X137747Y1422137D01*
X137830Y1421887D01*
X137788Y1421637D01*
X137622Y1421429D01*
X136788Y1421012D01*
X136413Y1420721D01*
X136163Y1420304D01*
X136080Y1419929D01*
X137830D01*
G01X155395Y1418200D02*
X141995D01*
G01X155395Y1428200D02*
Y1418200D01*
G01X141995Y1428200D02*
X155395D01*
G01X141995Y1418200D02*
Y1428200D01*
G01X256087Y1527769D02*
Y1470269D01*
X239887D01*
Y1439269D01*
X161687D01*
Y1470269D01*
X145487D01*
Y1527769D01*
X256087D01*
G01X147374Y1451800D02*
X151374D01*
Y1459200D01*
G01X133291Y1485600D02*
Y1488100D01*
X134332D01*
X134666Y1487975D01*
X134874Y1487808D01*
X134957Y1487475D01*
X134874Y1487142D01*
X134624Y1486933D01*
X134332Y1486808D01*
X133291D01*
G01X134332D02*
X134957Y1485600D01*
G01X136516Y1485892D02*
X136807Y1485683D01*
X137141Y1485600D01*
X137474Y1485683D01*
X137766Y1485933D01*
X137974Y1486308D01*
X138057Y1486683D01*
Y1487142D01*
X137974Y1487517D01*
X137766Y1487850D01*
X137516Y1488017D01*
X137224Y1488100D01*
X136891Y1488017D01*
X136641Y1487850D01*
X136474Y1487600D01*
X136391Y1487267D01*
X136474Y1486975D01*
X136682Y1486683D01*
X136932Y1486517D01*
X137224Y1486475D01*
X137557Y1486558D01*
X137807Y1486767D01*
X138057Y1487142D01*
G01X139532Y1487683D02*
X139782Y1487933D01*
X140074Y1488058D01*
X140407Y1488100D01*
X140824Y1488017D01*
X141116Y1487808D01*
X141199Y1487558D01*
X141157Y1487308D01*
X140991Y1487100D01*
X140157Y1486683D01*
X139782Y1486392D01*
X139532Y1485975D01*
X139449Y1485600D01*
X141199D01*
G01X142507Y1485975D02*
X142757Y1485767D01*
X143049Y1485642D01*
X143424Y1485600D01*
X143799Y1485683D01*
X144091Y1485850D01*
X144299Y1486142D01*
X144341Y1486475D01*
X144257Y1486808D01*
X144049Y1487017D01*
X143757Y1487183D01*
X143466Y1487225D01*
X143174Y1487183D01*
X142799Y1487017D01*
X142924Y1488100D01*
X144049D01*
G01X143174Y1470900D02*
Y1474900D01*
X135774D01*
G01X144074Y1450500D02*
Y1454500D01*
X136674D01*
G01X147374Y1433300D02*
X151374D01*
Y1440700D01*
G01X142474Y1490217D02*
X139974D01*
Y1491258D01*
X140099Y1491592D01*
X140266Y1491800D01*
X140599Y1491883D01*
X140932Y1491800D01*
X141141Y1491550D01*
X141266Y1491258D01*
Y1490217D01*
G01Y1491258D02*
X142474Y1491883D01*
G01X142182Y1493442D02*
X142391Y1493733D01*
X142474Y1494067D01*
X142391Y1494400D01*
X142141Y1494692D01*
X141766Y1494900D01*
X141391Y1494983D01*
X140932D01*
X140557Y1494900D01*
X140224Y1494692D01*
X140057Y1494442D01*
X139974Y1494150D01*
X140057Y1493817D01*
X140224Y1493567D01*
X140474Y1493400D01*
X140807Y1493317D01*
X141099Y1493400D01*
X141391Y1493608D01*
X141557Y1493858D01*
X141599Y1494150D01*
X141516Y1494483D01*
X141307Y1494733D01*
X140932Y1494983D01*
G01X141974Y1496333D02*
X142266Y1496583D01*
X142432Y1496917D01*
X142474Y1497292D01*
X142432Y1497625D01*
X142224Y1497958D01*
X141974Y1498167D01*
X141724Y1498208D01*
X141432Y1498125D01*
X141224Y1497833D01*
X141141Y1497542D01*
Y1497167D01*
G01Y1497542D02*
X141016Y1497792D01*
X140807Y1498000D01*
X140557Y1498083D01*
X140307Y1498000D01*
X140099Y1497792D01*
X139974Y1497417D01*
X140016Y1497042D01*
X140182Y1496667D01*
G01X139974Y1500350D02*
X140057Y1500017D01*
X140266Y1499767D01*
X140516Y1499600D01*
X140849Y1499475D01*
X141224Y1499433D01*
X141599Y1499475D01*
X141932Y1499600D01*
X142182Y1499767D01*
X142391Y1500017D01*
X142474Y1500350D01*
X142391Y1500683D01*
X142182Y1500933D01*
X141932Y1501100D01*
X141599Y1501225D01*
X141224Y1501267D01*
X140849Y1501225D01*
X140516Y1501100D01*
X140266Y1500933D01*
X140057Y1500683D01*
X139974Y1500350D01*
G01X141374Y1483700D02*
X137374D01*
Y1476300D01*
G01X106164Y1430000D02*
Y1432500D01*
X107205D01*
X107539Y1432375D01*
X107747Y1432208D01*
X107830Y1431875D01*
X107747Y1431542D01*
X107497Y1431333D01*
X107205Y1431208D01*
X106164D01*
G01X107205D02*
X107830Y1430000D01*
G01X109389Y1430292D02*
X109680Y1430083D01*
X110014Y1430000D01*
X110347Y1430083D01*
X110639Y1430333D01*
X110847Y1430708D01*
X110930Y1431083D01*
Y1431542D01*
X110847Y1431917D01*
X110639Y1432250D01*
X110389Y1432417D01*
X110097Y1432500D01*
X109764Y1432417D01*
X109514Y1432250D01*
X109347Y1432000D01*
X109264Y1431667D01*
X109347Y1431375D01*
X109555Y1431083D01*
X109805Y1430917D01*
X110097Y1430875D01*
X110430Y1430958D01*
X110680Y1431167D01*
X110930Y1431542D01*
G01X112280Y1430500D02*
X112530Y1430208D01*
X112864Y1430042D01*
X113239Y1430000D01*
X113572Y1430042D01*
X113905Y1430250D01*
X114114Y1430500D01*
X114155Y1430750D01*
X114072Y1431042D01*
X113780Y1431250D01*
X113489Y1431333D01*
X113114D01*
G01X113489D02*
X113739Y1431458D01*
X113947Y1431667D01*
X114030Y1431917D01*
X113947Y1432167D01*
X113739Y1432375D01*
X113364Y1432500D01*
X112989Y1432458D01*
X112614Y1432292D01*
G01X116297Y1430000D02*
Y1432500D01*
X115797Y1432000D01*
G01Y1430000D02*
X116797D01*
G01X144074Y1432000D02*
Y1436000D01*
X136674D01*
G01X112274Y1482400D02*
Y1478400D01*
X119674D01*
G01X123541Y1493500D02*
Y1496000D01*
X124582D01*
X124916Y1495875D01*
X125124Y1495708D01*
X125207Y1495375D01*
X125124Y1495042D01*
X124874Y1494833D01*
X124582Y1494708D01*
X123541D01*
G01X124582D02*
X125207Y1493500D01*
G01X127474D02*
Y1496000D01*
X126974Y1495500D01*
G01Y1493500D02*
X127974D01*
G01X129782Y1495583D02*
X130032Y1495833D01*
X130324Y1495958D01*
X130657Y1496000D01*
X131074Y1495917D01*
X131366Y1495708D01*
X131449Y1495458D01*
X131407Y1495208D01*
X131241Y1495000D01*
X130407Y1494583D01*
X130032Y1494292D01*
X129782Y1493875D01*
X129699Y1493500D01*
X131449D01*
G01X132966Y1493792D02*
X133257Y1493583D01*
X133591Y1493500D01*
X133924Y1493583D01*
X134216Y1493833D01*
X134424Y1494208D01*
X134507Y1494583D01*
Y1495042D01*
X134424Y1495417D01*
X134216Y1495750D01*
X133966Y1495917D01*
X133674Y1496000D01*
X133341Y1495917D01*
X133091Y1495750D01*
X132924Y1495500D01*
X132841Y1495167D01*
X132924Y1494875D01*
X133132Y1494583D01*
X133382Y1494417D01*
X133674Y1494375D01*
X134007Y1494458D01*
X134257Y1494667D01*
X134507Y1495042D01*
G01X136691Y1493500D02*
X136774Y1494042D01*
X136899Y1494500D01*
X137066Y1494917D01*
X137274Y1495375D01*
X137607Y1496000D01*
X135941D01*
G01X123674Y1486200D02*
Y1482200D01*
X131074D01*
G01X107474Y1478685D02*
X103474D01*
Y1471285D01*
G01X123441Y1489900D02*
Y1492400D01*
X124482D01*
X124816Y1492275D01*
X125024Y1492108D01*
X125107Y1491775D01*
X125024Y1491442D01*
X124774Y1491233D01*
X124482Y1491108D01*
X123441D01*
G01X124482D02*
X125107Y1489900D01*
G01X127374D02*
Y1492400D01*
X126874Y1491900D01*
G01Y1489900D02*
X127874D01*
G01X129557Y1490400D02*
X129807Y1490108D01*
X130141Y1489942D01*
X130516Y1489900D01*
X130849Y1489942D01*
X131182Y1490150D01*
X131391Y1490400D01*
X131432Y1490650D01*
X131349Y1490942D01*
X131057Y1491150D01*
X130766Y1491233D01*
X130391D01*
G01X130766D02*
X131016Y1491358D01*
X131224Y1491567D01*
X131307Y1491817D01*
X131224Y1492067D01*
X131016Y1492275D01*
X130641Y1492400D01*
X130266Y1492358D01*
X129891Y1492192D01*
G01X133574Y1492400D02*
X133241Y1492317D01*
X132991Y1492108D01*
X132824Y1491858D01*
X132699Y1491525D01*
X132657Y1491150D01*
X132699Y1490775D01*
X132824Y1490442D01*
X132991Y1490192D01*
X133241Y1489983D01*
X133574Y1489900D01*
X133907Y1489983D01*
X134157Y1490192D01*
X134324Y1490442D01*
X134449Y1490775D01*
X134491Y1491150D01*
X134449Y1491525D01*
X134324Y1491858D01*
X134157Y1492108D01*
X133907Y1492317D01*
X133574Y1492400D01*
G01X135757Y1490275D02*
X136007Y1490067D01*
X136299Y1489942D01*
X136674Y1489900D01*
X137049Y1489983D01*
X137341Y1490150D01*
X137549Y1490442D01*
X137591Y1490775D01*
X137507Y1491108D01*
X137299Y1491317D01*
X137007Y1491483D01*
X136716Y1491525D01*
X136424Y1491483D01*
X136049Y1491317D01*
X136174Y1492400D01*
X137299D01*
G01X130274Y1477100D02*
Y1481100D01*
X122874D01*
G01X106164Y1434000D02*
Y1436500D01*
X107205D01*
X107539Y1436375D01*
X107747Y1436208D01*
X107830Y1435875D01*
X107747Y1435542D01*
X107497Y1435333D01*
X107205Y1435208D01*
X106164D01*
G01X107205D02*
X107830Y1434000D01*
G01X109389Y1434292D02*
X109680Y1434083D01*
X110014Y1434000D01*
X110347Y1434083D01*
X110639Y1434333D01*
X110847Y1434708D01*
X110930Y1435083D01*
Y1435542D01*
X110847Y1435917D01*
X110639Y1436250D01*
X110389Y1436417D01*
X110097Y1436500D01*
X109764Y1436417D01*
X109514Y1436250D01*
X109347Y1436000D01*
X109264Y1435667D01*
X109347Y1435375D01*
X109555Y1435083D01*
X109805Y1434917D01*
X110097Y1434875D01*
X110430Y1434958D01*
X110680Y1435167D01*
X110930Y1435542D01*
G01X112405Y1436083D02*
X112655Y1436333D01*
X112947Y1436458D01*
X113280Y1436500D01*
X113697Y1436417D01*
X113989Y1436208D01*
X114072Y1435958D01*
X114030Y1435708D01*
X113864Y1435500D01*
X113030Y1435083D01*
X112655Y1434792D01*
X112405Y1434375D01*
X112322Y1434000D01*
X114072D01*
G01X115589Y1434292D02*
X115880Y1434083D01*
X116214Y1434000D01*
X116547Y1434083D01*
X116839Y1434333D01*
X117047Y1434708D01*
X117130Y1435083D01*
Y1435542D01*
X117047Y1435917D01*
X116839Y1436250D01*
X116589Y1436417D01*
X116297Y1436500D01*
X115964Y1436417D01*
X115714Y1436250D01*
X115547Y1436000D01*
X115464Y1435667D01*
X115547Y1435375D01*
X115755Y1435083D01*
X116005Y1434917D01*
X116297Y1434875D01*
X116630Y1434958D01*
X116880Y1435167D01*
X117130Y1435542D01*
G01X124124Y1469300D02*
X123791Y1469342D01*
X123499Y1469508D01*
X123249Y1469758D01*
X123082Y1470050D01*
X122999Y1470383D01*
Y1470717D01*
X123082Y1471050D01*
X123249Y1471342D01*
X123499Y1471592D01*
X123791Y1471758D01*
X124124Y1471800D01*
X124457Y1471758D01*
X124749Y1471592D01*
X124999Y1471342D01*
X125166Y1471050D01*
X125249Y1470717D01*
Y1470383D01*
X125166Y1470050D01*
X124999Y1469758D01*
X124749Y1469508D01*
X124457Y1469342D01*
X124124Y1469300D01*
G01X124457Y1469967D02*
X124957Y1469300D01*
G01X126432Y1471383D02*
X126682Y1471633D01*
X126974Y1471758D01*
X127307Y1471800D01*
X127724Y1471717D01*
X128016Y1471508D01*
X128099Y1471258D01*
X128057Y1471008D01*
X127891Y1470800D01*
X127057Y1470383D01*
X126682Y1470092D01*
X126432Y1469675D01*
X126349Y1469300D01*
X128099D01*
G01X130324D02*
Y1471800D01*
X129824Y1471300D01*
G01Y1469300D02*
X130824D01*
G01X132507Y1469675D02*
X132757Y1469467D01*
X133049Y1469342D01*
X133424Y1469300D01*
X133799Y1469383D01*
X134091Y1469550D01*
X134299Y1469842D01*
X134341Y1470175D01*
X134257Y1470508D01*
X134049Y1470717D01*
X133757Y1470883D01*
X133466Y1470925D01*
X133174Y1470883D01*
X132799Y1470717D01*
X132924Y1471800D01*
X134049D01*
G01X108174Y1477700D02*
Y1466300D01*
G01X121574Y1477700D02*
X108174D01*
G01X121574Y1466300D02*
Y1477700D01*
G01X108174Y1466300D02*
X121574D01*
G01X125557Y1462000D02*
Y1464500D01*
X126391D01*
X126724Y1464375D01*
X126974Y1464208D01*
X127182Y1463958D01*
X127349Y1463667D01*
X127391Y1463250D01*
X127349Y1462833D01*
X127182Y1462542D01*
X126974Y1462292D01*
X126724Y1462125D01*
X126391Y1462000D01*
X125557D01*
G01X128657Y1462500D02*
X128907Y1462208D01*
X129241Y1462042D01*
X129616Y1462000D01*
X129949Y1462042D01*
X130282Y1462250D01*
X130491Y1462500D01*
X130532Y1462750D01*
X130449Y1463042D01*
X130157Y1463250D01*
X129866Y1463333D01*
X129491D01*
G01X129866D02*
X130116Y1463458D01*
X130324Y1463667D01*
X130407Y1463917D01*
X130324Y1464167D01*
X130116Y1464375D01*
X129741Y1464500D01*
X129366Y1464458D01*
X128991Y1464292D01*
G01X132591Y1462000D02*
X132674Y1462542D01*
X132799Y1463000D01*
X132966Y1463417D01*
X133174Y1463875D01*
X133507Y1464500D01*
X131841D01*
G01X136374Y1460000D02*
X157374D01*
G01D02*
Y1468000D01*
G01D02*
X136374D01*
G01D02*
Y1460000D01*
G01X124757Y1444900D02*
Y1447400D01*
X125591D01*
X125924Y1447275D01*
X126174Y1447108D01*
X126382Y1446858D01*
X126549Y1446567D01*
X126591Y1446150D01*
X126549Y1445733D01*
X126382Y1445442D01*
X126174Y1445192D01*
X125924Y1445025D01*
X125591Y1444900D01*
X124757D01*
G01X127857Y1445400D02*
X128107Y1445108D01*
X128441Y1444942D01*
X128816Y1444900D01*
X129149Y1444942D01*
X129482Y1445150D01*
X129691Y1445400D01*
X129732Y1445650D01*
X129649Y1445942D01*
X129357Y1446150D01*
X129066Y1446233D01*
X128691D01*
G01X129066D02*
X129316Y1446358D01*
X129524Y1446567D01*
X129607Y1446817D01*
X129524Y1447067D01*
X129316Y1447275D01*
X128941Y1447400D01*
X128566Y1447358D01*
X128191Y1447192D01*
G01X131874Y1444900D02*
X132166Y1444942D01*
X132499Y1445067D01*
X132707Y1445275D01*
X132791Y1445567D01*
X132707Y1445858D01*
X132457Y1446108D01*
X132082Y1446233D01*
X131666D01*
X131416Y1446317D01*
X131207Y1446525D01*
X131124Y1446817D01*
X131249Y1447108D01*
X131541Y1447317D01*
X131874Y1447400D01*
X132207Y1447317D01*
X132499Y1447108D01*
X132624Y1446817D01*
X132541Y1446525D01*
X132332Y1446317D01*
X132082Y1446233D01*
X131666D01*
X131291Y1446108D01*
X131041Y1445858D01*
X130957Y1445567D01*
X131041Y1445275D01*
X131249Y1445067D01*
X131582Y1444942D01*
X131874Y1444900D01*
G01X136374Y1441500D02*
X157374D01*
G01D02*
Y1449500D01*
G01D02*
X136374D01*
G01D02*
Y1441500D01*
G01X170624Y1434700D02*
X170291Y1434742D01*
X169999Y1434908D01*
X169749Y1435158D01*
X169582Y1435450D01*
X169499Y1435783D01*
Y1436117D01*
X169582Y1436450D01*
X169749Y1436742D01*
X169999Y1436992D01*
X170291Y1437158D01*
X170624Y1437200D01*
X170957Y1437158D01*
X171249Y1436992D01*
X171499Y1436742D01*
X171666Y1436450D01*
X171749Y1436117D01*
Y1435783D01*
X171666Y1435450D01*
X171499Y1435158D01*
X171249Y1434908D01*
X170957Y1434742D01*
X170624Y1434700D01*
G01X170957Y1435367D02*
X171457Y1434700D01*
G01X172932Y1436783D02*
X173182Y1437033D01*
X173474Y1437158D01*
X173807Y1437200D01*
X174224Y1437117D01*
X174516Y1436908D01*
X174599Y1436658D01*
X174557Y1436408D01*
X174391Y1436200D01*
X173557Y1435783D01*
X173182Y1435492D01*
X172932Y1435075D01*
X172849Y1434700D01*
X174599D01*
G01X176824D02*
Y1437200D01*
X176324Y1436700D01*
G01Y1434700D02*
X177324D01*
G01X179924D02*
Y1437200D01*
X179424Y1436700D01*
G01Y1434700D02*
X180424D01*
G01X177874Y1432500D02*
X164874D01*
G01X120874Y1462400D02*
Y1449000D01*
G01X110874Y1462400D02*
X120874D01*
G01X110874Y1449000D02*
Y1462400D01*
G01X120874Y1449000D02*
X110874D01*
G01X111070Y1500422D02*
X110737Y1500464D01*
X110445Y1500630D01*
X110195Y1500880D01*
X110028Y1501172D01*
X109945Y1501505D01*
Y1501839D01*
X110028Y1502172D01*
X110195Y1502464D01*
X110445Y1502714D01*
X110737Y1502880D01*
X111070Y1502922D01*
X111403Y1502880D01*
X111695Y1502714D01*
X111945Y1502464D01*
X112112Y1502172D01*
X112195Y1501839D01*
Y1501505D01*
X112112Y1501172D01*
X111945Y1500880D01*
X111695Y1500630D01*
X111403Y1500464D01*
X111070Y1500422D01*
G01X111403Y1501089D02*
X111903Y1500422D01*
G01X113378Y1502505D02*
X113628Y1502755D01*
X113920Y1502880D01*
X114253Y1502922D01*
X114670Y1502839D01*
X114962Y1502630D01*
X115045Y1502380D01*
X115003Y1502130D01*
X114837Y1501922D01*
X114003Y1501505D01*
X113628Y1501214D01*
X113378Y1500797D01*
X113295Y1500422D01*
X115045D01*
G01X117270Y1502922D02*
X116937Y1502839D01*
X116687Y1502630D01*
X116520Y1502380D01*
X116395Y1502047D01*
X116353Y1501672D01*
X116395Y1501297D01*
X116520Y1500964D01*
X116687Y1500714D01*
X116937Y1500505D01*
X117270Y1500422D01*
X117603Y1500505D01*
X117853Y1500714D01*
X118020Y1500964D01*
X118145Y1501297D01*
X118187Y1501672D01*
X118145Y1502047D01*
X118020Y1502380D01*
X117853Y1502630D01*
X117603Y1502839D01*
X117270Y1502922D01*
G01X120870Y1500422D02*
Y1502922D01*
X119328Y1501130D01*
X121412D01*
G01X116109Y1482600D02*
Y1482860D01*
X114674Y1484295D01*
X113239Y1482860D01*
G01X116109Y1482600D02*
X113239D01*
Y1493600D01*
G01X116109D02*
Y1482600D01*
G01Y1493600D02*
X113239D01*
G01X218336Y107319D02*
X223386D01*
Y206019D01*
X248036D01*
Y21619D01*
X223386D01*
Y80319D01*
X218336D01*
Y107319D01*
G01X263788Y57172D02*
X263538Y57297D01*
X263246Y57380D01*
X262913D01*
X262538Y57255D01*
X262246Y57047D01*
X262038Y56797D01*
X261871Y56380D01*
X261829Y56005D01*
X261913Y55630D01*
X262038Y55380D01*
X262288Y55130D01*
X262579Y54963D01*
X262871Y54880D01*
X263163D01*
X263454Y54963D01*
X263704Y55088D01*
X263913Y55255D01*
G01X265054Y55380D02*
X265304Y55088D01*
X265638Y54922D01*
X266013Y54880D01*
X266346Y54922D01*
X266679Y55130D01*
X266888Y55380D01*
X266929Y55630D01*
X266846Y55922D01*
X266554Y56130D01*
X266263Y56213D01*
X265888D01*
G01X266263D02*
X266513Y56338D01*
X266721Y56547D01*
X266804Y56797D01*
X266721Y57047D01*
X266513Y57255D01*
X266138Y57380D01*
X265763Y57338D01*
X265388Y57172D01*
G01X268154Y55255D02*
X268404Y55047D01*
X268696Y54922D01*
X269071Y54880D01*
X269446Y54963D01*
X269738Y55130D01*
X269946Y55422D01*
X269988Y55755D01*
X269904Y56088D01*
X269696Y56297D01*
X269404Y56463D01*
X269113Y56505D01*
X268821Y56463D01*
X268446Y56297D01*
X268571Y57380D01*
X269696D01*
G01X272671Y54880D02*
Y57380D01*
X271129Y55588D01*
X273213D01*
G01X263767Y61292D02*
X263517Y61417D01*
X263225Y61500D01*
X262892D01*
X262517Y61375D01*
X262225Y61167D01*
X262017Y60917D01*
X261850Y60500D01*
X261808Y60125D01*
X261892Y59750D01*
X262017Y59500D01*
X262267Y59250D01*
X262558Y59083D01*
X262850Y59000D01*
X263142D01*
X263433Y59083D01*
X263683Y59208D01*
X263892Y59375D01*
G01X265033Y59500D02*
X265283Y59208D01*
X265617Y59042D01*
X265992Y59000D01*
X266325Y59042D01*
X266658Y59250D01*
X266867Y59500D01*
X266908Y59750D01*
X266825Y60042D01*
X266533Y60250D01*
X266242Y60333D01*
X265867D01*
G01X266242D02*
X266492Y60458D01*
X266700Y60667D01*
X266783Y60917D01*
X266700Y61167D01*
X266492Y61375D01*
X266117Y61500D01*
X265742Y61458D01*
X265367Y61292D01*
G01X268133Y59375D02*
X268383Y59167D01*
X268675Y59042D01*
X269050Y59000D01*
X269425Y59083D01*
X269717Y59250D01*
X269925Y59542D01*
X269967Y59875D01*
X269883Y60208D01*
X269675Y60417D01*
X269383Y60583D01*
X269092Y60625D01*
X268800Y60583D01*
X268425Y60417D01*
X268550Y61500D01*
X269675D01*
G01X271233Y59500D02*
X271483Y59208D01*
X271817Y59042D01*
X272192Y59000D01*
X272525Y59042D01*
X272858Y59250D01*
X273067Y59500D01*
X273108Y59750D01*
X273025Y60042D01*
X272733Y60250D01*
X272442Y60333D01*
X272067D01*
G01X272442D02*
X272692Y60458D01*
X272900Y60667D01*
X272983Y60917D01*
X272900Y61167D01*
X272692Y61375D01*
X272317Y61500D01*
X271942Y61458D01*
X271567Y61292D01*
G01X197608Y22367D02*
X197483Y22117D01*
X197400Y21825D01*
Y21492D01*
X197525Y21117D01*
X197733Y20825D01*
X197983Y20617D01*
X198400Y20450D01*
X198775Y20408D01*
X199150Y20492D01*
X199400Y20617D01*
X199650Y20867D01*
X199817Y21158D01*
X199900Y21450D01*
Y21742D01*
X199817Y22033D01*
X199692Y22283D01*
X199525Y22492D01*
G01X199400Y23633D02*
X199692Y23883D01*
X199858Y24217D01*
X199900Y24592D01*
X199858Y24925D01*
X199650Y25258D01*
X199400Y25467D01*
X199150Y25508D01*
X198858Y25425D01*
X198650Y25133D01*
X198567Y24842D01*
Y24467D01*
G01Y24842D02*
X198442Y25092D01*
X198233Y25300D01*
X197983Y25383D01*
X197733Y25300D01*
X197525Y25092D01*
X197400Y24717D01*
X197442Y24342D01*
X197608Y23967D01*
G01X198858Y26858D02*
X198567Y27150D01*
X198400Y27400D01*
X198317Y27733D01*
X198400Y28025D01*
X198567Y28233D01*
X198817Y28400D01*
X199108Y28442D01*
X199358Y28400D01*
X199608Y28233D01*
X199817Y27983D01*
X199900Y27692D01*
X199817Y27358D01*
X199567Y27067D01*
X199192Y26900D01*
X198775Y26858D01*
X198233Y26942D01*
X197942Y27067D01*
X197650Y27275D01*
X197442Y27567D01*
X197400Y27858D01*
X197483Y28150D01*
X197692Y28358D01*
G01X199900Y31250D02*
X197400D01*
X199192Y29708D01*
Y31792D01*
G01X217500Y79200D02*
X213500D01*
Y71800D01*
G01X222000Y79200D02*
X218000D01*
Y71800D01*
G01X205000D02*
X209000D01*
Y79200D01*
G01X215000Y27817D02*
X212500D01*
Y28858D01*
X212625Y29192D01*
X212792Y29400D01*
X213125Y29483D01*
X213458Y29400D01*
X213667Y29150D01*
X213792Y28858D01*
Y27817D01*
G01Y28858D02*
X215000Y29483D01*
G01X213958Y30958D02*
X213667Y31250D01*
X213500Y31500D01*
X213417Y31833D01*
X213500Y32125D01*
X213667Y32333D01*
X213917Y32500D01*
X214208Y32542D01*
X214458Y32500D01*
X214708Y32333D01*
X214917Y32083D01*
X215000Y31792D01*
X214917Y31458D01*
X214667Y31167D01*
X214292Y31000D01*
X213875Y30958D01*
X213333Y31042D01*
X213042Y31167D01*
X212750Y31375D01*
X212542Y31667D01*
X212500Y31958D01*
X212583Y32250D01*
X212792Y32458D01*
G01X214625Y33933D02*
X214833Y34183D01*
X214958Y34475D01*
X215000Y34850D01*
X214917Y35225D01*
X214750Y35517D01*
X214458Y35725D01*
X214125Y35767D01*
X213792Y35683D01*
X213583Y35475D01*
X213417Y35183D01*
X213375Y34892D01*
X213417Y34600D01*
X213583Y34225D01*
X212500Y34350D01*
Y35475D01*
G01X214708Y37242D02*
X214917Y37533D01*
X215000Y37867D01*
X214917Y38200D01*
X214667Y38492D01*
X214292Y38700D01*
X213917Y38783D01*
X213458D01*
X213083Y38700D01*
X212750Y38492D01*
X212583Y38242D01*
X212500Y37950D01*
X212583Y37617D01*
X212750Y37367D01*
X213000Y37200D01*
X213333Y37117D01*
X213625Y37200D01*
X213917Y37408D01*
X214083Y37658D01*
X214125Y37950D01*
X214042Y38283D01*
X213833Y38533D01*
X213458Y38783D01*
G01X215000Y39800D02*
X219000D01*
Y47200D01*
G01X204100Y20617D02*
X201600D01*
Y21658D01*
X201725Y21992D01*
X201892Y22200D01*
X202225Y22283D01*
X202558Y22200D01*
X202767Y21950D01*
X202892Y21658D01*
Y20617D01*
G01Y21658D02*
X204100Y22283D01*
G01X203058Y23758D02*
X202767Y24050D01*
X202600Y24300D01*
X202517Y24633D01*
X202600Y24925D01*
X202767Y25133D01*
X203017Y25300D01*
X203308Y25342D01*
X203558Y25300D01*
X203808Y25133D01*
X204017Y24883D01*
X204100Y24592D01*
X204017Y24258D01*
X203767Y23967D01*
X203392Y23800D01*
X202975Y23758D01*
X202433Y23842D01*
X202142Y23967D01*
X201850Y24175D01*
X201642Y24467D01*
X201600Y24758D01*
X201683Y25050D01*
X201892Y25258D01*
G01X203058Y26858D02*
X202767Y27150D01*
X202600Y27400D01*
X202517Y27733D01*
X202600Y28025D01*
X202767Y28233D01*
X203017Y28400D01*
X203308Y28442D01*
X203558Y28400D01*
X203808Y28233D01*
X204017Y27983D01*
X204100Y27692D01*
X204017Y27358D01*
X203767Y27067D01*
X203392Y26900D01*
X202975Y26858D01*
X202433Y26942D01*
X202142Y27067D01*
X201850Y27275D01*
X201642Y27567D01*
X201600Y27858D01*
X201683Y28150D01*
X201892Y28358D01*
G01X201600Y30750D02*
X201683Y30417D01*
X201892Y30167D01*
X202142Y30000D01*
X202475Y29875D01*
X202850Y29833D01*
X203225Y29875D01*
X203558Y30000D01*
X203808Y30167D01*
X204017Y30417D01*
X204100Y30750D01*
X204017Y31083D01*
X203808Y31333D01*
X203558Y31500D01*
X203225Y31625D01*
X202850Y31667D01*
X202475Y31625D01*
X202142Y31500D01*
X201892Y31333D01*
X201683Y31083D01*
X201600Y30750D01*
G01X204800Y42900D02*
X200800D01*
Y35500D01*
G01X210600Y31217D02*
X208100D01*
Y32258D01*
X208225Y32592D01*
X208392Y32800D01*
X208725Y32883D01*
X209058Y32800D01*
X209267Y32550D01*
X209392Y32258D01*
Y31217D01*
G01Y32258D02*
X210600Y32883D01*
G01X209558Y34358D02*
X209267Y34650D01*
X209100Y34900D01*
X209017Y35233D01*
X209100Y35525D01*
X209267Y35733D01*
X209517Y35900D01*
X209808Y35942D01*
X210058Y35900D01*
X210308Y35733D01*
X210517Y35483D01*
X210600Y35192D01*
X210517Y34858D01*
X210267Y34567D01*
X209892Y34400D01*
X209475Y34358D01*
X208933Y34442D01*
X208642Y34567D01*
X208350Y34775D01*
X208142Y35067D01*
X208100Y35358D01*
X208183Y35650D01*
X208392Y35858D01*
G01X209558Y37458D02*
X209267Y37750D01*
X209100Y38000D01*
X209017Y38333D01*
X209100Y38625D01*
X209267Y38833D01*
X209517Y39000D01*
X209808Y39042D01*
X210058Y39000D01*
X210308Y38833D01*
X210517Y38583D01*
X210600Y38292D01*
X210517Y37958D01*
X210267Y37667D01*
X209892Y37500D01*
X209475Y37458D01*
X208933Y37542D01*
X208642Y37667D01*
X208350Y37875D01*
X208142Y38167D01*
X208100Y38458D01*
X208183Y38750D01*
X208392Y38958D01*
G01X210600Y41350D02*
X208100D01*
X208600Y40850D01*
G01X210600D02*
Y41850D01*
G01X209200Y43100D02*
Y47100D01*
X201800D01*
G01X198017Y56000D02*
Y58500D01*
X199058D01*
X199392Y58375D01*
X199600Y58208D01*
X199683Y57875D01*
X199600Y57542D01*
X199350Y57333D01*
X199058Y57208D01*
X198017D01*
G01X199058D02*
X199683Y56000D01*
G01X201158Y57042D02*
X201450Y57333D01*
X201700Y57500D01*
X202033Y57583D01*
X202325Y57500D01*
X202533Y57333D01*
X202700Y57083D01*
X202742Y56792D01*
X202700Y56542D01*
X202533Y56292D01*
X202283Y56083D01*
X201992Y56000D01*
X201658Y56083D01*
X201367Y56333D01*
X201200Y56708D01*
X201158Y57125D01*
X201242Y57667D01*
X201367Y57958D01*
X201575Y58250D01*
X201867Y58458D01*
X202158Y58500D01*
X202450Y58417D01*
X202658Y58208D01*
G01X204258Y57042D02*
X204550Y57333D01*
X204800Y57500D01*
X205133Y57583D01*
X205425Y57500D01*
X205633Y57333D01*
X205800Y57083D01*
X205842Y56792D01*
X205800Y56542D01*
X205633Y56292D01*
X205383Y56083D01*
X205092Y56000D01*
X204758Y56083D01*
X204467Y56333D01*
X204300Y56708D01*
X204258Y57125D01*
X204342Y57667D01*
X204467Y57958D01*
X204675Y58250D01*
X204967Y58458D01*
X205258Y58500D01*
X205550Y58417D01*
X205758Y58208D01*
G01X207358Y58083D02*
X207608Y58333D01*
X207900Y58458D01*
X208233Y58500D01*
X208650Y58417D01*
X208942Y58208D01*
X209025Y57958D01*
X208983Y57708D01*
X208817Y57500D01*
X207983Y57083D01*
X207608Y56792D01*
X207358Y56375D01*
X207275Y56000D01*
X209025D01*
G01X212900Y59400D02*
Y55400D01*
X220300D01*
G01X289017Y64500D02*
Y67000D01*
X290058D01*
X290392Y66875D01*
X290600Y66708D01*
X290683Y66375D01*
X290600Y66042D01*
X290350Y65833D01*
X290058Y65708D01*
X289017D01*
G01X290058D02*
X290683Y64500D01*
G01X292158Y65542D02*
X292450Y65833D01*
X292700Y66000D01*
X293033Y66083D01*
X293325Y66000D01*
X293533Y65833D01*
X293700Y65583D01*
X293742Y65292D01*
X293700Y65042D01*
X293533Y64792D01*
X293283Y64583D01*
X292992Y64500D01*
X292658Y64583D01*
X292367Y64833D01*
X292200Y65208D01*
X292158Y65625D01*
X292242Y66167D01*
X292367Y66458D01*
X292575Y66750D01*
X292867Y66958D01*
X293158Y67000D01*
X293450Y66917D01*
X293658Y66708D01*
G01X296050Y64500D02*
X296342Y64542D01*
X296675Y64667D01*
X296883Y64875D01*
X296967Y65167D01*
X296883Y65458D01*
X296633Y65708D01*
X296258Y65833D01*
X295842D01*
X295592Y65917D01*
X295383Y66125D01*
X295300Y66417D01*
X295425Y66708D01*
X295717Y66917D01*
X296050Y67000D01*
X296383Y66917D01*
X296675Y66708D01*
X296800Y66417D01*
X296717Y66125D01*
X296508Y65917D01*
X296258Y65833D01*
X295842D01*
X295467Y65708D01*
X295217Y65458D01*
X295133Y65167D01*
X295217Y64875D01*
X295425Y64667D01*
X295758Y64542D01*
X296050Y64500D01*
G01X298358Y66583D02*
X298608Y66833D01*
X298900Y66958D01*
X299233Y67000D01*
X299650Y66917D01*
X299942Y66708D01*
X300025Y66458D01*
X299983Y66208D01*
X299817Y66000D01*
X298983Y65583D01*
X298608Y65292D01*
X298358Y64875D01*
X298275Y64500D01*
X300025D01*
G01X204500Y54700D02*
X220600D01*
G01X204500Y47700D02*
Y54700D01*
G01X220600Y47700D02*
X204500D01*
G01X220600Y54700D02*
Y47700D01*
G01X198500Y61350D02*
X198458Y61017D01*
X198292Y60725D01*
X198042Y60475D01*
X197750Y60308D01*
X197417Y60225D01*
X197083D01*
X196750Y60308D01*
X196458Y60475D01*
X196208Y60725D01*
X196042Y61017D01*
X196000Y61350D01*
X196042Y61683D01*
X196208Y61975D01*
X196458Y62225D01*
X196750Y62392D01*
X197083Y62475D01*
X197417D01*
X197750Y62392D01*
X198042Y62225D01*
X198292Y61975D01*
X198458Y61683D01*
X198500Y61350D01*
G01X197833Y61683D02*
X198500Y62183D01*
G01Y64450D02*
X196000D01*
X196500Y63950D01*
G01X198500D02*
Y64950D01*
G01X196417Y66758D02*
X196167Y67008D01*
X196042Y67300D01*
X196000Y67633D01*
X196083Y68050D01*
X196292Y68342D01*
X196542Y68425D01*
X196792Y68383D01*
X197000Y68217D01*
X197417Y67383D01*
X197708Y67008D01*
X198125Y66758D01*
X198500Y66675D01*
Y68425D01*
G01X198125Y69733D02*
X198333Y69983D01*
X198458Y70275D01*
X198500Y70650D01*
X198417Y71025D01*
X198250Y71317D01*
X197958Y71525D01*
X197625Y71567D01*
X197292Y71483D01*
X197083Y71275D01*
X196917Y70983D01*
X196875Y70692D01*
X196917Y70400D01*
X197083Y70025D01*
X196000Y70150D01*
Y71275D01*
G01X200300Y71200D02*
Y59800D01*
G01X213700Y71200D02*
X200300D01*
G01X213700Y59800D02*
Y71200D01*
G01X200300Y59800D02*
X213700D01*
G01X250435Y131867D02*
X250310Y131617D01*
X250227Y131325D01*
Y130992D01*
X250352Y130617D01*
X250560Y130325D01*
X250810Y130117D01*
X251227Y129950D01*
X251602Y129908D01*
X251977Y129992D01*
X252227Y130117D01*
X252477Y130367D01*
X252644Y130658D01*
X252727Y130950D01*
Y131242D01*
X252644Y131533D01*
X252519Y131783D01*
X252352Y131992D01*
G01X252227Y133133D02*
X252519Y133383D01*
X252685Y133717D01*
X252727Y134092D01*
X252685Y134425D01*
X252477Y134758D01*
X252227Y134967D01*
X251977Y135008D01*
X251685Y134925D01*
X251477Y134633D01*
X251394Y134342D01*
Y133967D01*
G01Y134342D02*
X251269Y134592D01*
X251060Y134800D01*
X250810Y134883D01*
X250560Y134800D01*
X250352Y134592D01*
X250227Y134217D01*
X250269Y133842D01*
X250435Y133467D01*
G01X251685Y136358D02*
X251394Y136650D01*
X251227Y136900D01*
X251144Y137233D01*
X251227Y137525D01*
X251394Y137733D01*
X251644Y137900D01*
X251935Y137942D01*
X252185Y137900D01*
X252435Y137733D01*
X252644Y137483D01*
X252727Y137192D01*
X252644Y136858D01*
X252394Y136567D01*
X252019Y136400D01*
X251602Y136358D01*
X251060Y136442D01*
X250769Y136567D01*
X250477Y136775D01*
X250269Y137067D01*
X250227Y137358D01*
X250310Y137650D01*
X250519Y137858D01*
G01X250644Y139458D02*
X250394Y139708D01*
X250269Y140000D01*
X250227Y140333D01*
X250310Y140750D01*
X250519Y141042D01*
X250769Y141125D01*
X251019Y141083D01*
X251227Y140917D01*
X251644Y140083D01*
X251935Y139708D01*
X252352Y139458D01*
X252727Y139375D01*
Y141125D01*
G01X291767Y101953D02*
X291517Y102078D01*
X291225Y102161D01*
X290892D01*
X290517Y102036D01*
X290225Y101828D01*
X290017Y101578D01*
X289850Y101161D01*
X289808Y100786D01*
X289892Y100411D01*
X290017Y100161D01*
X290267Y99911D01*
X290558Y99744D01*
X290850Y99661D01*
X291142D01*
X291433Y99744D01*
X291683Y99869D01*
X291892Y100036D01*
G01X293033Y100161D02*
X293283Y99869D01*
X293617Y99703D01*
X293992Y99661D01*
X294325Y99703D01*
X294658Y99911D01*
X294867Y100161D01*
X294908Y100411D01*
X294825Y100703D01*
X294533Y100911D01*
X294242Y100994D01*
X293867D01*
G01X294242D02*
X294492Y101119D01*
X294700Y101328D01*
X294783Y101578D01*
X294700Y101828D01*
X294492Y102036D01*
X294117Y102161D01*
X293742Y102119D01*
X293367Y101953D01*
G01X296967Y99661D02*
X297050Y100203D01*
X297175Y100661D01*
X297342Y101078D01*
X297550Y101536D01*
X297883Y102161D01*
X296217D01*
G01X300067Y99661D02*
X300150Y100203D01*
X300275Y100661D01*
X300442Y101078D01*
X300650Y101536D01*
X300983Y102161D01*
X299317D01*
G01X256727Y130117D02*
X254227D01*
Y131158D01*
X254352Y131492D01*
X254519Y131700D01*
X254852Y131783D01*
X255185Y131700D01*
X255394Y131450D01*
X255519Y131158D01*
Y130117D01*
G01Y131158D02*
X256727Y131783D01*
G01X255685Y133258D02*
X255394Y133550D01*
X255227Y133800D01*
X255144Y134133D01*
X255227Y134425D01*
X255394Y134633D01*
X255644Y134800D01*
X255935Y134842D01*
X256185Y134800D01*
X256435Y134633D01*
X256644Y134383D01*
X256727Y134092D01*
X256644Y133758D01*
X256394Y133467D01*
X256019Y133300D01*
X255602Y133258D01*
X255060Y133342D01*
X254769Y133467D01*
X254477Y133675D01*
X254269Y133967D01*
X254227Y134258D01*
X254310Y134550D01*
X254519Y134758D01*
G01X256727Y137650D02*
X254227D01*
X256019Y136108D01*
Y138192D01*
G01X256352Y139333D02*
X256560Y139583D01*
X256685Y139875D01*
X256727Y140250D01*
X256644Y140625D01*
X256477Y140917D01*
X256185Y141125D01*
X255852Y141167D01*
X255519Y141083D01*
X255310Y140875D01*
X255144Y140583D01*
X255102Y140292D01*
X255144Y140000D01*
X255310Y139625D01*
X254227Y139750D01*
Y140875D01*
G01X252900Y120900D02*
X256900D01*
Y128300D01*
G01X290017Y95661D02*
Y98161D01*
X291058D01*
X291392Y98036D01*
X291600Y97869D01*
X291683Y97536D01*
X291600Y97203D01*
X291350Y96994D01*
X291058Y96869D01*
X290017D01*
G01X291058D02*
X291683Y95661D01*
G01X293158Y96703D02*
X293450Y96994D01*
X293700Y97161D01*
X294033Y97244D01*
X294325Y97161D01*
X294533Y96994D01*
X294700Y96744D01*
X294742Y96453D01*
X294700Y96203D01*
X294533Y95953D01*
X294283Y95744D01*
X293992Y95661D01*
X293658Y95744D01*
X293367Y95994D01*
X293200Y96369D01*
X293158Y96786D01*
X293242Y97328D01*
X293367Y97619D01*
X293575Y97911D01*
X293867Y98119D01*
X294158Y98161D01*
X294450Y98078D01*
X294658Y97869D01*
G01X297050Y95661D02*
X297342Y95703D01*
X297675Y95828D01*
X297883Y96036D01*
X297967Y96328D01*
X297883Y96619D01*
X297633Y96869D01*
X297258Y96994D01*
X296842D01*
X296592Y97078D01*
X296383Y97286D01*
X296300Y97578D01*
X296425Y97869D01*
X296717Y98078D01*
X297050Y98161D01*
X297383Y98078D01*
X297675Y97869D01*
X297800Y97578D01*
X297717Y97286D01*
X297508Y97078D01*
X297258Y96994D01*
X296842D01*
X296467Y96869D01*
X296217Y96619D01*
X296133Y96328D01*
X296217Y96036D01*
X296425Y95828D01*
X296758Y95703D01*
X297050Y95661D01*
G01X299233Y96161D02*
X299483Y95869D01*
X299817Y95703D01*
X300192Y95661D01*
X300525Y95703D01*
X300858Y95911D01*
X301067Y96161D01*
X301108Y96411D01*
X301025Y96703D01*
X300733Y96911D01*
X300442Y96994D01*
X300067D01*
G01X300442D02*
X300692Y97119D01*
X300900Y97328D01*
X300983Y97578D01*
X300900Y97828D01*
X300692Y98036D01*
X300317Y98161D01*
X299942Y98119D01*
X299567Y97953D01*
G01X197067Y155792D02*
X196817Y155917D01*
X196525Y156000D01*
X196192D01*
X195817Y155875D01*
X195525Y155667D01*
X195317Y155417D01*
X195150Y155000D01*
X195108Y154625D01*
X195192Y154250D01*
X195317Y154000D01*
X195567Y153750D01*
X195858Y153583D01*
X196150Y153500D01*
X196442D01*
X196733Y153583D01*
X196983Y153708D01*
X197192Y153875D01*
G01X198333Y154000D02*
X198583Y153708D01*
X198917Y153542D01*
X199292Y153500D01*
X199625Y153542D01*
X199958Y153750D01*
X200167Y154000D01*
X200208Y154250D01*
X200125Y154542D01*
X199833Y154750D01*
X199542Y154833D01*
X199167D01*
G01X199542D02*
X199792Y154958D01*
X200000Y155167D01*
X200083Y155417D01*
X200000Y155667D01*
X199792Y155875D01*
X199417Y156000D01*
X199042Y155958D01*
X198667Y155792D01*
G01X201433Y153875D02*
X201683Y153667D01*
X201975Y153542D01*
X202350Y153500D01*
X202725Y153583D01*
X203017Y153750D01*
X203225Y154042D01*
X203267Y154375D01*
X203183Y154708D01*
X202975Y154917D01*
X202683Y155083D01*
X202392Y155125D01*
X202100Y155083D01*
X201725Y154917D01*
X201850Y156000D01*
X202975D01*
G01X204533Y153875D02*
X204783Y153667D01*
X205075Y153542D01*
X205450Y153500D01*
X205825Y153583D01*
X206117Y153750D01*
X206325Y154042D01*
X206367Y154375D01*
X206283Y154708D01*
X206075Y154917D01*
X205783Y155083D01*
X205492Y155125D01*
X205200Y155083D01*
X204825Y154917D01*
X204950Y156000D01*
X206075D01*
G01X207267Y183792D02*
X207017Y183917D01*
X206725Y184000D01*
X206392D01*
X206017Y183875D01*
X205725Y183667D01*
X205517Y183417D01*
X205350Y183000D01*
X205308Y182625D01*
X205392Y182250D01*
X205517Y182000D01*
X205767Y181750D01*
X206058Y181583D01*
X206350Y181500D01*
X206642D01*
X206933Y181583D01*
X207183Y181708D01*
X207392Y181875D01*
G01X208533Y182000D02*
X208783Y181708D01*
X209117Y181542D01*
X209492Y181500D01*
X209825Y181542D01*
X210158Y181750D01*
X210367Y182000D01*
X210408Y182250D01*
X210325Y182542D01*
X210033Y182750D01*
X209742Y182833D01*
X209367D01*
G01X209742D02*
X209992Y182958D01*
X210200Y183167D01*
X210283Y183417D01*
X210200Y183667D01*
X209992Y183875D01*
X209617Y184000D01*
X209242Y183958D01*
X208867Y183792D01*
G01X211758Y182542D02*
X212050Y182833D01*
X212300Y183000D01*
X212633Y183083D01*
X212925Y183000D01*
X213133Y182833D01*
X213300Y182583D01*
X213342Y182292D01*
X213300Y182042D01*
X213133Y181792D01*
X212883Y181583D01*
X212592Y181500D01*
X212258Y181583D01*
X211967Y181833D01*
X211800Y182208D01*
X211758Y182625D01*
X211842Y183167D01*
X211967Y183458D01*
X212175Y183750D01*
X212467Y183958D01*
X212758Y184000D01*
X213050Y183917D01*
X213258Y183708D01*
G01X215650Y181500D02*
Y184000D01*
X215150Y183500D01*
G01Y181500D02*
X216150D01*
G01X254800Y163000D02*
Y160500D01*
G01X253842Y163000D02*
X255758D01*
G01X257067Y160500D02*
Y163000D01*
X258067D01*
X258400Y162875D01*
X258650Y162583D01*
X258733Y162250D01*
X258650Y161917D01*
X258442Y161667D01*
X258067Y161542D01*
X257067D01*
G01X261000Y160500D02*
Y163000D01*
X260500Y162500D01*
G01Y160500D02*
X261500D01*
G01X264600D02*
Y163000D01*
X263058Y161208D01*
X265142D01*
G01X266408Y161542D02*
X266700Y161833D01*
X266950Y162000D01*
X267283Y162083D01*
X267575Y162000D01*
X267783Y161833D01*
X267950Y161583D01*
X267992Y161292D01*
X267950Y161042D01*
X267783Y160792D01*
X267533Y160583D01*
X267242Y160500D01*
X266908Y160583D01*
X266617Y160833D01*
X266450Y161208D01*
X266408Y161625D01*
X266492Y162167D01*
X266617Y162458D01*
X266825Y162750D01*
X267117Y162958D01*
X267408Y163000D01*
X267700Y162917D01*
X267908Y162708D01*
G01X202350Y118500D02*
X202017Y118542D01*
X201725Y118708D01*
X201475Y118958D01*
X201308Y119250D01*
X201225Y119583D01*
Y119917D01*
X201308Y120250D01*
X201475Y120542D01*
X201725Y120792D01*
X202017Y120958D01*
X202350Y121000D01*
X202683Y120958D01*
X202975Y120792D01*
X203225Y120542D01*
X203392Y120250D01*
X203475Y119917D01*
Y119583D01*
X203392Y119250D01*
X203225Y118958D01*
X202975Y118708D01*
X202683Y118542D01*
X202350Y118500D01*
G01X202683Y119167D02*
X203183Y118500D01*
G01X205450D02*
Y121000D01*
X204950Y120500D01*
G01Y118500D02*
X205950D01*
G01X207758Y120583D02*
X208008Y120833D01*
X208300Y120958D01*
X208633Y121000D01*
X209050Y120917D01*
X209342Y120708D01*
X209425Y120458D01*
X209383Y120208D01*
X209217Y120000D01*
X208383Y119583D01*
X208008Y119292D01*
X207758Y118875D01*
X207675Y118500D01*
X209425D01*
G01X212150D02*
Y121000D01*
X210608Y119208D01*
X212692D01*
G01X216200Y101500D02*
X214100Y103300D01*
X216200Y105500D01*
G01X216300Y109100D02*
X197100D01*
Y97900D01*
X216300D01*
Y109100D01*
X215900D01*
G01X266000Y136017D02*
X263500D01*
Y137058D01*
X263625Y137392D01*
X263792Y137600D01*
X264125Y137683D01*
X264458Y137600D01*
X264667Y137350D01*
X264792Y137058D01*
Y136017D01*
G01Y137058D02*
X266000Y137683D01*
G01X264958Y139158D02*
X264667Y139450D01*
X264500Y139700D01*
X264417Y140033D01*
X264500Y140325D01*
X264667Y140533D01*
X264917Y140700D01*
X265208Y140742D01*
X265458Y140700D01*
X265708Y140533D01*
X265917Y140283D01*
X266000Y139992D01*
X265917Y139658D01*
X265667Y139367D01*
X265292Y139200D01*
X264875Y139158D01*
X264333Y139242D01*
X264042Y139367D01*
X263750Y139575D01*
X263542Y139867D01*
X263500Y140158D01*
X263583Y140450D01*
X263792Y140658D01*
G01X266000Y143550D02*
X263500D01*
X265292Y142008D01*
Y144092D01*
G01X265708Y145442D02*
X265917Y145733D01*
X266000Y146067D01*
X265917Y146400D01*
X265667Y146692D01*
X265292Y146900D01*
X264917Y146983D01*
X264458D01*
X264083Y146900D01*
X263750Y146692D01*
X263583Y146442D01*
X263500Y146150D01*
X263583Y145817D01*
X263750Y145567D01*
X264000Y145400D01*
X264333Y145317D01*
X264625Y145400D01*
X264917Y145608D01*
X265083Y145858D01*
X265125Y146150D01*
X265042Y146483D01*
X264833Y146733D01*
X264458Y146983D01*
G01X211800Y122000D02*
X206300D01*
G01X211800Y130000D02*
Y122000D01*
G01X206300Y130000D02*
X211800D01*
G01X210017Y141000D02*
Y143500D01*
X211058D01*
X211392Y143375D01*
X211600Y143208D01*
X211683Y142875D01*
X211600Y142542D01*
X211350Y142333D01*
X211058Y142208D01*
X210017D01*
G01X211058D02*
X211683Y141000D01*
G01X213158Y142042D02*
X213450Y142333D01*
X213700Y142500D01*
X214033Y142583D01*
X214325Y142500D01*
X214533Y142333D01*
X214700Y142083D01*
X214742Y141792D01*
X214700Y141542D01*
X214533Y141292D01*
X214283Y141083D01*
X213992Y141000D01*
X213658Y141083D01*
X213367Y141333D01*
X213200Y141708D01*
X213158Y142125D01*
X213242Y142667D01*
X213367Y142958D01*
X213575Y143250D01*
X213867Y143458D01*
X214158Y143500D01*
X214450Y143417D01*
X214658Y143208D01*
G01X217550Y141000D02*
Y143500D01*
X216008Y141708D01*
X218092D01*
G01X220650Y141000D02*
Y143500D01*
X219108Y141708D01*
X221192D01*
G01X213500Y139800D02*
X221500D01*
Y122200D01*
X213500D01*
Y139800D01*
G01X195517Y157000D02*
Y159500D01*
X196558D01*
X196892Y159375D01*
X197100Y159208D01*
X197183Y158875D01*
X197100Y158542D01*
X196850Y158333D01*
X196558Y158208D01*
X195517D01*
G01X196558D02*
X197183Y157000D01*
G01X198658Y158042D02*
X198950Y158333D01*
X199200Y158500D01*
X199533Y158583D01*
X199825Y158500D01*
X200033Y158333D01*
X200200Y158083D01*
X200242Y157792D01*
X200200Y157542D01*
X200033Y157292D01*
X199783Y157083D01*
X199492Y157000D01*
X199158Y157083D01*
X198867Y157333D01*
X198700Y157708D01*
X198658Y158125D01*
X198742Y158667D01*
X198867Y158958D01*
X199075Y159250D01*
X199367Y159458D01*
X199658Y159500D01*
X199950Y159417D01*
X200158Y159208D01*
G01X203050Y157000D02*
Y159500D01*
X201508Y157708D01*
X203592D01*
G01X204858Y158042D02*
X205150Y158333D01*
X205400Y158500D01*
X205733Y158583D01*
X206025Y158500D01*
X206233Y158333D01*
X206400Y158083D01*
X206442Y157792D01*
X206400Y157542D01*
X206233Y157292D01*
X205983Y157083D01*
X205692Y157000D01*
X205358Y157083D01*
X205067Y157333D01*
X204900Y157708D01*
X204858Y158125D01*
X204942Y158667D01*
X205067Y158958D01*
X205275Y159250D01*
X205567Y159458D01*
X205858Y159500D01*
X206150Y159417D01*
X206358Y159208D01*
G01X204267Y172792D02*
X204017Y172917D01*
X203725Y173000D01*
X203392D01*
X203017Y172875D01*
X202725Y172667D01*
X202517Y172417D01*
X202350Y172000D01*
X202308Y171625D01*
X202392Y171250D01*
X202517Y171000D01*
X202767Y170750D01*
X203058Y170583D01*
X203350Y170500D01*
X203642D01*
X203933Y170583D01*
X204183Y170708D01*
X204392Y170875D01*
G01X205533Y171000D02*
X205783Y170708D01*
X206117Y170542D01*
X206492Y170500D01*
X206825Y170542D01*
X207158Y170750D01*
X207367Y171000D01*
X207408Y171250D01*
X207325Y171542D01*
X207033Y171750D01*
X206742Y171833D01*
X206367D01*
G01X206742D02*
X206992Y171958D01*
X207200Y172167D01*
X207283Y172417D01*
X207200Y172667D01*
X206992Y172875D01*
X206617Y173000D01*
X206242Y172958D01*
X205867Y172792D01*
G01X208758Y171542D02*
X209050Y171833D01*
X209300Y172000D01*
X209633Y172083D01*
X209925Y172000D01*
X210133Y171833D01*
X210300Y171583D01*
X210342Y171292D01*
X210300Y171042D01*
X210133Y170792D01*
X209883Y170583D01*
X209592Y170500D01*
X209258Y170583D01*
X208967Y170833D01*
X208800Y171208D01*
X208758Y171625D01*
X208842Y172167D01*
X208967Y172458D01*
X209175Y172750D01*
X209467Y172958D01*
X209758Y173000D01*
X210050Y172917D01*
X210258Y172708D01*
G01X212650Y173000D02*
X212317Y172917D01*
X212067Y172708D01*
X211900Y172458D01*
X211775Y172125D01*
X211733Y171750D01*
X211775Y171375D01*
X211900Y171042D01*
X212067Y170792D01*
X212317Y170583D01*
X212650Y170500D01*
X212983Y170583D01*
X213233Y170792D01*
X213400Y171042D01*
X213525Y171375D01*
X213567Y171750D01*
X213525Y172125D01*
X213400Y172458D01*
X213233Y172708D01*
X212983Y172917D01*
X212650Y173000D01*
G01X223775Y208566D02*
Y211066D01*
G01X225525D02*
Y208566D01*
G01Y209816D02*
X223775D01*
G01X226833Y208566D02*
Y211066D01*
X227667D01*
X228000Y210941D01*
X228250Y210774D01*
X228458Y210524D01*
X228625Y210233D01*
X228667Y209816D01*
X228625Y209399D01*
X228458Y209108D01*
X228250Y208858D01*
X228000Y208691D01*
X227667Y208566D01*
X226833D01*
G01X229933D02*
Y211066D01*
X230767D01*
X231100Y210941D01*
X231350Y210774D01*
X231558Y210524D01*
X231725Y210233D01*
X231767Y209816D01*
X231725Y209399D01*
X231558Y209108D01*
X231350Y208858D01*
X231100Y208691D01*
X230767Y208566D01*
X229933D01*
G01X233075Y208899D02*
X233408Y208691D01*
X233783Y208566D01*
X234117D01*
X234450Y208691D01*
X234700Y208899D01*
X234825Y209191D01*
X234742Y209483D01*
X234533Y209733D01*
X234158Y209899D01*
X233658Y209983D01*
X233367Y210149D01*
X233242Y210441D01*
X233325Y210733D01*
X233533Y210941D01*
X233825Y211066D01*
X234117D01*
X234408Y210983D01*
X234658Y210774D01*
G01X236008Y208566D02*
X237050Y211066D01*
X238092Y208566D01*
G01X237717Y209441D02*
X236383D01*
G01X239275Y208899D02*
X239608Y208691D01*
X239983Y208566D01*
X240317D01*
X240650Y208691D01*
X240900Y208899D01*
X241025Y209191D01*
X240942Y209483D01*
X240733Y209733D01*
X240358Y209899D01*
X239858Y209983D01*
X239567Y210149D01*
X239442Y210441D01*
X239525Y210733D01*
X239733Y210941D01*
X240025Y211066D01*
X240317D01*
X240608Y210983D01*
X240858Y210774D01*
G01X242458Y210649D02*
X242708Y210899D01*
X243000Y211024D01*
X243333Y211066D01*
X243750Y210983D01*
X244042Y210774D01*
X244125Y210524D01*
X244083Y210274D01*
X243917Y210066D01*
X243083Y209649D01*
X242708Y209358D01*
X242458Y208941D01*
X242375Y208566D01*
X244125D01*
G01X245433Y208941D02*
X245683Y208733D01*
X245975Y208608D01*
X246350Y208566D01*
X246725Y208649D01*
X247017Y208816D01*
X247225Y209108D01*
X247267Y209441D01*
X247183Y209774D01*
X246975Y209983D01*
X246683Y210149D01*
X246392Y210191D01*
X246100Y210149D01*
X245725Y209983D01*
X245850Y211066D01*
X246975D01*
G01X218336Y560075D02*
X223386D01*
Y658775D01*
X248036D01*
Y474375D01*
X223386D01*
Y533075D01*
X218336D01*
Y560075D01*
G01X215050Y441279D02*
X214800Y441404D01*
X214508Y441487D01*
X214175D01*
X213800Y441362D01*
X213508Y441154D01*
X213300Y440904D01*
X213133Y440487D01*
X213091Y440112D01*
X213175Y439737D01*
X213300Y439487D01*
X213550Y439237D01*
X213841Y439070D01*
X214133Y438987D01*
X214425D01*
X214716Y439070D01*
X214966Y439195D01*
X215175Y439362D01*
G01X216441Y440029D02*
X216733Y440320D01*
X216983Y440487D01*
X217316Y440570D01*
X217608Y440487D01*
X217816Y440320D01*
X217983Y440070D01*
X218025Y439779D01*
X217983Y439529D01*
X217816Y439279D01*
X217566Y439070D01*
X217275Y438987D01*
X216941Y439070D01*
X216650Y439320D01*
X216483Y439695D01*
X216441Y440112D01*
X216525Y440654D01*
X216650Y440945D01*
X216858Y441237D01*
X217150Y441445D01*
X217441Y441487D01*
X217733Y441404D01*
X217941Y441195D01*
G01X220833Y438987D02*
Y441487D01*
X219291Y439695D01*
X221375D01*
G01X222516Y439487D02*
X222766Y439195D01*
X223100Y439029D01*
X223475Y438987D01*
X223808Y439029D01*
X224141Y439237D01*
X224350Y439487D01*
X224391Y439737D01*
X224308Y440029D01*
X224016Y440237D01*
X223725Y440320D01*
X223350D01*
G01X223725D02*
X223975Y440445D01*
X224183Y440654D01*
X224266Y440904D01*
X224183Y441154D01*
X223975Y441362D01*
X223600Y441487D01*
X223225Y441445D01*
X222850Y441279D01*
G01X215022Y436252D02*
X214772Y436377D01*
X214480Y436460D01*
X214147D01*
X213772Y436335D01*
X213480Y436127D01*
X213272Y435877D01*
X213105Y435460D01*
X213063Y435085D01*
X213147Y434710D01*
X213272Y434460D01*
X213522Y434210D01*
X213813Y434043D01*
X214105Y433960D01*
X214397D01*
X214688Y434043D01*
X214938Y434168D01*
X215147Y434335D01*
G01X216413Y435002D02*
X216705Y435293D01*
X216955Y435460D01*
X217288Y435543D01*
X217580Y435460D01*
X217788Y435293D01*
X217955Y435043D01*
X217997Y434752D01*
X217955Y434502D01*
X217788Y434252D01*
X217538Y434043D01*
X217247Y433960D01*
X216913Y434043D01*
X216622Y434293D01*
X216455Y434668D01*
X216413Y435085D01*
X216497Y435627D01*
X216622Y435918D01*
X216830Y436210D01*
X217122Y436418D01*
X217413Y436460D01*
X217705Y436377D01*
X217913Y436168D01*
G01X220805Y433960D02*
Y436460D01*
X219263Y434668D01*
X221347D01*
G01X223905Y433960D02*
Y436460D01*
X222363Y434668D01*
X224447D01*
G01X202090Y479989D02*
X198090D01*
Y472589D01*
G01X209590Y472189D02*
Y476189D01*
X202190D01*
G01X215394Y464364D02*
Y466864D01*
X216435D01*
X216769Y466739D01*
X216977Y466572D01*
X217060Y466239D01*
X216977Y465906D01*
X216727Y465697D01*
X216435Y465572D01*
X215394D01*
G01X216435D02*
X217060Y464364D01*
G01X219327D02*
Y466864D01*
X218827Y466364D01*
G01Y464364D02*
X219827D01*
G01X222427D02*
Y466864D01*
X221927Y466364D01*
G01Y464364D02*
X222927D01*
G01X224735Y466447D02*
X224985Y466697D01*
X225277Y466822D01*
X225610Y466864D01*
X226027Y466781D01*
X226319Y466572D01*
X226402Y466322D01*
X226360Y466072D01*
X226194Y465864D01*
X225360Y465447D01*
X224985Y465156D01*
X224735Y464739D01*
X224652Y464364D01*
X226402D01*
G01X228627D02*
Y466864D01*
X228127Y466364D01*
G01Y464364D02*
X229127D01*
G01X209549Y463814D02*
Y467814D01*
X202149D01*
G01X274696Y382160D02*
Y384660D01*
X275737D01*
X276071Y384535D01*
X276279Y384368D01*
X276362Y384035D01*
X276279Y383702D01*
X276029Y383493D01*
X275737Y383368D01*
X274696D01*
G01X275737D02*
X276362Y382160D01*
G01X277712Y382660D02*
X277962Y382368D01*
X278296Y382202D01*
X278671Y382160D01*
X279004Y382202D01*
X279337Y382410D01*
X279546Y382660D01*
X279587Y382910D01*
X279504Y383202D01*
X279212Y383410D01*
X278921Y383493D01*
X278546D01*
G01X278921D02*
X279171Y383618D01*
X279379Y383827D01*
X279462Y384077D01*
X279379Y384327D01*
X279171Y384535D01*
X278796Y384660D01*
X278421Y384618D01*
X278046Y384452D01*
G01X281646Y382160D02*
X281729Y382702D01*
X281854Y383160D01*
X282021Y383577D01*
X282229Y384035D01*
X282562Y384660D01*
X280896D01*
G01X285329Y382160D02*
Y384660D01*
X283787Y382868D01*
X285871D01*
G01X296492Y381482D02*
Y385482D01*
X289092D01*
G01X198517Y406500D02*
Y409000D01*
X199558D01*
X199892Y408875D01*
X200100Y408708D01*
X200183Y408375D01*
X200100Y408042D01*
X199850Y407833D01*
X199558Y407708D01*
X198517D01*
G01X199558D02*
X200183Y406500D01*
G01X201533Y407000D02*
X201783Y406708D01*
X202117Y406542D01*
X202492Y406500D01*
X202825Y406542D01*
X203158Y406750D01*
X203367Y407000D01*
X203408Y407250D01*
X203325Y407542D01*
X203033Y407750D01*
X202742Y407833D01*
X202367D01*
G01X202742D02*
X202992Y407958D01*
X203200Y408167D01*
X203283Y408417D01*
X203200Y408667D01*
X202992Y408875D01*
X202617Y409000D01*
X202242Y408958D01*
X201867Y408792D01*
G01X204758Y407542D02*
X205050Y407833D01*
X205300Y408000D01*
X205633Y408083D01*
X205925Y408000D01*
X206133Y407833D01*
X206300Y407583D01*
X206342Y407292D01*
X206300Y407042D01*
X206133Y406792D01*
X205883Y406583D01*
X205592Y406500D01*
X205258Y406583D01*
X204967Y406833D01*
X204800Y407208D01*
X204758Y407625D01*
X204842Y408167D01*
X204967Y408458D01*
X205175Y408750D01*
X205467Y408958D01*
X205758Y409000D01*
X206050Y408917D01*
X206258Y408708D01*
G01X207733Y406875D02*
X207983Y406667D01*
X208275Y406542D01*
X208650Y406500D01*
X209025Y406583D01*
X209317Y406750D01*
X209525Y407042D01*
X209567Y407375D01*
X209483Y407708D01*
X209275Y407917D01*
X208983Y408083D01*
X208692Y408125D01*
X208400Y408083D01*
X208025Y407917D01*
X208150Y409000D01*
X209275D01*
G01X209525Y400959D02*
Y404959D01*
X202125D01*
G01X219300Y472000D02*
Y469500D01*
G01X218342Y472000D02*
X220258D01*
G01X221567Y469500D02*
Y472000D01*
X222567D01*
X222900Y471875D01*
X223150Y471583D01*
X223233Y471250D01*
X223150Y470917D01*
X222942Y470667D01*
X222567Y470542D01*
X221567D01*
G01X224708Y471583D02*
X224958Y471833D01*
X225250Y471958D01*
X225583Y472000D01*
X226000Y471917D01*
X226292Y471708D01*
X226375Y471458D01*
X226333Y471208D01*
X226167Y471000D01*
X225333Y470583D01*
X224958Y470292D01*
X224708Y469875D01*
X224625Y469500D01*
X226375D01*
G01X228600Y472000D02*
X228267Y471917D01*
X228017Y471708D01*
X227850Y471458D01*
X227725Y471125D01*
X227683Y470750D01*
X227725Y470375D01*
X227850Y470042D01*
X228017Y469792D01*
X228267Y469583D01*
X228600Y469500D01*
X228933Y469583D01*
X229183Y469792D01*
X229350Y470042D01*
X229475Y470375D01*
X229517Y470750D01*
X229475Y471125D01*
X229350Y471458D01*
X229183Y471708D01*
X228933Y471917D01*
X228600Y472000D01*
G01X230783Y470000D02*
X231033Y469708D01*
X231367Y469542D01*
X231742Y469500D01*
X232075Y469542D01*
X232408Y469750D01*
X232617Y470000D01*
X232658Y470250D01*
X232575Y470542D01*
X232283Y470750D01*
X231992Y470833D01*
X231617D01*
G01X231992D02*
X232242Y470958D01*
X232450Y471167D01*
X232533Y471417D01*
X232450Y471667D01*
X232242Y471875D01*
X231867Y472000D01*
X231492Y471958D01*
X231117Y471792D01*
G01X198927Y437331D02*
X196427D01*
Y438372D01*
X196552Y438706D01*
X196719Y438914D01*
X197052Y438997D01*
X197385Y438914D01*
X197594Y438664D01*
X197719Y438372D01*
Y437331D01*
G01Y438372D02*
X198927Y438997D01*
G01Y441264D02*
X196427D01*
X196927Y440764D01*
G01X198927D02*
Y441764D01*
G01Y444364D02*
X196427D01*
X196927Y443864D01*
G01X198927D02*
Y444864D01*
G01X196844Y446672D02*
X196594Y446922D01*
X196469Y447214D01*
X196427Y447547D01*
X196510Y447964D01*
X196719Y448256D01*
X196969Y448339D01*
X197219Y448297D01*
X197427Y448131D01*
X197844Y447297D01*
X198135Y446922D01*
X198552Y446672D01*
X198927Y446589D01*
Y448339D01*
G01X196427Y450564D02*
X196510Y450231D01*
X196719Y449981D01*
X196969Y449814D01*
X197302Y449689D01*
X197677Y449647D01*
X198052Y449689D01*
X198385Y449814D01*
X198635Y449981D01*
X198844Y450231D01*
X198927Y450564D01*
X198844Y450897D01*
X198635Y451147D01*
X198385Y451314D01*
X198052Y451439D01*
X197677Y451481D01*
X197302Y451439D01*
X196969Y451314D01*
X196719Y451147D01*
X196510Y450897D01*
X196427Y450564D01*
G01X214800Y400117D02*
X212300D01*
Y401158D01*
X212425Y401492D01*
X212592Y401700D01*
X212925Y401783D01*
X213258Y401700D01*
X213467Y401450D01*
X213592Y401158D01*
Y400117D01*
G01Y401158D02*
X214800Y401783D01*
G01X214300Y403133D02*
X214592Y403383D01*
X214758Y403717D01*
X214800Y404092D01*
X214758Y404425D01*
X214550Y404758D01*
X214300Y404967D01*
X214050Y405008D01*
X213758Y404925D01*
X213550Y404633D01*
X213467Y404342D01*
Y403967D01*
G01Y404342D02*
X213342Y404592D01*
X213133Y404800D01*
X212883Y404883D01*
X212633Y404800D01*
X212425Y404592D01*
X212300Y404217D01*
X212342Y403842D01*
X212508Y403467D01*
G01X214508Y406442D02*
X214717Y406733D01*
X214800Y407067D01*
X214717Y407400D01*
X214467Y407692D01*
X214092Y407900D01*
X213717Y407983D01*
X213258D01*
X212883Y407900D01*
X212550Y407692D01*
X212383Y407442D01*
X212300Y407150D01*
X212383Y406817D01*
X212550Y406567D01*
X212800Y406400D01*
X213133Y406317D01*
X213425Y406400D01*
X213717Y406608D01*
X213883Y406858D01*
X213925Y407150D01*
X213842Y407483D01*
X213633Y407733D01*
X213258Y407983D01*
G01X212300Y410250D02*
X212383Y409917D01*
X212592Y409667D01*
X212842Y409500D01*
X213175Y409375D01*
X213550Y409333D01*
X213925Y409375D01*
X214258Y409500D01*
X214508Y409667D01*
X214717Y409917D01*
X214800Y410250D01*
X214717Y410583D01*
X214508Y410833D01*
X214258Y411000D01*
X213925Y411125D01*
X213550Y411167D01*
X213175Y411125D01*
X212842Y411000D01*
X212592Y410833D01*
X212383Y410583D01*
X212300Y410250D01*
G01X220040Y400162D02*
X217540D01*
Y401203D01*
X217665Y401537D01*
X217832Y401745D01*
X218165Y401828D01*
X218498Y401745D01*
X218707Y401495D01*
X218832Y401203D01*
Y400162D01*
G01Y401203D02*
X220040Y401828D01*
G01X219540Y403178D02*
X219832Y403428D01*
X219998Y403762D01*
X220040Y404137D01*
X219998Y404470D01*
X219790Y404803D01*
X219540Y405012D01*
X219290Y405053D01*
X218998Y404970D01*
X218790Y404678D01*
X218707Y404387D01*
Y404012D01*
G01Y404387D02*
X218582Y404637D01*
X218373Y404845D01*
X218123Y404928D01*
X217873Y404845D01*
X217665Y404637D01*
X217540Y404262D01*
X217582Y403887D01*
X217748Y403512D01*
G01X219748Y406487D02*
X219957Y406778D01*
X220040Y407112D01*
X219957Y407445D01*
X219707Y407737D01*
X219332Y407945D01*
X218957Y408028D01*
X218498D01*
X218123Y407945D01*
X217790Y407737D01*
X217623Y407487D01*
X217540Y407195D01*
X217623Y406862D01*
X217790Y406612D01*
X218040Y406445D01*
X218373Y406362D01*
X218665Y406445D01*
X218957Y406653D01*
X219123Y406903D01*
X219165Y407195D01*
X219082Y407528D01*
X218873Y407778D01*
X218498Y408028D01*
G01X220040Y410212D02*
X219498Y410295D01*
X219040Y410420D01*
X218623Y410587D01*
X218165Y410795D01*
X217540Y411128D01*
Y409462D01*
G01X199350Y381000D02*
X199017Y381042D01*
X198725Y381208D01*
X198475Y381458D01*
X198308Y381750D01*
X198225Y382083D01*
Y382417D01*
X198308Y382750D01*
X198475Y383042D01*
X198725Y383292D01*
X199017Y383458D01*
X199350Y383500D01*
X199683Y383458D01*
X199975Y383292D01*
X200225Y383042D01*
X200392Y382750D01*
X200475Y382417D01*
Y382083D01*
X200392Y381750D01*
X200225Y381458D01*
X199975Y381208D01*
X199683Y381042D01*
X199350Y381000D01*
G01X199683Y381667D02*
X200183Y381000D01*
G01X201658Y383083D02*
X201908Y383333D01*
X202200Y383458D01*
X202533Y383500D01*
X202950Y383417D01*
X203242Y383208D01*
X203325Y382958D01*
X203283Y382708D01*
X203117Y382500D01*
X202283Y382083D01*
X201908Y381792D01*
X201658Y381375D01*
X201575Y381000D01*
X203325D01*
G01X204633Y381500D02*
X204883Y381208D01*
X205217Y381042D01*
X205592Y381000D01*
X205925Y381042D01*
X206258Y381250D01*
X206467Y381500D01*
X206508Y381750D01*
X206425Y382042D01*
X206133Y382250D01*
X205842Y382333D01*
X205467D01*
G01X205842D02*
X206092Y382458D01*
X206300Y382667D01*
X206383Y382917D01*
X206300Y383167D01*
X206092Y383375D01*
X205717Y383500D01*
X205342Y383458D01*
X204967Y383292D01*
G01X207858Y383083D02*
X208108Y383333D01*
X208400Y383458D01*
X208733Y383500D01*
X209150Y383417D01*
X209442Y383208D01*
X209525Y382958D01*
X209483Y382708D01*
X209317Y382500D01*
X208483Y382083D01*
X208108Y381792D01*
X207858Y381375D01*
X207775Y381000D01*
X209525D01*
G01X210200Y385600D02*
Y399600D01*
G01X197200Y385600D02*
X210200D01*
G01X197200Y399600D02*
Y385600D01*
G01X210200Y399600D02*
X197200D01*
G01X282350Y401500D02*
X282017Y401542D01*
X281725Y401708D01*
X281475Y401958D01*
X281308Y402250D01*
X281225Y402583D01*
Y402917D01*
X281308Y403250D01*
X281475Y403542D01*
X281725Y403792D01*
X282017Y403958D01*
X282350Y404000D01*
X282683Y403958D01*
X282975Y403792D01*
X283225Y403542D01*
X283392Y403250D01*
X283475Y402917D01*
Y402583D01*
X283392Y402250D01*
X283225Y401958D01*
X282975Y401708D01*
X282683Y401542D01*
X282350Y401500D01*
G01X282683Y402167D02*
X283183Y401500D01*
G01X284658Y403583D02*
X284908Y403833D01*
X285200Y403958D01*
X285533Y404000D01*
X285950Y403917D01*
X286242Y403708D01*
X286325Y403458D01*
X286283Y403208D01*
X286117Y403000D01*
X285283Y402583D01*
X284908Y402292D01*
X284658Y401875D01*
X284575Y401500D01*
X286325D01*
G01X287633Y401875D02*
X287883Y401667D01*
X288175Y401542D01*
X288550Y401500D01*
X288925Y401583D01*
X289217Y401750D01*
X289425Y402042D01*
X289467Y402375D01*
X289383Y402708D01*
X289175Y402917D01*
X288883Y403083D01*
X288592Y403125D01*
X288300Y403083D01*
X287925Y402917D01*
X288050Y404000D01*
X289175D01*
G01X291567Y401500D02*
X291650Y402042D01*
X291775Y402500D01*
X291942Y402917D01*
X292150Y403375D01*
X292483Y404000D01*
X290817D01*
G01X283792Y386707D02*
X297792D01*
G01X283792Y399707D02*
Y386707D01*
G01X297792Y399707D02*
X283792D01*
G01X196092Y386407D02*
Y399407D01*
G01X195521Y431139D02*
Y438139D01*
G01X263288Y510428D02*
X263038Y510553D01*
X262746Y510636D01*
X262413D01*
X262038Y510511D01*
X261746Y510303D01*
X261538Y510053D01*
X261371Y509636D01*
X261329Y509261D01*
X261413Y508886D01*
X261538Y508636D01*
X261788Y508386D01*
X262079Y508219D01*
X262371Y508136D01*
X262663D01*
X262954Y508219D01*
X263204Y508344D01*
X263413Y508511D01*
G01X265471Y508136D02*
Y510636D01*
X264971Y510136D01*
G01Y508136D02*
X265971D01*
G01X267863Y508428D02*
X268154Y508219D01*
X268488Y508136D01*
X268821Y508219D01*
X269113Y508469D01*
X269321Y508844D01*
X269404Y509219D01*
Y509678D01*
X269321Y510053D01*
X269113Y510386D01*
X268863Y510553D01*
X268571Y510636D01*
X268238Y510553D01*
X267988Y510386D01*
X267821Y510136D01*
X267738Y509803D01*
X267821Y509511D01*
X268029Y509219D01*
X268279Y509053D01*
X268571Y509011D01*
X268904Y509094D01*
X269154Y509303D01*
X269404Y509678D01*
G01X271671Y508136D02*
X271963Y508178D01*
X272296Y508303D01*
X272504Y508511D01*
X272588Y508803D01*
X272504Y509094D01*
X272254Y509344D01*
X271879Y509469D01*
X271463D01*
X271213Y509553D01*
X271004Y509761D01*
X270921Y510053D01*
X271046Y510344D01*
X271338Y510553D01*
X271671Y510636D01*
X272004Y510553D01*
X272296Y510344D01*
X272421Y510053D01*
X272338Y509761D01*
X272129Y509553D01*
X271879Y509469D01*
X271463D01*
X271088Y509344D01*
X270838Y509094D01*
X270754Y508803D01*
X270838Y508511D01*
X271046Y508303D01*
X271379Y508178D01*
X271671Y508136D01*
G01X263267Y514792D02*
X263017Y514917D01*
X262725Y515000D01*
X262392D01*
X262017Y514875D01*
X261725Y514667D01*
X261517Y514417D01*
X261350Y514000D01*
X261308Y513625D01*
X261392Y513250D01*
X261517Y513000D01*
X261767Y512750D01*
X262058Y512583D01*
X262350Y512500D01*
X262642D01*
X262933Y512583D01*
X263183Y512708D01*
X263392Y512875D01*
G01X265450Y512500D02*
Y515000D01*
X264950Y514500D01*
G01Y512500D02*
X265950D01*
G01X267842Y512792D02*
X268133Y512583D01*
X268467Y512500D01*
X268800Y512583D01*
X269092Y512833D01*
X269300Y513208D01*
X269383Y513583D01*
Y514042D01*
X269300Y514417D01*
X269092Y514750D01*
X268842Y514917D01*
X268550Y515000D01*
X268217Y514917D01*
X267967Y514750D01*
X267800Y514500D01*
X267717Y514167D01*
X267800Y513875D01*
X268008Y513583D01*
X268258Y513417D01*
X268550Y513375D01*
X268883Y513458D01*
X269133Y513667D01*
X269383Y514042D01*
G01X271567Y512500D02*
X271650Y513042D01*
X271775Y513500D01*
X271942Y513917D01*
X272150Y514375D01*
X272483Y515000D01*
X270817D01*
G01X291767Y554453D02*
X291517Y554578D01*
X291225Y554661D01*
X290892D01*
X290517Y554536D01*
X290225Y554328D01*
X290017Y554078D01*
X289850Y553661D01*
X289808Y553286D01*
X289892Y552911D01*
X290017Y552661D01*
X290267Y552411D01*
X290558Y552244D01*
X290850Y552161D01*
X291142D01*
X291433Y552244D01*
X291683Y552369D01*
X291892Y552536D01*
G01X293158Y554244D02*
X293408Y554494D01*
X293700Y554619D01*
X294033Y554661D01*
X294450Y554578D01*
X294742Y554369D01*
X294825Y554119D01*
X294783Y553869D01*
X294617Y553661D01*
X293783Y553244D01*
X293408Y552953D01*
X293158Y552536D01*
X293075Y552161D01*
X294825D01*
G01X296258Y554244D02*
X296508Y554494D01*
X296800Y554619D01*
X297133Y554661D01*
X297550Y554578D01*
X297842Y554369D01*
X297925Y554119D01*
X297883Y553869D01*
X297717Y553661D01*
X296883Y553244D01*
X296508Y552953D01*
X296258Y552536D01*
X296175Y552161D01*
X297925D01*
G01X300150D02*
Y554661D01*
X299650Y554161D01*
G01Y552161D02*
X300650D01*
G01X208017Y505500D02*
Y508000D01*
X209058D01*
X209392Y507875D01*
X209600Y507708D01*
X209683Y507375D01*
X209600Y507042D01*
X209350Y506833D01*
X209058Y506708D01*
X208017D01*
G01X209058D02*
X209683Y505500D01*
G01X211033Y506000D02*
X211283Y505708D01*
X211617Y505542D01*
X211992Y505500D01*
X212325Y505542D01*
X212658Y505750D01*
X212867Y506000D01*
X212908Y506250D01*
X212825Y506542D01*
X212533Y506750D01*
X212242Y506833D01*
X211867D01*
G01X212242D02*
X212492Y506958D01*
X212700Y507167D01*
X212783Y507417D01*
X212700Y507667D01*
X212492Y507875D01*
X212117Y508000D01*
X211742Y507958D01*
X211367Y507792D01*
G01X214967Y505500D02*
X215050Y506042D01*
X215175Y506500D01*
X215342Y506917D01*
X215550Y507375D01*
X215883Y508000D01*
X214217D01*
G01X218067Y505500D02*
X218150Y506042D01*
X218275Y506500D01*
X218442Y506917D01*
X218650Y507375D01*
X218983Y508000D01*
X217317D01*
G01X218100Y523200D02*
Y527200D01*
X210700D01*
G01X208017Y501500D02*
Y504000D01*
X209058D01*
X209392Y503875D01*
X209600Y503708D01*
X209683Y503375D01*
X209600Y503042D01*
X209350Y502833D01*
X209058Y502708D01*
X208017D01*
G01X209058D02*
X209683Y501500D01*
G01X211033Y502000D02*
X211283Y501708D01*
X211617Y501542D01*
X211992Y501500D01*
X212325Y501542D01*
X212658Y501750D01*
X212867Y502000D01*
X212908Y502250D01*
X212825Y502542D01*
X212533Y502750D01*
X212242Y502833D01*
X211867D01*
G01X212242D02*
X212492Y502958D01*
X212700Y503167D01*
X212783Y503417D01*
X212700Y503667D01*
X212492Y503875D01*
X212117Y504000D01*
X211742Y503958D01*
X211367Y503792D01*
G01X214967Y501500D02*
X215050Y502042D01*
X215175Y502500D01*
X215342Y502917D01*
X215550Y503375D01*
X215883Y504000D01*
X214217D01*
G01X217442Y501792D02*
X217733Y501583D01*
X218067Y501500D01*
X218400Y501583D01*
X218692Y501833D01*
X218900Y502208D01*
X218983Y502583D01*
Y503042D01*
X218900Y503417D01*
X218692Y503750D01*
X218442Y503917D01*
X218150Y504000D01*
X217817Y503917D01*
X217567Y503750D01*
X217400Y503500D01*
X217317Y503167D01*
X217400Y502875D01*
X217608Y502583D01*
X217858Y502417D01*
X218150Y502375D01*
X218483Y502458D01*
X218733Y502667D01*
X218983Y503042D01*
G01X216600Y514600D02*
Y518600D01*
X209200D01*
G01X208017Y509500D02*
Y512000D01*
X209058D01*
X209392Y511875D01*
X209600Y511708D01*
X209683Y511375D01*
X209600Y511042D01*
X209350Y510833D01*
X209058Y510708D01*
X208017D01*
G01X209058D02*
X209683Y509500D01*
G01X211033Y510000D02*
X211283Y509708D01*
X211617Y509542D01*
X211992Y509500D01*
X212325Y509542D01*
X212658Y509750D01*
X212867Y510000D01*
X212908Y510250D01*
X212825Y510542D01*
X212533Y510750D01*
X212242Y510833D01*
X211867D01*
G01X212242D02*
X212492Y510958D01*
X212700Y511167D01*
X212783Y511417D01*
X212700Y511667D01*
X212492Y511875D01*
X212117Y512000D01*
X211742Y511958D01*
X211367Y511792D01*
G01X215050Y509500D02*
X215342Y509542D01*
X215675Y509667D01*
X215883Y509875D01*
X215967Y510167D01*
X215883Y510458D01*
X215633Y510708D01*
X215258Y510833D01*
X214842D01*
X214592Y510917D01*
X214383Y511125D01*
X214300Y511417D01*
X214425Y511708D01*
X214717Y511917D01*
X215050Y512000D01*
X215383Y511917D01*
X215675Y511708D01*
X215800Y511417D01*
X215717Y511125D01*
X215508Y510917D01*
X215258Y510833D01*
X214842D01*
X214467Y510708D01*
X214217Y510458D01*
X214133Y510167D01*
X214217Y509875D01*
X214425Y509667D01*
X214758Y509542D01*
X215050Y509500D01*
G01X218150D02*
Y512000D01*
X217650Y511500D01*
G01Y509500D02*
X218650D01*
G01X210800Y531500D02*
Y527500D01*
X218200D01*
G01X198000Y501517D02*
X195500D01*
Y502558D01*
X195625Y502892D01*
X195792Y503100D01*
X196125Y503183D01*
X196458Y503100D01*
X196667Y502850D01*
X196792Y502558D01*
Y501517D01*
G01Y502558D02*
X198000Y503183D01*
G01X197500Y504533D02*
X197792Y504783D01*
X197958Y505117D01*
X198000Y505492D01*
X197958Y505825D01*
X197750Y506158D01*
X197500Y506367D01*
X197250Y506408D01*
X196958Y506325D01*
X196750Y506033D01*
X196667Y505742D01*
Y505367D01*
G01Y505742D02*
X196542Y505992D01*
X196333Y506200D01*
X196083Y506283D01*
X195833Y506200D01*
X195625Y505992D01*
X195500Y505617D01*
X195542Y505242D01*
X195708Y504867D01*
G01X198000Y508550D02*
X197958Y508842D01*
X197833Y509175D01*
X197625Y509383D01*
X197333Y509467D01*
X197042Y509383D01*
X196792Y509133D01*
X196667Y508758D01*
Y508342D01*
X196583Y508092D01*
X196375Y507883D01*
X196083Y507800D01*
X195792Y507925D01*
X195583Y508217D01*
X195500Y508550D01*
X195583Y508883D01*
X195792Y509175D01*
X196083Y509300D01*
X196375Y509217D01*
X196583Y509008D01*
X196667Y508758D01*
Y508342D01*
X196792Y507967D01*
X197042Y507717D01*
X197333Y507633D01*
X197625Y507717D01*
X197833Y507925D01*
X197958Y508258D01*
X198000Y508550D01*
G01X196958Y510858D02*
X196667Y511150D01*
X196500Y511400D01*
X196417Y511733D01*
X196500Y512025D01*
X196667Y512233D01*
X196917Y512400D01*
X197208Y512442D01*
X197458Y512400D01*
X197708Y512233D01*
X197917Y511983D01*
X198000Y511692D01*
X197917Y511358D01*
X197667Y511067D01*
X197292Y510900D01*
X196875Y510858D01*
X196333Y510942D01*
X196042Y511067D01*
X195750Y511275D01*
X195542Y511567D01*
X195500Y511858D01*
X195583Y512150D01*
X195792Y512358D01*
G01X290017Y548161D02*
Y550661D01*
X291058D01*
X291392Y550536D01*
X291600Y550369D01*
X291683Y550036D01*
X291600Y549703D01*
X291350Y549494D01*
X291058Y549369D01*
X290017D01*
G01X291058D02*
X291683Y548161D01*
G01X294450D02*
Y550661D01*
X292908Y548869D01*
X294992D01*
G01X297050Y550661D02*
X296717Y550578D01*
X296467Y550369D01*
X296300Y550119D01*
X296175Y549786D01*
X296133Y549411D01*
X296175Y549036D01*
X296300Y548703D01*
X296467Y548453D01*
X296717Y548244D01*
X297050Y548161D01*
X297383Y548244D01*
X297633Y548453D01*
X297800Y548703D01*
X297925Y549036D01*
X297967Y549411D01*
X297925Y549786D01*
X297800Y550119D01*
X297633Y550369D01*
X297383Y550578D01*
X297050Y550661D01*
G01X300067Y548161D02*
X300150Y548703D01*
X300275Y549161D01*
X300442Y549578D01*
X300650Y550036D01*
X300983Y550661D01*
X299317D01*
G01X199394Y483864D02*
Y486364D01*
X200435D01*
X200769Y486239D01*
X200977Y486072D01*
X201060Y485739D01*
X200977Y485406D01*
X200727Y485197D01*
X200435Y485072D01*
X199394D01*
G01X200435D02*
X201060Y483864D01*
G01X203327D02*
Y486364D01*
X202827Y485864D01*
G01Y483864D02*
X203827D01*
G01X206427D02*
Y486364D01*
X205927Y485864D01*
G01Y483864D02*
X206927D01*
G01X209527D02*
Y486364D01*
X209027Y485864D01*
G01Y483864D02*
X210027D01*
G01X211835Y484906D02*
X212127Y485197D01*
X212377Y485364D01*
X212710Y485447D01*
X213002Y485364D01*
X213210Y485197D01*
X213377Y484947D01*
X213419Y484656D01*
X213377Y484406D01*
X213210Y484156D01*
X212960Y483947D01*
X212669Y483864D01*
X212335Y483947D01*
X212044Y484197D01*
X211877Y484572D01*
X211835Y484989D01*
X211919Y485531D01*
X212044Y485822D01*
X212252Y486114D01*
X212544Y486322D01*
X212835Y486364D01*
X213127Y486281D01*
X213335Y486072D01*
G01X204394Y477864D02*
Y480364D01*
X205435D01*
X205769Y480239D01*
X205977Y480072D01*
X206060Y479739D01*
X205977Y479406D01*
X205727Y479197D01*
X205435Y479072D01*
X204394D01*
G01X205435D02*
X206060Y477864D01*
G01X208327D02*
Y480364D01*
X207827Y479864D01*
G01Y477864D02*
X208827D01*
G01X211427D02*
Y480364D01*
X210927Y479864D01*
G01Y477864D02*
X211927D01*
G01X214527D02*
Y480364D01*
X214027Y479864D01*
G01Y477864D02*
X215027D01*
G01X217544D02*
X217627Y478406D01*
X217752Y478864D01*
X217919Y479281D01*
X218127Y479739D01*
X218460Y480364D01*
X216794D01*
G01X202400Y571000D02*
X202067Y571042D01*
X201775Y571208D01*
X201525Y571458D01*
X201358Y571750D01*
X201275Y572083D01*
Y572417D01*
X201358Y572750D01*
X201525Y573042D01*
X201775Y573292D01*
X202067Y573458D01*
X202400Y573500D01*
X202733Y573458D01*
X203025Y573292D01*
X203275Y573042D01*
X203442Y572750D01*
X203525Y572417D01*
Y572083D01*
X203442Y571750D01*
X203275Y571458D01*
X203025Y571208D01*
X202733Y571042D01*
X202400Y571000D01*
G01X202733Y571667D02*
X203233Y571000D01*
G01X204583Y571375D02*
X204833Y571167D01*
X205125Y571042D01*
X205500Y571000D01*
X205875Y571083D01*
X206167Y571250D01*
X206375Y571542D01*
X206417Y571875D01*
X206333Y572208D01*
X206125Y572417D01*
X205833Y572583D01*
X205542Y572625D01*
X205250Y572583D01*
X204875Y572417D01*
X205000Y573500D01*
X206125D01*
G01X208600Y571000D02*
Y573500D01*
X208100Y573000D01*
G01Y571000D02*
X209100D01*
G01X216200Y554000D02*
X214100Y555800D01*
X216200Y558000D01*
G01X216300Y561600D02*
X197100D01*
Y550400D01*
X216300D01*
Y561600D01*
X215900D01*
G01X198000Y528900D02*
X197958Y528567D01*
X197792Y528275D01*
X197542Y528025D01*
X197250Y527858D01*
X196917Y527775D01*
X196583D01*
X196250Y527858D01*
X195958Y528025D01*
X195708Y528275D01*
X195542Y528567D01*
X195500Y528900D01*
X195542Y529233D01*
X195708Y529525D01*
X195958Y529775D01*
X196250Y529942D01*
X196583Y530025D01*
X196917D01*
X197250Y529942D01*
X197542Y529775D01*
X197792Y529525D01*
X197958Y529233D01*
X198000Y528900D01*
G01X197333Y529233D02*
X198000Y529733D01*
G01X197625Y531083D02*
X197833Y531333D01*
X197958Y531625D01*
X198000Y532000D01*
X197917Y532375D01*
X197750Y532667D01*
X197458Y532875D01*
X197125Y532917D01*
X196792Y532833D01*
X196583Y532625D01*
X196417Y532333D01*
X196375Y532042D01*
X196417Y531750D01*
X196583Y531375D01*
X195500Y531500D01*
Y532625D01*
G01X197500Y534183D02*
X197792Y534433D01*
X197958Y534767D01*
X198000Y535142D01*
X197958Y535475D01*
X197750Y535808D01*
X197500Y536017D01*
X197250Y536058D01*
X196958Y535975D01*
X196750Y535683D01*
X196667Y535392D01*
Y535017D01*
G01Y535392D02*
X196542Y535642D01*
X196333Y535850D01*
X196083Y535933D01*
X195833Y535850D01*
X195625Y535642D01*
X195500Y535267D01*
X195542Y534892D01*
X195708Y534517D01*
G01X210200Y536200D02*
X198800D01*
G01X210200Y522800D02*
Y536200D01*
G01X198800Y522800D02*
X210200D01*
G01X198800Y536200D02*
Y522800D01*
G01X223775Y661500D02*
Y664000D01*
G01X225525D02*
Y661500D01*
G01Y662750D02*
X223775D01*
G01X226833Y661500D02*
Y664000D01*
X227667D01*
X228000Y663875D01*
X228250Y663708D01*
X228458Y663458D01*
X228625Y663167D01*
X228667Y662750D01*
X228625Y662333D01*
X228458Y662042D01*
X228250Y661792D01*
X228000Y661625D01*
X227667Y661500D01*
X226833D01*
G01X229933D02*
Y664000D01*
X230767D01*
X231100Y663875D01*
X231350Y663708D01*
X231558Y663458D01*
X231725Y663167D01*
X231767Y662750D01*
X231725Y662333D01*
X231558Y662042D01*
X231350Y661792D01*
X231100Y661625D01*
X230767Y661500D01*
X229933D01*
G01X233075Y661833D02*
X233408Y661625D01*
X233783Y661500D01*
X234117D01*
X234450Y661625D01*
X234700Y661833D01*
X234825Y662125D01*
X234742Y662417D01*
X234533Y662667D01*
X234158Y662833D01*
X233658Y662917D01*
X233367Y663083D01*
X233242Y663375D01*
X233325Y663667D01*
X233533Y663875D01*
X233825Y664000D01*
X234117D01*
X234408Y663917D01*
X234658Y663708D01*
G01X236008Y661500D02*
X237050Y664000D01*
X238092Y661500D01*
G01X237717Y662375D02*
X236383D01*
G01X239275Y661833D02*
X239608Y661625D01*
X239983Y661500D01*
X240317D01*
X240650Y661625D01*
X240900Y661833D01*
X241025Y662125D01*
X240942Y662417D01*
X240733Y662667D01*
X240358Y662833D01*
X239858Y662917D01*
X239567Y663083D01*
X239442Y663375D01*
X239525Y663667D01*
X239733Y663875D01*
X240025Y664000D01*
X240317D01*
X240608Y663917D01*
X240858Y663708D01*
G01X243250Y661500D02*
Y664000D01*
X242750Y663500D01*
G01Y661500D02*
X243750D01*
G01X245433Y662000D02*
X245683Y661708D01*
X246017Y661542D01*
X246392Y661500D01*
X246725Y661542D01*
X247058Y661750D01*
X247267Y662000D01*
X247308Y662250D01*
X247225Y662542D01*
X246933Y662750D01*
X246642Y662833D01*
X246267D01*
G01X246642D02*
X246892Y662958D01*
X247100Y663167D01*
X247183Y663417D01*
X247100Y663667D01*
X246892Y663875D01*
X246517Y664000D01*
X246142Y663958D01*
X245767Y663792D01*
G01X270767Y582953D02*
X270517Y583078D01*
X270225Y583161D01*
X269892D01*
X269517Y583036D01*
X269225Y582828D01*
X269017Y582578D01*
X268850Y582161D01*
X268808Y581786D01*
X268892Y581411D01*
X269017Y581161D01*
X269267Y580911D01*
X269558Y580744D01*
X269850Y580661D01*
X270142D01*
X270433Y580744D01*
X270683Y580869D01*
X270892Y581036D01*
G01X272158Y582744D02*
X272408Y582994D01*
X272700Y583119D01*
X273033Y583161D01*
X273450Y583078D01*
X273742Y582869D01*
X273825Y582619D01*
X273783Y582369D01*
X273617Y582161D01*
X272783Y581744D01*
X272408Y581453D01*
X272158Y581036D01*
X272075Y580661D01*
X273825D01*
G01X276050Y583161D02*
X275717Y583078D01*
X275467Y582869D01*
X275300Y582619D01*
X275175Y582286D01*
X275133Y581911D01*
X275175Y581536D01*
X275300Y581203D01*
X275467Y580953D01*
X275717Y580744D01*
X276050Y580661D01*
X276383Y580744D01*
X276633Y580953D01*
X276800Y581203D01*
X276925Y581536D01*
X276967Y581911D01*
X276925Y582286D01*
X276800Y582619D01*
X276633Y582869D01*
X276383Y583078D01*
X276050Y583161D01*
G01X278233Y581036D02*
X278483Y580828D01*
X278775Y580703D01*
X279150Y580661D01*
X279525Y580744D01*
X279817Y580911D01*
X280025Y581203D01*
X280067Y581536D01*
X279983Y581869D01*
X279775Y582078D01*
X279483Y582244D01*
X279192Y582286D01*
X278900Y582244D01*
X278525Y582078D01*
X278650Y583161D01*
X279775D01*
G01X269017Y584661D02*
Y587161D01*
X270058D01*
X270392Y587036D01*
X270600Y586869D01*
X270683Y586536D01*
X270600Y586203D01*
X270350Y585994D01*
X270058Y585869D01*
X269017D01*
G01X270058D02*
X270683Y584661D01*
G01X272033Y585161D02*
X272283Y584869D01*
X272617Y584703D01*
X272992Y584661D01*
X273325Y584703D01*
X273658Y584911D01*
X273867Y585161D01*
X273908Y585411D01*
X273825Y585703D01*
X273533Y585911D01*
X273242Y585994D01*
X272867D01*
G01X273242D02*
X273492Y586119D01*
X273700Y586328D01*
X273783Y586578D01*
X273700Y586828D01*
X273492Y587036D01*
X273117Y587161D01*
X272742Y587119D01*
X272367Y586953D01*
G01X275258Y585703D02*
X275550Y585994D01*
X275800Y586161D01*
X276133Y586244D01*
X276425Y586161D01*
X276633Y585994D01*
X276800Y585744D01*
X276842Y585453D01*
X276800Y585203D01*
X276633Y584953D01*
X276383Y584744D01*
X276092Y584661D01*
X275758Y584744D01*
X275467Y584994D01*
X275300Y585369D01*
X275258Y585786D01*
X275342Y586328D01*
X275467Y586619D01*
X275675Y586911D01*
X275967Y587119D01*
X276258Y587161D01*
X276550Y587078D01*
X276758Y586869D01*
G01X278442Y584953D02*
X278733Y584744D01*
X279067Y584661D01*
X279400Y584744D01*
X279692Y584994D01*
X279900Y585369D01*
X279983Y585744D01*
Y586203D01*
X279900Y586578D01*
X279692Y586911D01*
X279442Y587078D01*
X279150Y587161D01*
X278817Y587078D01*
X278567Y586911D01*
X278400Y586661D01*
X278317Y586328D01*
X278400Y586036D01*
X278608Y585744D01*
X278858Y585578D01*
X279150Y585536D01*
X279483Y585619D01*
X279733Y585828D01*
X279983Y586203D01*
G01X266700Y581000D02*
Y585000D01*
X259300D01*
G01X211708Y633767D02*
X211583Y633517D01*
X211500Y633225D01*
Y632892D01*
X211625Y632517D01*
X211833Y632225D01*
X212083Y632017D01*
X212500Y631850D01*
X212875Y631808D01*
X213250Y631892D01*
X213500Y632017D01*
X213750Y632267D01*
X213917Y632558D01*
X214000Y632850D01*
Y633142D01*
X213917Y633433D01*
X213792Y633683D01*
X213625Y633892D01*
G01X211917Y635158D02*
X211667Y635408D01*
X211542Y635700D01*
X211500Y636033D01*
X211583Y636450D01*
X211792Y636742D01*
X212042Y636825D01*
X212292Y636783D01*
X212500Y636617D01*
X212917Y635783D01*
X213208Y635408D01*
X213625Y635158D01*
X214000Y635075D01*
Y636825D01*
G01X211500Y639050D02*
X211583Y638717D01*
X211792Y638467D01*
X212042Y638300D01*
X212375Y638175D01*
X212750Y638133D01*
X213125Y638175D01*
X213458Y638300D01*
X213708Y638467D01*
X213917Y638717D01*
X214000Y639050D01*
X213917Y639383D01*
X213708Y639633D01*
X213458Y639800D01*
X213125Y639925D01*
X212750Y639967D01*
X212375Y639925D01*
X212042Y639800D01*
X211792Y639633D01*
X211583Y639383D01*
X211500Y639050D01*
G01X212958Y641358D02*
X212667Y641650D01*
X212500Y641900D01*
X212417Y642233D01*
X212500Y642525D01*
X212667Y642733D01*
X212917Y642900D01*
X213208Y642942D01*
X213458Y642900D01*
X213708Y642733D01*
X213917Y642483D01*
X214000Y642192D01*
X213917Y641858D01*
X213667Y641567D01*
X213292Y641400D01*
X212875Y641358D01*
X212333Y641442D01*
X212042Y641567D01*
X211750Y641775D01*
X211542Y642067D01*
X211500Y642358D01*
X211583Y642650D01*
X211792Y642858D01*
G01X257350Y617000D02*
Y614500D01*
G01X256392Y617000D02*
X258308D01*
G01X259617Y614500D02*
Y617000D01*
X260617D01*
X260950Y616875D01*
X261200Y616583D01*
X261283Y616250D01*
X261200Y615917D01*
X260992Y615667D01*
X260617Y615542D01*
X259617D01*
G01X263550Y614500D02*
X263842Y614542D01*
X264175Y614667D01*
X264383Y614875D01*
X264467Y615167D01*
X264383Y615458D01*
X264133Y615708D01*
X263758Y615833D01*
X263342D01*
X263092Y615917D01*
X262883Y616125D01*
X262800Y616417D01*
X262925Y616708D01*
X263217Y616917D01*
X263550Y617000D01*
X263883Y616917D01*
X264175Y616708D01*
X264300Y616417D01*
X264217Y616125D01*
X264008Y615917D01*
X263758Y615833D01*
X263342D01*
X262967Y615708D01*
X262717Y615458D01*
X262633Y615167D01*
X262717Y614875D01*
X262925Y614667D01*
X263258Y614542D01*
X263550Y614500D01*
G01X265858Y615542D02*
X266150Y615833D01*
X266400Y616000D01*
X266733Y616083D01*
X267025Y616000D01*
X267233Y615833D01*
X267400Y615583D01*
X267442Y615292D01*
X267400Y615042D01*
X267233Y614792D01*
X266983Y614583D01*
X266692Y614500D01*
X266358Y614583D01*
X266067Y614833D01*
X265900Y615208D01*
X265858Y615625D01*
X265942Y616167D01*
X266067Y616458D01*
X266275Y616750D01*
X266567Y616958D01*
X266858Y617000D01*
X267150Y616917D01*
X267358Y616708D01*
G01X286900Y571500D02*
X286567Y571542D01*
X286275Y571708D01*
X286025Y571958D01*
X285858Y572250D01*
X285775Y572583D01*
Y572917D01*
X285858Y573250D01*
X286025Y573542D01*
X286275Y573792D01*
X286567Y573958D01*
X286900Y574000D01*
X287233Y573958D01*
X287525Y573792D01*
X287775Y573542D01*
X287942Y573250D01*
X288025Y572917D01*
Y572583D01*
X287942Y572250D01*
X287775Y571958D01*
X287525Y571708D01*
X287233Y571542D01*
X286900Y571500D01*
G01X287233Y572167D02*
X287733Y571500D01*
G01X289208Y572542D02*
X289500Y572833D01*
X289750Y573000D01*
X290083Y573083D01*
X290375Y573000D01*
X290583Y572833D01*
X290750Y572583D01*
X290792Y572292D01*
X290750Y572042D01*
X290583Y571792D01*
X290333Y571583D01*
X290042Y571500D01*
X289708Y571583D01*
X289417Y571833D01*
X289250Y572208D01*
X289208Y572625D01*
X289292Y573167D01*
X289417Y573458D01*
X289625Y573750D01*
X289917Y573958D01*
X290208Y574000D01*
X290500Y573917D01*
X290708Y573708D01*
G01X293100Y574000D02*
X292767Y573917D01*
X292517Y573708D01*
X292350Y573458D01*
X292225Y573125D01*
X292183Y572750D01*
X292225Y572375D01*
X292350Y572042D01*
X292517Y571792D01*
X292767Y571583D01*
X293100Y571500D01*
X293433Y571583D01*
X293683Y571792D01*
X293850Y572042D01*
X293975Y572375D01*
X294017Y572750D01*
X293975Y573125D01*
X293850Y573458D01*
X293683Y573708D01*
X293433Y573917D01*
X293100Y574000D01*
G01X259517Y598500D02*
Y601000D01*
X260558D01*
X260892Y600875D01*
X261100Y600708D01*
X261183Y600375D01*
X261100Y600042D01*
X260850Y599833D01*
X260558Y599708D01*
X259517D01*
G01X260558D02*
X261183Y598500D01*
G01X262533Y599000D02*
X262783Y598708D01*
X263117Y598542D01*
X263492Y598500D01*
X263825Y598542D01*
X264158Y598750D01*
X264367Y599000D01*
X264408Y599250D01*
X264325Y599542D01*
X264033Y599750D01*
X263742Y599833D01*
X263367D01*
G01X263742D02*
X263992Y599958D01*
X264200Y600167D01*
X264283Y600417D01*
X264200Y600667D01*
X263992Y600875D01*
X263617Y601000D01*
X263242Y600958D01*
X262867Y600792D01*
G01X266467Y598500D02*
X266550Y599042D01*
X266675Y599500D01*
X266842Y599917D01*
X267050Y600375D01*
X267383Y601000D01*
X265717D01*
G01X268733Y599000D02*
X268983Y598708D01*
X269317Y598542D01*
X269692Y598500D01*
X270025Y598542D01*
X270358Y598750D01*
X270567Y599000D01*
X270608Y599250D01*
X270525Y599542D01*
X270233Y599750D01*
X269942Y599833D01*
X269567D01*
G01X269942D02*
X270192Y599958D01*
X270400Y600167D01*
X270483Y600417D01*
X270400Y600667D01*
X270192Y600875D01*
X269817Y601000D01*
X269442Y600958D01*
X269067Y600792D01*
G01X211800Y574500D02*
X206300D01*
G01X211800Y582500D02*
Y574500D01*
G01X206300Y582500D02*
X211800D01*
G01X219000Y593517D02*
X216500D01*
Y594558D01*
X216625Y594892D01*
X216792Y595100D01*
X217125Y595183D01*
X217458Y595100D01*
X217667Y594850D01*
X217792Y594558D01*
Y593517D01*
G01Y594558D02*
X219000Y595183D01*
G01X218500Y596533D02*
X218792Y596783D01*
X218958Y597117D01*
X219000Y597492D01*
X218958Y597825D01*
X218750Y598158D01*
X218500Y598367D01*
X218250Y598408D01*
X217958Y598325D01*
X217750Y598033D01*
X217667Y597742D01*
Y597367D01*
G01Y597742D02*
X217542Y597992D01*
X217333Y598200D01*
X217083Y598283D01*
X216833Y598200D01*
X216625Y597992D01*
X216500Y597617D01*
X216542Y597242D01*
X216708Y596867D01*
G01X217958Y599758D02*
X217667Y600050D01*
X217500Y600300D01*
X217417Y600633D01*
X217500Y600925D01*
X217667Y601133D01*
X217917Y601300D01*
X218208Y601342D01*
X218458Y601300D01*
X218708Y601133D01*
X218917Y600883D01*
X219000Y600592D01*
X218917Y600258D01*
X218667Y599967D01*
X218292Y599800D01*
X217875Y599758D01*
X217333Y599842D01*
X217042Y599967D01*
X216750Y600175D01*
X216542Y600467D01*
X216500Y600758D01*
X216583Y601050D01*
X216792Y601258D01*
G01X219000Y603650D02*
X218958Y603942D01*
X218833Y604275D01*
X218625Y604483D01*
X218333Y604567D01*
X218042Y604483D01*
X217792Y604233D01*
X217667Y603858D01*
Y603442D01*
X217583Y603192D01*
X217375Y602983D01*
X217083Y602900D01*
X216792Y603025D01*
X216583Y603317D01*
X216500Y603650D01*
X216583Y603983D01*
X216792Y604275D01*
X217083Y604400D01*
X217375Y604317D01*
X217583Y604108D01*
X217667Y603858D01*
Y603442D01*
X217792Y603067D01*
X218042Y602817D01*
X218333Y602733D01*
X218625Y602817D01*
X218833Y603025D01*
X218958Y603358D01*
X219000Y603650D01*
G01X213500Y592300D02*
X221500D01*
Y574700D01*
X213500D01*
Y592300D01*
G01X211547Y619767D02*
X211422Y619517D01*
X211339Y619225D01*
Y618892D01*
X211464Y618517D01*
X211672Y618225D01*
X211922Y618017D01*
X212339Y617850D01*
X212714Y617808D01*
X213089Y617892D01*
X213339Y618017D01*
X213589Y618267D01*
X213756Y618558D01*
X213839Y618850D01*
Y619142D01*
X213756Y619433D01*
X213631Y619683D01*
X213464Y619892D01*
G01X211756Y621158D02*
X211506Y621408D01*
X211381Y621700D01*
X211339Y622033D01*
X211422Y622450D01*
X211631Y622742D01*
X211881Y622825D01*
X212131Y622783D01*
X212339Y622617D01*
X212756Y621783D01*
X213047Y621408D01*
X213464Y621158D01*
X213839Y621075D01*
Y622825D01*
G01X211339Y625050D02*
X211422Y624717D01*
X211631Y624467D01*
X211881Y624300D01*
X212214Y624175D01*
X212589Y624133D01*
X212964Y624175D01*
X213297Y624300D01*
X213547Y624467D01*
X213756Y624717D01*
X213839Y625050D01*
X213756Y625383D01*
X213547Y625633D01*
X213297Y625800D01*
X212964Y625925D01*
X212589Y625967D01*
X212214Y625925D01*
X211881Y625800D01*
X211631Y625633D01*
X211422Y625383D01*
X211339Y625050D01*
G01X213839Y628650D02*
X211339D01*
X213131Y627108D01*
Y629192D01*
G01X276517Y835000D02*
Y837500D01*
X277558D01*
X277892Y837375D01*
X278100Y837208D01*
X278183Y836875D01*
X278100Y836542D01*
X277850Y836333D01*
X277558Y836208D01*
X276517D01*
G01X277558D02*
X278183Y835000D01*
G01X280450D02*
Y837500D01*
X279950Y837000D01*
G01Y835000D02*
X280950D01*
G01X283467D02*
X283550Y835542D01*
X283675Y836000D01*
X283842Y836417D01*
X284050Y836875D01*
X284383Y837500D01*
X282717D01*
G01X285858Y837083D02*
X286108Y837333D01*
X286400Y837458D01*
X286733Y837500D01*
X287150Y837417D01*
X287442Y837208D01*
X287525Y836958D01*
X287483Y836708D01*
X287317Y836500D01*
X286483Y836083D01*
X286108Y835792D01*
X285858Y835375D01*
X285775Y835000D01*
X287525D01*
G01X296492Y834182D02*
Y838182D01*
X289092D01*
G01X284650Y855500D02*
X284317Y855542D01*
X284025Y855708D01*
X283775Y855958D01*
X283608Y856250D01*
X283525Y856583D01*
Y856917D01*
X283608Y857250D01*
X283775Y857542D01*
X284025Y857792D01*
X284317Y857958D01*
X284650Y858000D01*
X284983Y857958D01*
X285275Y857792D01*
X285525Y857542D01*
X285692Y857250D01*
X285775Y856917D01*
Y856583D01*
X285692Y856250D01*
X285525Y855958D01*
X285275Y855708D01*
X284983Y855542D01*
X284650Y855500D01*
G01X284983Y856167D02*
X285483Y855500D01*
G01X286958Y857583D02*
X287208Y857833D01*
X287500Y857958D01*
X287833Y858000D01*
X288250Y857917D01*
X288542Y857708D01*
X288625Y857458D01*
X288583Y857208D01*
X288417Y857000D01*
X287583Y856583D01*
X287208Y856292D01*
X286958Y855875D01*
X286875Y855500D01*
X288625D01*
G01X291350D02*
Y858000D01*
X289808Y856208D01*
X291892D01*
G01X293033Y855875D02*
X293283Y855667D01*
X293575Y855542D01*
X293950Y855500D01*
X294325Y855583D01*
X294617Y855750D01*
X294825Y856042D01*
X294867Y856375D01*
X294783Y856708D01*
X294575Y856917D01*
X294283Y857083D01*
X293992Y857125D01*
X293700Y857083D01*
X293325Y856917D01*
X293450Y858000D01*
X294575D01*
G01X283792Y839407D02*
X297792D01*
G01X283792Y852407D02*
Y839407D01*
G01X297792Y852407D02*
X283792D01*
G01X218336Y1012831D02*
X223386D01*
Y1111531D01*
X248036D01*
Y927131D01*
X223386D01*
Y985831D01*
X218336D01*
Y1012831D01*
G01X263338Y963684D02*
X263088Y963809D01*
X262796Y963892D01*
X262463D01*
X262088Y963767D01*
X261796Y963559D01*
X261588Y963309D01*
X261421Y962892D01*
X261379Y962517D01*
X261463Y962142D01*
X261588Y961892D01*
X261838Y961642D01*
X262129Y961475D01*
X262421Y961392D01*
X262713D01*
X263004Y961475D01*
X263254Y961600D01*
X263463Y961767D01*
G01X266021Y961392D02*
Y963892D01*
X264479Y962100D01*
X266563D01*
G01X267829Y963475D02*
X268079Y963725D01*
X268371Y963850D01*
X268704Y963892D01*
X269121Y963809D01*
X269413Y963600D01*
X269496Y963350D01*
X269454Y963100D01*
X269288Y962892D01*
X268454Y962475D01*
X268079Y962184D01*
X267829Y961767D01*
X267746Y961392D01*
X269496D01*
G01X263317Y967792D02*
X263067Y967917D01*
X262775Y968000D01*
X262442D01*
X262067Y967875D01*
X261775Y967667D01*
X261567Y967417D01*
X261400Y967000D01*
X261358Y966625D01*
X261442Y966250D01*
X261567Y966000D01*
X261817Y965750D01*
X262108Y965583D01*
X262400Y965500D01*
X262692D01*
X262983Y965583D01*
X263233Y965708D01*
X263442Y965875D01*
G01X266000Y965500D02*
Y968000D01*
X264458Y966208D01*
X266542D01*
G01X268600Y965500D02*
Y968000D01*
X268100Y967500D01*
G01Y965500D02*
X269100D01*
G01X270017Y1032792D02*
X269767Y1032917D01*
X269475Y1033000D01*
X269142D01*
X268767Y1032875D01*
X268475Y1032667D01*
X268267Y1032417D01*
X268100Y1032000D01*
X268058Y1031625D01*
X268142Y1031250D01*
X268267Y1031000D01*
X268517Y1030750D01*
X268808Y1030583D01*
X269100Y1030500D01*
X269392D01*
X269683Y1030583D01*
X269933Y1030708D01*
X270142Y1030875D01*
G01X272700Y1030500D02*
Y1033000D01*
X271158Y1031208D01*
X273242D01*
G01X274383Y1031000D02*
X274633Y1030708D01*
X274967Y1030542D01*
X275342Y1030500D01*
X275675Y1030542D01*
X276008Y1030750D01*
X276217Y1031000D01*
X276258Y1031250D01*
X276175Y1031542D01*
X275883Y1031750D01*
X275592Y1031833D01*
X275217D01*
G01X275592D02*
X275842Y1031958D01*
X276050Y1032167D01*
X276133Y1032417D01*
X276050Y1032667D01*
X275842Y1032875D01*
X275467Y1033000D01*
X275092Y1032958D01*
X274717Y1032792D01*
G01X198500Y954517D02*
X196000D01*
Y955558D01*
X196125Y955892D01*
X196292Y956100D01*
X196625Y956183D01*
X196958Y956100D01*
X197167Y955850D01*
X197292Y955558D01*
Y954517D01*
G01Y955558D02*
X198500Y956183D01*
G01Y958450D02*
X196000D01*
X196500Y957950D01*
G01X198500D02*
Y958950D01*
G01Y961550D02*
X198458Y961842D01*
X198333Y962175D01*
X198125Y962383D01*
X197833Y962467D01*
X197542Y962383D01*
X197292Y962133D01*
X197167Y961758D01*
Y961342D01*
X197083Y961092D01*
X196875Y960883D01*
X196583Y960800D01*
X196292Y960925D01*
X196083Y961217D01*
X196000Y961550D01*
X196083Y961883D01*
X196292Y962175D01*
X196583Y962300D01*
X196875Y962217D01*
X197083Y962008D01*
X197167Y961758D01*
Y961342D01*
X197292Y960967D01*
X197542Y960717D01*
X197833Y960633D01*
X198125Y960717D01*
X198333Y960925D01*
X198458Y961258D01*
X198500Y961550D01*
G01Y964567D02*
X197958Y964650D01*
X197500Y964775D01*
X197083Y964942D01*
X196625Y965150D01*
X196000Y965483D01*
Y963817D01*
G01X199000Y974700D02*
X195000D01*
Y967300D01*
G01X209517Y954000D02*
Y956500D01*
X210558D01*
X210892Y956375D01*
X211100Y956208D01*
X211183Y955875D01*
X211100Y955542D01*
X210850Y955333D01*
X210558Y955208D01*
X209517D01*
G01X210558D02*
X211183Y954000D01*
G01X213450D02*
Y956500D01*
X212950Y956000D01*
G01Y954000D02*
X213950D01*
G01X216550D02*
X216842Y954042D01*
X217175Y954167D01*
X217383Y954375D01*
X217467Y954667D01*
X217383Y954958D01*
X217133Y955208D01*
X216758Y955333D01*
X216342D01*
X216092Y955417D01*
X215883Y955625D01*
X215800Y955917D01*
X215925Y956208D01*
X216217Y956417D01*
X216550Y956500D01*
X216883Y956417D01*
X217175Y956208D01*
X217300Y955917D01*
X217217Y955625D01*
X217008Y955417D01*
X216758Y955333D01*
X216342D01*
X215967Y955208D01*
X215717Y954958D01*
X215633Y954667D01*
X215717Y954375D01*
X215925Y954167D01*
X216258Y954042D01*
X216550Y954000D01*
G01X218858Y956083D02*
X219108Y956333D01*
X219400Y956458D01*
X219733Y956500D01*
X220150Y956417D01*
X220442Y956208D01*
X220525Y955958D01*
X220483Y955708D01*
X220317Y955500D01*
X219483Y955083D01*
X219108Y954792D01*
X218858Y954375D01*
X218775Y954000D01*
X220525D01*
G01X216300Y967700D02*
Y971700D01*
X208900D01*
G01X209517Y958000D02*
Y960500D01*
X210558D01*
X210892Y960375D01*
X211100Y960208D01*
X211183Y959875D01*
X211100Y959542D01*
X210850Y959333D01*
X210558Y959208D01*
X209517D01*
G01X210558D02*
X211183Y958000D01*
G01X213450D02*
Y960500D01*
X212950Y960000D01*
G01Y958000D02*
X213950D01*
G01X216550D02*
X216842Y958042D01*
X217175Y958167D01*
X217383Y958375D01*
X217467Y958667D01*
X217383Y958958D01*
X217133Y959208D01*
X216758Y959333D01*
X216342D01*
X216092Y959417D01*
X215883Y959625D01*
X215800Y959917D01*
X215925Y960208D01*
X216217Y960417D01*
X216550Y960500D01*
X216883Y960417D01*
X217175Y960208D01*
X217300Y959917D01*
X217217Y959625D01*
X217008Y959417D01*
X216758Y959333D01*
X216342D01*
X215967Y959208D01*
X215717Y958958D01*
X215633Y958667D01*
X215717Y958375D01*
X215925Y958167D01*
X216258Y958042D01*
X216550Y958000D01*
G01X219650Y960500D02*
X219317Y960417D01*
X219067Y960208D01*
X218900Y959958D01*
X218775Y959625D01*
X218733Y959250D01*
X218775Y958875D01*
X218900Y958542D01*
X219067Y958292D01*
X219317Y958083D01*
X219650Y958000D01*
X219983Y958083D01*
X220233Y958292D01*
X220400Y958542D01*
X220525Y958875D01*
X220567Y959250D01*
X220525Y959625D01*
X220400Y959958D01*
X220233Y960208D01*
X219983Y960417D01*
X219650Y960500D01*
G01X218700Y976100D02*
Y980100D01*
X211300D01*
G01X209517Y962000D02*
Y964500D01*
X210558D01*
X210892Y964375D01*
X211100Y964208D01*
X211183Y963875D01*
X211100Y963542D01*
X210850Y963333D01*
X210558Y963208D01*
X209517D01*
G01X210558D02*
X211183Y962000D01*
G01X213450D02*
Y964500D01*
X212950Y964000D01*
G01Y962000D02*
X213950D01*
G01X216550D02*
X216842Y962042D01*
X217175Y962167D01*
X217383Y962375D01*
X217467Y962667D01*
X217383Y962958D01*
X217133Y963208D01*
X216758Y963333D01*
X216342D01*
X216092Y963417D01*
X215883Y963625D01*
X215800Y963917D01*
X215925Y964208D01*
X216217Y964417D01*
X216550Y964500D01*
X216883Y964417D01*
X217175Y964208D01*
X217300Y963917D01*
X217217Y963625D01*
X217008Y963417D01*
X216758Y963333D01*
X216342D01*
X215967Y963208D01*
X215717Y962958D01*
X215633Y962667D01*
X215717Y962375D01*
X215925Y962167D01*
X216258Y962042D01*
X216550Y962000D01*
G01X218733Y962500D02*
X218983Y962208D01*
X219317Y962042D01*
X219692Y962000D01*
X220025Y962042D01*
X220358Y962250D01*
X220567Y962500D01*
X220608Y962750D01*
X220525Y963042D01*
X220233Y963250D01*
X219942Y963333D01*
X219567D01*
G01X219942D02*
X220192Y963458D01*
X220400Y963667D01*
X220483Y963917D01*
X220400Y964167D01*
X220192Y964375D01*
X219817Y964500D01*
X219442Y964458D01*
X219067Y964292D01*
G01X211300Y984500D02*
Y980500D01*
X218700D01*
G01X268217Y1035161D02*
Y1037661D01*
X269258D01*
X269592Y1037536D01*
X269800Y1037369D01*
X269883Y1037036D01*
X269800Y1036703D01*
X269550Y1036494D01*
X269258Y1036369D01*
X268217D01*
G01X269258D02*
X269883Y1035161D01*
G01X272150D02*
Y1037661D01*
X271650Y1037161D01*
G01Y1035161D02*
X272650D01*
G01X275167D02*
X275250Y1035703D01*
X275375Y1036161D01*
X275542Y1036578D01*
X275750Y1037036D01*
X276083Y1037661D01*
X274417D01*
G01X278850Y1035161D02*
Y1037661D01*
X277308Y1035869D01*
X279392D01*
G01X266400Y1034000D02*
Y1038000D01*
X259000D01*
G01X204650Y1024100D02*
X204317Y1024142D01*
X204025Y1024308D01*
X203775Y1024558D01*
X203608Y1024850D01*
X203525Y1025183D01*
Y1025517D01*
X203608Y1025850D01*
X203775Y1026142D01*
X204025Y1026392D01*
X204317Y1026558D01*
X204650Y1026600D01*
X204983Y1026558D01*
X205275Y1026392D01*
X205525Y1026142D01*
X205692Y1025850D01*
X205775Y1025517D01*
Y1025183D01*
X205692Y1024850D01*
X205525Y1024558D01*
X205275Y1024308D01*
X204983Y1024142D01*
X204650Y1024100D01*
G01X204983Y1024767D02*
X205483Y1024100D01*
G01X206958Y1026183D02*
X207208Y1026433D01*
X207500Y1026558D01*
X207833Y1026600D01*
X208250Y1026517D01*
X208542Y1026308D01*
X208625Y1026058D01*
X208583Y1025808D01*
X208417Y1025600D01*
X207583Y1025183D01*
X207208Y1024892D01*
X206958Y1024475D01*
X206875Y1024100D01*
X208625D01*
G01X216700Y1007000D02*
X214600Y1008800D01*
X216700Y1011000D01*
G01X216800Y1014600D02*
X197600D01*
Y1003400D01*
X216800D01*
Y1014600D01*
X216400D01*
G01X212300Y1027500D02*
X206800D01*
G01X212300Y1035500D02*
Y1027500D01*
G01X206800Y1035500D02*
X212300D01*
G01X198034Y982150D02*
X197992Y981817D01*
X197826Y981525D01*
X197576Y981275D01*
X197284Y981108D01*
X196951Y981025D01*
X196617D01*
X196284Y981108D01*
X195992Y981275D01*
X195742Y981525D01*
X195576Y981817D01*
X195534Y982150D01*
X195576Y982483D01*
X195742Y982775D01*
X195992Y983025D01*
X196284Y983192D01*
X196617Y983275D01*
X196951D01*
X197284Y983192D01*
X197576Y983025D01*
X197826Y982775D01*
X197992Y982483D01*
X198034Y982150D01*
G01X197367Y982483D02*
X198034Y982983D01*
G01X197534Y984333D02*
X197826Y984583D01*
X197992Y984917D01*
X198034Y985292D01*
X197992Y985625D01*
X197784Y985958D01*
X197534Y986167D01*
X197284Y986208D01*
X196992Y986125D01*
X196784Y985833D01*
X196701Y985542D01*
Y985167D01*
G01Y985542D02*
X196576Y985792D01*
X196367Y986000D01*
X196117Y986083D01*
X195867Y986000D01*
X195659Y985792D01*
X195534Y985417D01*
X195576Y985042D01*
X195742Y984667D01*
G01X210700Y989200D02*
X199300D01*
G01X210700Y975800D02*
Y989200D01*
G01X199300Y975800D02*
X210700D01*
G01X199300Y989200D02*
Y975800D01*
G01X219000Y1046517D02*
X216500D01*
Y1047558D01*
X216625Y1047892D01*
X216792Y1048100D01*
X217125Y1048183D01*
X217458Y1048100D01*
X217667Y1047850D01*
X217792Y1047558D01*
Y1046517D01*
G01Y1047558D02*
X219000Y1048183D01*
G01Y1050450D02*
X216500D01*
X217000Y1049950D01*
G01X219000D02*
Y1050950D01*
G01Y1053467D02*
X218458Y1053550D01*
X218000Y1053675D01*
X217583Y1053842D01*
X217125Y1054050D01*
X216500Y1054383D01*
Y1052717D01*
G01X218625Y1055733D02*
X218833Y1055983D01*
X218958Y1056275D01*
X219000Y1056650D01*
X218917Y1057025D01*
X218750Y1057317D01*
X218458Y1057525D01*
X218125Y1057567D01*
X217792Y1057483D01*
X217583Y1057275D01*
X217417Y1056983D01*
X217375Y1056692D01*
X217417Y1056400D01*
X217583Y1056025D01*
X216500Y1056150D01*
Y1057275D01*
G01X214000Y1045300D02*
X222000D01*
Y1027700D01*
X214000D01*
Y1045300D01*
G01X224825Y1116000D02*
Y1118500D01*
G01X226575D02*
Y1116000D01*
G01Y1117250D02*
X224825D01*
G01X227883Y1116000D02*
Y1118500D01*
X228717D01*
X229050Y1118375D01*
X229300Y1118208D01*
X229508Y1117958D01*
X229675Y1117667D01*
X229717Y1117250D01*
X229675Y1116833D01*
X229508Y1116542D01*
X229300Y1116292D01*
X229050Y1116125D01*
X228717Y1116000D01*
X227883D01*
G01X230983D02*
Y1118500D01*
X231817D01*
X232150Y1118375D01*
X232400Y1118208D01*
X232608Y1117958D01*
X232775Y1117667D01*
X232817Y1117250D01*
X232775Y1116833D01*
X232608Y1116542D01*
X232400Y1116292D01*
X232150Y1116125D01*
X231817Y1116000D01*
X230983D01*
G01X234125Y1116333D02*
X234458Y1116125D01*
X234833Y1116000D01*
X235167D01*
X235500Y1116125D01*
X235750Y1116333D01*
X235875Y1116625D01*
X235792Y1116917D01*
X235583Y1117167D01*
X235208Y1117333D01*
X234708Y1117417D01*
X234417Y1117583D01*
X234292Y1117875D01*
X234375Y1118167D01*
X234583Y1118375D01*
X234875Y1118500D01*
X235167D01*
X235458Y1118417D01*
X235708Y1118208D01*
G01X237058Y1116000D02*
X238100Y1118500D01*
X239142Y1116000D01*
G01X238767Y1116875D02*
X237433D01*
G01X240325Y1116333D02*
X240658Y1116125D01*
X241033Y1116000D01*
X241367D01*
X241700Y1116125D01*
X241950Y1116333D01*
X242075Y1116625D01*
X241992Y1116917D01*
X241783Y1117167D01*
X241408Y1117333D01*
X240908Y1117417D01*
X240617Y1117583D01*
X240492Y1117875D01*
X240575Y1118167D01*
X240783Y1118375D01*
X241075Y1118500D01*
X241367D01*
X241658Y1118417D01*
X241908Y1118208D01*
G01X244300Y1116000D02*
Y1118500D01*
X243800Y1118000D01*
G01Y1116000D02*
X244800D01*
G01X198217Y1059292D02*
X197967Y1059417D01*
X197675Y1059500D01*
X197342D01*
X196967Y1059375D01*
X196675Y1059167D01*
X196467Y1058917D01*
X196300Y1058500D01*
X196258Y1058125D01*
X196342Y1057750D01*
X196467Y1057500D01*
X196717Y1057250D01*
X197008Y1057083D01*
X197300Y1057000D01*
X197592D01*
X197883Y1057083D01*
X198133Y1057208D01*
X198342Y1057375D01*
G01X200900Y1057000D02*
Y1059500D01*
X199358Y1057708D01*
X201442D01*
G01X204000Y1057000D02*
Y1059500D01*
X202458Y1057708D01*
X204542D01*
G01X213708Y1082817D02*
X213583Y1082567D01*
X213500Y1082275D01*
Y1081942D01*
X213625Y1081567D01*
X213833Y1081275D01*
X214083Y1081067D01*
X214500Y1080900D01*
X214875Y1080858D01*
X215250Y1080942D01*
X215500Y1081067D01*
X215750Y1081317D01*
X215917Y1081608D01*
X216000Y1081900D01*
Y1082192D01*
X215917Y1082483D01*
X215792Y1082733D01*
X215625Y1082942D01*
G01Y1084083D02*
X215833Y1084333D01*
X215958Y1084625D01*
X216000Y1085000D01*
X215917Y1085375D01*
X215750Y1085667D01*
X215458Y1085875D01*
X215125Y1085917D01*
X214792Y1085833D01*
X214583Y1085625D01*
X214417Y1085333D01*
X214375Y1085042D01*
X214417Y1084750D01*
X214583Y1084375D01*
X213500Y1084500D01*
Y1085625D01*
G01Y1088100D02*
X213583Y1087767D01*
X213792Y1087517D01*
X214042Y1087350D01*
X214375Y1087225D01*
X214750Y1087183D01*
X215125Y1087225D01*
X215458Y1087350D01*
X215708Y1087517D01*
X215917Y1087767D01*
X216000Y1088100D01*
X215917Y1088433D01*
X215708Y1088683D01*
X215458Y1088850D01*
X215125Y1088975D01*
X214750Y1089017D01*
X214375Y1088975D01*
X214042Y1088850D01*
X213792Y1088683D01*
X213583Y1088433D01*
X213500Y1088100D01*
G01X254850Y1069000D02*
Y1066500D01*
G01X253892Y1069000D02*
X255808D01*
G01X257117Y1066500D02*
Y1069000D01*
X258117D01*
X258450Y1068875D01*
X258700Y1068583D01*
X258783Y1068250D01*
X258700Y1067917D01*
X258492Y1067667D01*
X258117Y1067542D01*
X257117D01*
G01X260258Y1068583D02*
X260508Y1068833D01*
X260800Y1068958D01*
X261133Y1069000D01*
X261550Y1068917D01*
X261842Y1068708D01*
X261925Y1068458D01*
X261883Y1068208D01*
X261717Y1068000D01*
X260883Y1067583D01*
X260508Y1067292D01*
X260258Y1066875D01*
X260175Y1066500D01*
X261925D01*
G01X263358Y1067542D02*
X263650Y1067833D01*
X263900Y1068000D01*
X264233Y1068083D01*
X264525Y1068000D01*
X264733Y1067833D01*
X264900Y1067583D01*
X264942Y1067292D01*
X264900Y1067042D01*
X264733Y1066792D01*
X264483Y1066583D01*
X264192Y1066500D01*
X263858Y1066583D01*
X263567Y1066833D01*
X263400Y1067208D01*
X263358Y1067625D01*
X263442Y1068167D01*
X263567Y1068458D01*
X263775Y1068750D01*
X264067Y1068958D01*
X264358Y1069000D01*
X264650Y1068917D01*
X264858Y1068708D01*
G01X258517Y1051500D02*
Y1054000D01*
X259558D01*
X259892Y1053875D01*
X260100Y1053708D01*
X260183Y1053375D01*
X260100Y1053042D01*
X259850Y1052833D01*
X259558Y1052708D01*
X258517D01*
G01X259558D02*
X260183Y1051500D01*
G01X262450D02*
Y1054000D01*
X261950Y1053500D01*
G01Y1051500D02*
X262950D01*
G01X265467D02*
X265550Y1052042D01*
X265675Y1052500D01*
X265842Y1052917D01*
X266050Y1053375D01*
X266383Y1054000D01*
X264717D01*
G01X267858Y1052542D02*
X268150Y1052833D01*
X268400Y1053000D01*
X268733Y1053083D01*
X269025Y1053000D01*
X269233Y1052833D01*
X269400Y1052583D01*
X269442Y1052292D01*
X269400Y1052042D01*
X269233Y1051792D01*
X268983Y1051583D01*
X268692Y1051500D01*
X268358Y1051583D01*
X268067Y1051833D01*
X267900Y1052208D01*
X267858Y1052625D01*
X267942Y1053167D01*
X268067Y1053458D01*
X268275Y1053750D01*
X268567Y1053958D01*
X268858Y1054000D01*
X269150Y1053917D01*
X269358Y1053708D01*
G01X198317Y1054453D02*
X198067Y1054578D01*
X197775Y1054661D01*
X197442D01*
X197067Y1054536D01*
X196775Y1054328D01*
X196567Y1054078D01*
X196400Y1053661D01*
X196358Y1053286D01*
X196442Y1052911D01*
X196567Y1052661D01*
X196817Y1052411D01*
X197108Y1052244D01*
X197400Y1052161D01*
X197692D01*
X197983Y1052244D01*
X198233Y1052369D01*
X198442Y1052536D01*
G01X201000Y1052161D02*
Y1054661D01*
X199458Y1052869D01*
X201542D01*
G01X202683Y1052536D02*
X202933Y1052328D01*
X203225Y1052203D01*
X203600Y1052161D01*
X203975Y1052244D01*
X204267Y1052411D01*
X204475Y1052703D01*
X204517Y1053036D01*
X204433Y1053369D01*
X204225Y1053578D01*
X203933Y1053744D01*
X203642Y1053786D01*
X203350Y1053744D01*
X202975Y1053578D01*
X203100Y1054661D01*
X204225D01*
G01X196517Y1061500D02*
Y1064000D01*
X197558D01*
X197892Y1063875D01*
X198100Y1063708D01*
X198183Y1063375D01*
X198100Y1063042D01*
X197850Y1062833D01*
X197558Y1062708D01*
X196517D01*
G01X197558D02*
X198183Y1061500D01*
G01X200450D02*
Y1064000D01*
X199950Y1063500D01*
G01Y1061500D02*
X200950D01*
G01X203467D02*
X203550Y1062042D01*
X203675Y1062500D01*
X203842Y1062917D01*
X204050Y1063375D01*
X204383Y1064000D01*
X202717D01*
G01X206567Y1061500D02*
X206650Y1062042D01*
X206775Y1062500D01*
X206942Y1062917D01*
X207150Y1063375D01*
X207483Y1064000D01*
X205817D01*
G01X211547Y1072817D02*
X211422Y1072567D01*
X211339Y1072275D01*
Y1071942D01*
X211464Y1071567D01*
X211672Y1071275D01*
X211922Y1071067D01*
X212339Y1070900D01*
X212714Y1070858D01*
X213089Y1070942D01*
X213339Y1071067D01*
X213589Y1071317D01*
X213756Y1071608D01*
X213839Y1071900D01*
Y1072192D01*
X213756Y1072483D01*
X213631Y1072733D01*
X213464Y1072942D01*
G01X213839Y1075500D02*
X211339D01*
X213131Y1073958D01*
Y1076042D01*
G01X213547Y1077392D02*
X213756Y1077683D01*
X213839Y1078017D01*
X213756Y1078350D01*
X213506Y1078642D01*
X213131Y1078850D01*
X212756Y1078933D01*
X212297D01*
X211922Y1078850D01*
X211589Y1078642D01*
X211422Y1078392D01*
X211339Y1078100D01*
X211422Y1077767D01*
X211589Y1077517D01*
X211839Y1077350D01*
X212172Y1077267D01*
X212464Y1077350D01*
X212756Y1077558D01*
X212922Y1077808D01*
X212964Y1078100D01*
X212881Y1078433D01*
X212672Y1078683D01*
X212297Y1078933D01*
G01X235535Y1305772D02*
Y1335172D01*
X245535D01*
Y1365172D01*
X532535D01*
Y1335172D01*
X542535D01*
Y1305772D01*
X235535D01*
G01X243741Y1431053D02*
X243491Y1431178D01*
X243199Y1431261D01*
X242866D01*
X242491Y1431136D01*
X242199Y1430928D01*
X241991Y1430678D01*
X241824Y1430261D01*
X241782Y1429886D01*
X241866Y1429511D01*
X241991Y1429261D01*
X242241Y1429011D01*
X242532Y1428844D01*
X242824Y1428761D01*
X243116D01*
X243407Y1428844D01*
X243657Y1428969D01*
X243866Y1429136D01*
G01X245007D02*
X245257Y1428928D01*
X245549Y1428803D01*
X245924Y1428761D01*
X246299Y1428844D01*
X246591Y1429011D01*
X246799Y1429303D01*
X246841Y1429636D01*
X246757Y1429969D01*
X246549Y1430178D01*
X246257Y1430344D01*
X245966Y1430386D01*
X245674Y1430344D01*
X245299Y1430178D01*
X245424Y1431261D01*
X246549D01*
G01X248232Y1430844D02*
X248482Y1431094D01*
X248774Y1431219D01*
X249107Y1431261D01*
X249524Y1431178D01*
X249816Y1430969D01*
X249899Y1430719D01*
X249857Y1430469D01*
X249691Y1430261D01*
X248857Y1429844D01*
X248482Y1429553D01*
X248232Y1429136D01*
X248149Y1428761D01*
X249899D01*
G01X251332Y1430844D02*
X251582Y1431094D01*
X251874Y1431219D01*
X252207Y1431261D01*
X252624Y1431178D01*
X252916Y1430969D01*
X252999Y1430719D01*
X252957Y1430469D01*
X252791Y1430261D01*
X251957Y1429844D01*
X251582Y1429553D01*
X251332Y1429136D01*
X251249Y1428761D01*
X252999D01*
G01X214300Y1422250D02*
X214258Y1421917D01*
X214092Y1421625D01*
X213842Y1421375D01*
X213550Y1421208D01*
X213217Y1421125D01*
X212883D01*
X212550Y1421208D01*
X212258Y1421375D01*
X212008Y1421625D01*
X211842Y1421917D01*
X211800Y1422250D01*
X211842Y1422583D01*
X212008Y1422875D01*
X212258Y1423125D01*
X212550Y1423292D01*
X212883Y1423375D01*
X213217D01*
X213550Y1423292D01*
X213842Y1423125D01*
X214092Y1422875D01*
X214258Y1422583D01*
X214300Y1422250D01*
G01X213633Y1422583D02*
X214300Y1423083D01*
G01Y1425350D02*
X211800D01*
X212300Y1424850D01*
G01X214300D02*
Y1425850D01*
G01X212217Y1427658D02*
X211967Y1427908D01*
X211842Y1428200D01*
X211800Y1428533D01*
X211883Y1428950D01*
X212092Y1429242D01*
X212342Y1429325D01*
X212592Y1429283D01*
X212800Y1429117D01*
X213217Y1428283D01*
X213508Y1427908D01*
X213925Y1427658D01*
X214300Y1427575D01*
Y1429325D01*
G01Y1431467D02*
X213758Y1431550D01*
X213300Y1431675D01*
X212883Y1431842D01*
X212425Y1432050D01*
X211800Y1432383D01*
Y1430717D01*
G01X241641Y1422792D02*
X241391Y1422917D01*
X241099Y1423000D01*
X240766D01*
X240391Y1422875D01*
X240099Y1422667D01*
X239891Y1422417D01*
X239724Y1422000D01*
X239682Y1421625D01*
X239766Y1421250D01*
X239891Y1421000D01*
X240141Y1420750D01*
X240432Y1420583D01*
X240724Y1420500D01*
X241016D01*
X241307Y1420583D01*
X241557Y1420708D01*
X241766Y1420875D01*
G01X242907D02*
X243157Y1420667D01*
X243449Y1420542D01*
X243824Y1420500D01*
X244199Y1420583D01*
X244491Y1420750D01*
X244699Y1421042D01*
X244741Y1421375D01*
X244657Y1421708D01*
X244449Y1421917D01*
X244157Y1422083D01*
X243866Y1422125D01*
X243574Y1422083D01*
X243199Y1421917D01*
X243324Y1423000D01*
X244449D01*
G01X246132Y1422583D02*
X246382Y1422833D01*
X246674Y1422958D01*
X247007Y1423000D01*
X247424Y1422917D01*
X247716Y1422708D01*
X247799Y1422458D01*
X247757Y1422208D01*
X247591Y1422000D01*
X246757Y1421583D01*
X246382Y1421292D01*
X246132Y1420875D01*
X246049Y1420500D01*
X247799D01*
G01X250024Y1423000D02*
X249691Y1422917D01*
X249441Y1422708D01*
X249274Y1422458D01*
X249149Y1422125D01*
X249107Y1421750D01*
X249149Y1421375D01*
X249274Y1421042D01*
X249441Y1420792D01*
X249691Y1420583D01*
X250024Y1420500D01*
X250357Y1420583D01*
X250607Y1420792D01*
X250774Y1421042D01*
X250899Y1421375D01*
X250941Y1421750D01*
X250899Y1422125D01*
X250774Y1422458D01*
X250607Y1422708D01*
X250357Y1422917D01*
X250024Y1423000D01*
G01X222874Y1427200D02*
X216674D01*
Y1414800D01*
X222874D01*
G01X228874D02*
X235074D01*
Y1427200D01*
X228874D01*
G01X258458Y1471200D02*
Y1473700D01*
X260042D01*
G01X259458Y1472492D02*
X258458D01*
G01X261308Y1471200D02*
X262350Y1473700D01*
X263392Y1471200D01*
G01X263017Y1472075D02*
X261683D01*
G01X264492Y1471200D02*
Y1473700D01*
X266408Y1471200D01*
Y1473700D01*
G01X268550Y1471200D02*
Y1473700D01*
X268050Y1473200D01*
G01Y1471200D02*
X269050D01*
G01X243522Y1435082D02*
X243272Y1435207D01*
X242980Y1435290D01*
X242647D01*
X242272Y1435165D01*
X241980Y1434957D01*
X241772Y1434707D01*
X241605Y1434290D01*
X241563Y1433915D01*
X241647Y1433540D01*
X241772Y1433290D01*
X242022Y1433040D01*
X242313Y1432873D01*
X242605Y1432790D01*
X242897D01*
X243188Y1432873D01*
X243438Y1432998D01*
X243647Y1433165D01*
G01X244788D02*
X245038Y1432957D01*
X245330Y1432832D01*
X245705Y1432790D01*
X246080Y1432873D01*
X246372Y1433040D01*
X246580Y1433332D01*
X246622Y1433665D01*
X246538Y1433998D01*
X246330Y1434207D01*
X246038Y1434373D01*
X245747Y1434415D01*
X245455Y1434373D01*
X245080Y1434207D01*
X245205Y1435290D01*
X246330D01*
G01X248013Y1434873D02*
X248263Y1435123D01*
X248555Y1435248D01*
X248888Y1435290D01*
X249305Y1435207D01*
X249597Y1434998D01*
X249680Y1434748D01*
X249638Y1434498D01*
X249472Y1434290D01*
X248638Y1433873D01*
X248263Y1433582D01*
X248013Y1433165D01*
X247930Y1432790D01*
X249680D01*
G01X251905D02*
Y1435290D01*
X251405Y1434790D01*
G01Y1432790D02*
X252405D01*
G01X342549Y107319D02*
X347599D01*
Y206019D01*
X372249D01*
Y21619D01*
X347599D01*
Y80319D01*
X342549D01*
Y107319D01*
G01X387767Y57292D02*
X387517Y57417D01*
X387225Y57500D01*
X386892D01*
X386517Y57375D01*
X386225Y57167D01*
X386017Y56917D01*
X385850Y56500D01*
X385808Y56125D01*
X385892Y55750D01*
X386017Y55500D01*
X386267Y55250D01*
X386558Y55083D01*
X386850Y55000D01*
X387142D01*
X387433Y55083D01*
X387683Y55208D01*
X387892Y55375D01*
G01X389033Y55500D02*
X389283Y55208D01*
X389617Y55042D01*
X389992Y55000D01*
X390325Y55042D01*
X390658Y55250D01*
X390867Y55500D01*
X390908Y55750D01*
X390825Y56042D01*
X390533Y56250D01*
X390242Y56333D01*
X389867D01*
G01X390242D02*
X390492Y56458D01*
X390700Y56667D01*
X390783Y56917D01*
X390700Y57167D01*
X390492Y57375D01*
X390117Y57500D01*
X389742Y57458D01*
X389367Y57292D01*
G01X392258Y56042D02*
X392550Y56333D01*
X392800Y56500D01*
X393133Y56583D01*
X393425Y56500D01*
X393633Y56333D01*
X393800Y56083D01*
X393842Y55792D01*
X393800Y55542D01*
X393633Y55292D01*
X393383Y55083D01*
X393092Y55000D01*
X392758Y55083D01*
X392467Y55333D01*
X392300Y55708D01*
X392258Y56125D01*
X392342Y56667D01*
X392467Y56958D01*
X392675Y57250D01*
X392967Y57458D01*
X393258Y57500D01*
X393550Y57417D01*
X393758Y57208D01*
G01X396067Y55000D02*
X396150Y55542D01*
X396275Y56000D01*
X396442Y56417D01*
X396650Y56875D01*
X396983Y57500D01*
X395317D01*
G01X387767Y61292D02*
X387517Y61417D01*
X387225Y61500D01*
X386892D01*
X386517Y61375D01*
X386225Y61167D01*
X386017Y60917D01*
X385850Y60500D01*
X385808Y60125D01*
X385892Y59750D01*
X386017Y59500D01*
X386267Y59250D01*
X386558Y59083D01*
X386850Y59000D01*
X387142D01*
X387433Y59083D01*
X387683Y59208D01*
X387892Y59375D01*
G01X389033Y59500D02*
X389283Y59208D01*
X389617Y59042D01*
X389992Y59000D01*
X390325Y59042D01*
X390658Y59250D01*
X390867Y59500D01*
X390908Y59750D01*
X390825Y60042D01*
X390533Y60250D01*
X390242Y60333D01*
X389867D01*
G01X390242D02*
X390492Y60458D01*
X390700Y60667D01*
X390783Y60917D01*
X390700Y61167D01*
X390492Y61375D01*
X390117Y61500D01*
X389742Y61458D01*
X389367Y61292D01*
G01X392258Y60042D02*
X392550Y60333D01*
X392800Y60500D01*
X393133Y60583D01*
X393425Y60500D01*
X393633Y60333D01*
X393800Y60083D01*
X393842Y59792D01*
X393800Y59542D01*
X393633Y59292D01*
X393383Y59083D01*
X393092Y59000D01*
X392758Y59083D01*
X392467Y59333D01*
X392300Y59708D01*
X392258Y60125D01*
X392342Y60667D01*
X392467Y60958D01*
X392675Y61250D01*
X392967Y61458D01*
X393258Y61500D01*
X393550Y61417D01*
X393758Y61208D01*
G01X395358Y60042D02*
X395650Y60333D01*
X395900Y60500D01*
X396233Y60583D01*
X396525Y60500D01*
X396733Y60333D01*
X396900Y60083D01*
X396942Y59792D01*
X396900Y59542D01*
X396733Y59292D01*
X396483Y59083D01*
X396192Y59000D01*
X395858Y59083D01*
X395567Y59333D01*
X395400Y59708D01*
X395358Y60125D01*
X395442Y60667D01*
X395567Y60958D01*
X395775Y61250D01*
X396067Y61458D01*
X396358Y61500D01*
X396650Y61417D01*
X396858Y61208D01*
G01X300267Y92953D02*
X300017Y93078D01*
X299725Y93161D01*
X299392D01*
X299017Y93036D01*
X298725Y92828D01*
X298517Y92578D01*
X298350Y92161D01*
X298308Y91786D01*
X298392Y91411D01*
X298517Y91161D01*
X298767Y90911D01*
X299058Y90744D01*
X299350Y90661D01*
X299642D01*
X299933Y90744D01*
X300183Y90869D01*
X300392Y91036D01*
G01X301533Y91161D02*
X301783Y90869D01*
X302117Y90703D01*
X302492Y90661D01*
X302825Y90703D01*
X303158Y90911D01*
X303367Y91161D01*
X303408Y91411D01*
X303325Y91703D01*
X303033Y91911D01*
X302742Y91994D01*
X302367D01*
G01X302742D02*
X302992Y92119D01*
X303200Y92328D01*
X303283Y92578D01*
X303200Y92828D01*
X302992Y93036D01*
X302617Y93161D01*
X302242Y93119D01*
X301867Y92953D01*
G01X305467Y90661D02*
X305550Y91203D01*
X305675Y91661D01*
X305842Y92078D01*
X306050Y92536D01*
X306383Y93161D01*
X304717D01*
G01X307858Y91703D02*
X308150Y91994D01*
X308400Y92161D01*
X308733Y92244D01*
X309025Y92161D01*
X309233Y91994D01*
X309400Y91744D01*
X309442Y91453D01*
X309400Y91203D01*
X309233Y90953D01*
X308983Y90744D01*
X308692Y90661D01*
X308358Y90744D01*
X308067Y90994D01*
X307900Y91369D01*
X307858Y91786D01*
X307942Y92328D01*
X308067Y92619D01*
X308275Y92911D01*
X308567Y93119D01*
X308858Y93161D01*
X309150Y93078D01*
X309358Y92869D01*
G01X298517Y86500D02*
Y89000D01*
X299558D01*
X299892Y88875D01*
X300100Y88708D01*
X300183Y88375D01*
X300100Y88042D01*
X299850Y87833D01*
X299558Y87708D01*
X298517D01*
G01X299558D02*
X300183Y86500D01*
G01X301658Y87542D02*
X301950Y87833D01*
X302200Y88000D01*
X302533Y88083D01*
X302825Y88000D01*
X303033Y87833D01*
X303200Y87583D01*
X303242Y87292D01*
X303200Y87042D01*
X303033Y86792D01*
X302783Y86583D01*
X302492Y86500D01*
X302158Y86583D01*
X301867Y86833D01*
X301700Y87208D01*
X301658Y87625D01*
X301742Y88167D01*
X301867Y88458D01*
X302075Y88750D01*
X302367Y88958D01*
X302658Y89000D01*
X302950Y88917D01*
X303158Y88708D01*
G01X305467Y86500D02*
X305550Y87042D01*
X305675Y87500D01*
X305842Y87917D01*
X306050Y88375D01*
X306383Y89000D01*
X304717D01*
G01X307733Y86875D02*
X307983Y86667D01*
X308275Y86542D01*
X308650Y86500D01*
X309025Y86583D01*
X309317Y86750D01*
X309525Y87042D01*
X309567Y87375D01*
X309483Y87708D01*
X309275Y87917D01*
X308983Y88083D01*
X308692Y88125D01*
X308400Y88083D01*
X308025Y87917D01*
X308150Y89000D01*
X309275D01*
G01X310800Y93000D02*
Y89000D01*
X318200D01*
G01X333017Y53500D02*
Y56000D01*
X334058D01*
X334392Y55875D01*
X334600Y55708D01*
X334683Y55375D01*
X334600Y55042D01*
X334350Y54833D01*
X334058Y54708D01*
X333017D01*
G01X334058D02*
X334683Y53500D01*
G01X336158Y54542D02*
X336450Y54833D01*
X336700Y55000D01*
X337033Y55083D01*
X337325Y55000D01*
X337533Y54833D01*
X337700Y54583D01*
X337742Y54292D01*
X337700Y54042D01*
X337533Y53792D01*
X337283Y53583D01*
X336992Y53500D01*
X336658Y53583D01*
X336367Y53833D01*
X336200Y54208D01*
X336158Y54625D01*
X336242Y55167D01*
X336367Y55458D01*
X336575Y55750D01*
X336867Y55958D01*
X337158Y56000D01*
X337450Y55917D01*
X337658Y55708D01*
G01X339967Y53500D02*
X340050Y54042D01*
X340175Y54500D01*
X340342Y54917D01*
X340550Y55375D01*
X340883Y56000D01*
X339217D01*
G01X342358Y54542D02*
X342650Y54833D01*
X342900Y55000D01*
X343233Y55083D01*
X343525Y55000D01*
X343733Y54833D01*
X343900Y54583D01*
X343942Y54292D01*
X343900Y54042D01*
X343733Y53792D01*
X343483Y53583D01*
X343192Y53500D01*
X342858Y53583D01*
X342567Y53833D01*
X342400Y54208D01*
X342358Y54625D01*
X342442Y55167D01*
X342567Y55458D01*
X342775Y55750D01*
X343067Y55958D01*
X343358Y56000D01*
X343650Y55917D01*
X343858Y55708D01*
G01X342600Y70600D02*
Y74600D01*
X335200D01*
G01X333017Y49500D02*
Y52000D01*
X334058D01*
X334392Y51875D01*
X334600Y51708D01*
X334683Y51375D01*
X334600Y51042D01*
X334350Y50833D01*
X334058Y50708D01*
X333017D01*
G01X334058D02*
X334683Y49500D01*
G01X336158Y50542D02*
X336450Y50833D01*
X336700Y51000D01*
X337033Y51083D01*
X337325Y51000D01*
X337533Y50833D01*
X337700Y50583D01*
X337742Y50292D01*
X337700Y50042D01*
X337533Y49792D01*
X337283Y49583D01*
X336992Y49500D01*
X336658Y49583D01*
X336367Y49833D01*
X336200Y50208D01*
X336158Y50625D01*
X336242Y51167D01*
X336367Y51458D01*
X336575Y51750D01*
X336867Y51958D01*
X337158Y52000D01*
X337450Y51917D01*
X337658Y51708D01*
G01X339967Y49500D02*
X340050Y50042D01*
X340175Y50500D01*
X340342Y50917D01*
X340550Y51375D01*
X340883Y52000D01*
X339217D01*
G01X342442Y49792D02*
X342733Y49583D01*
X343067Y49500D01*
X343400Y49583D01*
X343692Y49833D01*
X343900Y50208D01*
X343983Y50583D01*
Y51042D01*
X343900Y51417D01*
X343692Y51750D01*
X343442Y51917D01*
X343150Y52000D01*
X342817Y51917D01*
X342567Y51750D01*
X342400Y51500D01*
X342317Y51167D01*
X342400Y50875D01*
X342608Y50583D01*
X342858Y50417D01*
X343150Y50375D01*
X343483Y50458D01*
X343733Y50667D01*
X343983Y51042D01*
G01X340400Y61700D02*
Y65700D01*
X333000D01*
G01X333017Y57500D02*
Y60000D01*
X334058D01*
X334392Y59875D01*
X334600Y59708D01*
X334683Y59375D01*
X334600Y59042D01*
X334350Y58833D01*
X334058Y58708D01*
X333017D01*
G01X334058D02*
X334683Y57500D01*
G01X336158Y58542D02*
X336450Y58833D01*
X336700Y59000D01*
X337033Y59083D01*
X337325Y59000D01*
X337533Y58833D01*
X337700Y58583D01*
X337742Y58292D01*
X337700Y58042D01*
X337533Y57792D01*
X337283Y57583D01*
X336992Y57500D01*
X336658Y57583D01*
X336367Y57833D01*
X336200Y58208D01*
X336158Y58625D01*
X336242Y59167D01*
X336367Y59458D01*
X336575Y59750D01*
X336867Y59958D01*
X337158Y60000D01*
X337450Y59917D01*
X337658Y59708D01*
G01X340050Y57500D02*
X340342Y57542D01*
X340675Y57667D01*
X340883Y57875D01*
X340967Y58167D01*
X340883Y58458D01*
X340633Y58708D01*
X340258Y58833D01*
X339842D01*
X339592Y58917D01*
X339383Y59125D01*
X339300Y59417D01*
X339425Y59708D01*
X339717Y59917D01*
X340050Y60000D01*
X340383Y59917D01*
X340675Y59708D01*
X340800Y59417D01*
X340717Y59125D01*
X340508Y58917D01*
X340258Y58833D01*
X339842D01*
X339467Y58708D01*
X339217Y58458D01*
X339133Y58167D01*
X339217Y57875D01*
X339425Y57667D01*
X339758Y57542D01*
X340050Y57500D01*
G01X343150Y60000D02*
X342817Y59917D01*
X342567Y59708D01*
X342400Y59458D01*
X342275Y59125D01*
X342233Y58750D01*
X342275Y58375D01*
X342400Y58042D01*
X342567Y57792D01*
X342817Y57583D01*
X343150Y57500D01*
X343483Y57583D01*
X343733Y57792D01*
X343900Y58042D01*
X344025Y58375D01*
X344067Y58750D01*
X344025Y59125D01*
X343900Y59458D01*
X343733Y59708D01*
X343483Y59917D01*
X343150Y60000D01*
G01X335300Y79000D02*
Y75000D01*
X342700D01*
G01X303300Y67500D02*
Y63500D01*
X310700D01*
G01X305500Y69517D02*
X303000D01*
Y70558D01*
X303125Y70892D01*
X303292Y71100D01*
X303625Y71183D01*
X303958Y71100D01*
X304167Y70850D01*
X304292Y70558D01*
Y69517D01*
G01Y70558D02*
X305500Y71183D01*
G01X304458Y72658D02*
X304167Y72950D01*
X304000Y73200D01*
X303917Y73533D01*
X304000Y73825D01*
X304167Y74033D01*
X304417Y74200D01*
X304708Y74242D01*
X304958Y74200D01*
X305208Y74033D01*
X305417Y73783D01*
X305500Y73492D01*
X305417Y73158D01*
X305167Y72867D01*
X304792Y72700D01*
X304375Y72658D01*
X303833Y72742D01*
X303542Y72867D01*
X303250Y73075D01*
X303042Y73367D01*
X303000Y73658D01*
X303083Y73950D01*
X303292Y74158D01*
G01X305500Y76550D02*
X305458Y76842D01*
X305333Y77175D01*
X305125Y77383D01*
X304833Y77467D01*
X304542Y77383D01*
X304292Y77133D01*
X304167Y76758D01*
Y76342D01*
X304083Y76092D01*
X303875Y75883D01*
X303583Y75800D01*
X303292Y75925D01*
X303083Y76217D01*
X303000Y76550D01*
X303083Y76883D01*
X303292Y77175D01*
X303583Y77300D01*
X303875Y77217D01*
X304083Y77008D01*
X304167Y76758D01*
Y76342D01*
X304292Y75967D01*
X304542Y75717D01*
X304833Y75633D01*
X305125Y75717D01*
X305333Y75925D01*
X305458Y76258D01*
X305500Y76550D01*
G01Y80150D02*
X303000D01*
X304792Y78608D01*
Y80692D01*
G01X306500Y67800D02*
X310500D01*
Y75200D01*
G01X322000Y49517D02*
X319500D01*
Y50558D01*
X319625Y50892D01*
X319792Y51100D01*
X320125Y51183D01*
X320458Y51100D01*
X320667Y50850D01*
X320792Y50558D01*
Y49517D01*
G01Y50558D02*
X322000Y51183D01*
G01X320958Y52658D02*
X320667Y52950D01*
X320500Y53200D01*
X320417Y53533D01*
X320500Y53825D01*
X320667Y54033D01*
X320917Y54200D01*
X321208Y54242D01*
X321458Y54200D01*
X321708Y54033D01*
X321917Y53783D01*
X322000Y53492D01*
X321917Y53158D01*
X321667Y52867D01*
X321292Y52700D01*
X320875Y52658D01*
X320333Y52742D01*
X320042Y52867D01*
X319750Y53075D01*
X319542Y53367D01*
X319500Y53658D01*
X319583Y53950D01*
X319792Y54158D01*
G01X322000Y56550D02*
X321958Y56842D01*
X321833Y57175D01*
X321625Y57383D01*
X321333Y57467D01*
X321042Y57383D01*
X320792Y57133D01*
X320667Y56758D01*
Y56342D01*
X320583Y56092D01*
X320375Y55883D01*
X320083Y55800D01*
X319792Y55925D01*
X319583Y56217D01*
X319500Y56550D01*
X319583Y56883D01*
X319792Y57175D01*
X320083Y57300D01*
X320375Y57217D01*
X320583Y57008D01*
X320667Y56758D01*
Y56342D01*
X320792Y55967D01*
X321042Y55717D01*
X321333Y55633D01*
X321625Y55717D01*
X321833Y55925D01*
X321958Y56258D01*
X322000Y56550D01*
G01X321625Y58733D02*
X321833Y58983D01*
X321958Y59275D01*
X322000Y59650D01*
X321917Y60025D01*
X321750Y60317D01*
X321458Y60525D01*
X321125Y60567D01*
X320792Y60483D01*
X320583Y60275D01*
X320417Y59983D01*
X320375Y59692D01*
X320417Y59400D01*
X320583Y59025D01*
X319500Y59150D01*
Y60275D01*
G01X323000Y69200D02*
X319000D01*
Y61800D01*
G01X316000Y49483D02*
X313500D01*
Y50317D01*
X313625Y50650D01*
X313792Y50900D01*
X314042Y51108D01*
X314333Y51275D01*
X314750Y51317D01*
X315167Y51275D01*
X315458Y51108D01*
X315708Y50900D01*
X315875Y50650D01*
X316000Y50317D01*
Y49483D01*
G01X313917Y52708D02*
X313667Y52958D01*
X313542Y53250D01*
X313500Y53583D01*
X313583Y54000D01*
X313792Y54292D01*
X314042Y54375D01*
X314292Y54333D01*
X314500Y54167D01*
X314917Y53333D01*
X315208Y52958D01*
X315625Y52708D01*
X316000Y52625D01*
Y54375D01*
G01X314958Y55808D02*
X314667Y56100D01*
X314500Y56350D01*
X314417Y56683D01*
X314500Y56975D01*
X314667Y57183D01*
X314917Y57350D01*
X315208Y57392D01*
X315458Y57350D01*
X315708Y57183D01*
X315917Y56933D01*
X316000Y56642D01*
X315917Y56308D01*
X315667Y56017D01*
X315292Y55850D01*
X314875Y55808D01*
X314333Y55892D01*
X314042Y56017D01*
X313750Y56225D01*
X313542Y56517D01*
X313500Y56808D01*
X313583Y57100D01*
X313792Y57308D01*
G01X318500Y78000D02*
Y61900D01*
G01X311500Y78000D02*
X318500D01*
G01X311500Y61900D02*
Y78000D01*
G01X318500Y61900D02*
X311500D01*
G01X322000Y75350D02*
X321958Y75017D01*
X321792Y74725D01*
X321542Y74475D01*
X321250Y74308D01*
X320917Y74225D01*
X320583D01*
X320250Y74308D01*
X319958Y74475D01*
X319708Y74725D01*
X319542Y75017D01*
X319500Y75350D01*
X319542Y75683D01*
X319708Y75975D01*
X319958Y76225D01*
X320250Y76392D01*
X320583Y76475D01*
X320917D01*
X321250Y76392D01*
X321542Y76225D01*
X321792Y75975D01*
X321958Y75683D01*
X322000Y75350D01*
G01X321333Y75683D02*
X322000Y76183D01*
G01Y78450D02*
X319500D01*
X320000Y77950D01*
G01X322000D02*
Y78950D01*
G01X321500Y80633D02*
X321792Y80883D01*
X321958Y81217D01*
X322000Y81592D01*
X321958Y81925D01*
X321750Y82258D01*
X321500Y82467D01*
X321250Y82508D01*
X320958Y82425D01*
X320750Y82133D01*
X320667Y81842D01*
Y81467D01*
G01Y81842D02*
X320542Y82092D01*
X320333Y82300D01*
X320083Y82383D01*
X319833Y82300D01*
X319625Y82092D01*
X319500Y81717D01*
X319542Y81342D01*
X319708Y80967D01*
G01X322000Y84650D02*
X319500D01*
X320000Y84150D01*
G01X322000D02*
Y85150D01*
G01X334700Y83700D02*
X323300D01*
G01X334700Y70300D02*
Y83700D01*
G01X323300Y70300D02*
X334700D01*
G01X323300Y83700D02*
Y70300D01*
G01X375035Y131367D02*
X374910Y131117D01*
X374827Y130825D01*
Y130492D01*
X374952Y130117D01*
X375160Y129825D01*
X375410Y129617D01*
X375827Y129450D01*
X376202Y129408D01*
X376577Y129492D01*
X376827Y129617D01*
X377077Y129867D01*
X377244Y130158D01*
X377327Y130450D01*
Y130742D01*
X377244Y131033D01*
X377119Y131283D01*
X376952Y131492D01*
G01X376827Y132633D02*
X377119Y132883D01*
X377285Y133217D01*
X377327Y133592D01*
X377285Y133925D01*
X377077Y134258D01*
X376827Y134467D01*
X376577Y134508D01*
X376285Y134425D01*
X376077Y134133D01*
X375994Y133842D01*
Y133467D01*
G01Y133842D02*
X375869Y134092D01*
X375660Y134300D01*
X375410Y134383D01*
X375160Y134300D01*
X374952Y134092D01*
X374827Y133717D01*
X374869Y133342D01*
X375035Y132967D01*
G01X377327Y136567D02*
X376785Y136650D01*
X376327Y136775D01*
X375910Y136942D01*
X375452Y137150D01*
X374827Y137483D01*
Y135817D01*
G01X376952Y138833D02*
X377160Y139083D01*
X377285Y139375D01*
X377327Y139750D01*
X377244Y140125D01*
X377077Y140417D01*
X376785Y140625D01*
X376452Y140667D01*
X376119Y140583D01*
X375910Y140375D01*
X375744Y140083D01*
X375702Y139792D01*
X375744Y139500D01*
X375910Y139125D01*
X374827Y139250D01*
Y140375D01*
G01X381327Y129617D02*
X378827D01*
Y130658D01*
X378952Y130992D01*
X379119Y131200D01*
X379452Y131283D01*
X379785Y131200D01*
X379994Y130950D01*
X380119Y130658D01*
Y129617D01*
G01Y130658D02*
X381327Y131283D01*
G01X380285Y132758D02*
X379994Y133050D01*
X379827Y133300D01*
X379744Y133633D01*
X379827Y133925D01*
X379994Y134133D01*
X380244Y134300D01*
X380535Y134342D01*
X380785Y134300D01*
X381035Y134133D01*
X381244Y133883D01*
X381327Y133592D01*
X381244Y133258D01*
X380994Y132967D01*
X380619Y132800D01*
X380202Y132758D01*
X379660Y132842D01*
X379369Y132967D01*
X379077Y133175D01*
X378869Y133467D01*
X378827Y133758D01*
X378910Y134050D01*
X379119Y134258D01*
G01X380285Y135858D02*
X379994Y136150D01*
X379827Y136400D01*
X379744Y136733D01*
X379827Y137025D01*
X379994Y137233D01*
X380244Y137400D01*
X380535Y137442D01*
X380785Y137400D01*
X381035Y137233D01*
X381244Y136983D01*
X381327Y136692D01*
X381244Y136358D01*
X380994Y136067D01*
X380619Y135900D01*
X380202Y135858D01*
X379660Y135942D01*
X379369Y136067D01*
X379077Y136275D01*
X378869Y136567D01*
X378827Y136858D01*
X378910Y137150D01*
X379119Y137358D01*
G01X381327Y139750D02*
X381285Y140042D01*
X381160Y140375D01*
X380952Y140583D01*
X380660Y140667D01*
X380369Y140583D01*
X380119Y140333D01*
X379994Y139958D01*
Y139542D01*
X379910Y139292D01*
X379702Y139083D01*
X379410Y139000D01*
X379119Y139125D01*
X378910Y139417D01*
X378827Y139750D01*
X378910Y140083D01*
X379119Y140375D01*
X379410Y140500D01*
X379702Y140417D01*
X379910Y140208D01*
X379994Y139958D01*
Y139542D01*
X380119Y139167D01*
X380369Y138917D01*
X380660Y138833D01*
X380952Y138917D01*
X381160Y139125D01*
X381285Y139458D01*
X381327Y139750D01*
G01X377500Y120900D02*
X381500D01*
Y128300D01*
G01X310700Y94500D02*
Y98500D01*
X303300D01*
G01X320867Y155792D02*
X320617Y155917D01*
X320325Y156000D01*
X319992D01*
X319617Y155875D01*
X319325Y155667D01*
X319117Y155417D01*
X318950Y155000D01*
X318908Y154625D01*
X318992Y154250D01*
X319117Y154000D01*
X319367Y153750D01*
X319658Y153583D01*
X319950Y153500D01*
X320242D01*
X320533Y153583D01*
X320783Y153708D01*
X320992Y153875D01*
G01X322133Y154000D02*
X322383Y153708D01*
X322717Y153542D01*
X323092Y153500D01*
X323425Y153542D01*
X323758Y153750D01*
X323967Y154000D01*
X324008Y154250D01*
X323925Y154542D01*
X323633Y154750D01*
X323342Y154833D01*
X322967D01*
G01X323342D02*
X323592Y154958D01*
X323800Y155167D01*
X323883Y155417D01*
X323800Y155667D01*
X323592Y155875D01*
X323217Y156000D01*
X322842Y155958D01*
X322467Y155792D01*
G01X325358Y154542D02*
X325650Y154833D01*
X325900Y155000D01*
X326233Y155083D01*
X326525Y155000D01*
X326733Y154833D01*
X326900Y154583D01*
X326942Y154292D01*
X326900Y154042D01*
X326733Y153792D01*
X326483Y153583D01*
X326192Y153500D01*
X325858Y153583D01*
X325567Y153833D01*
X325400Y154208D01*
X325358Y154625D01*
X325442Y155167D01*
X325567Y155458D01*
X325775Y155750D01*
X326067Y155958D01*
X326358Y156000D01*
X326650Y155917D01*
X326858Y155708D01*
G01X329250Y153500D02*
X329542Y153542D01*
X329875Y153667D01*
X330083Y153875D01*
X330167Y154167D01*
X330083Y154458D01*
X329833Y154708D01*
X329458Y154833D01*
X329042D01*
X328792Y154917D01*
X328583Y155125D01*
X328500Y155417D01*
X328625Y155708D01*
X328917Y155917D01*
X329250Y156000D01*
X329583Y155917D01*
X329875Y155708D01*
X330000Y155417D01*
X329917Y155125D01*
X329708Y154917D01*
X329458Y154833D01*
X329042D01*
X328667Y154708D01*
X328417Y154458D01*
X328333Y154167D01*
X328417Y153875D01*
X328625Y153667D01*
X328958Y153542D01*
X329250Y153500D01*
G01X331267Y183792D02*
X331017Y183917D01*
X330725Y184000D01*
X330392D01*
X330017Y183875D01*
X329725Y183667D01*
X329517Y183417D01*
X329350Y183000D01*
X329308Y182625D01*
X329392Y182250D01*
X329517Y182000D01*
X329767Y181750D01*
X330058Y181583D01*
X330350Y181500D01*
X330642D01*
X330933Y181583D01*
X331183Y181708D01*
X331392Y181875D01*
G01X332533Y182000D02*
X332783Y181708D01*
X333117Y181542D01*
X333492Y181500D01*
X333825Y181542D01*
X334158Y181750D01*
X334367Y182000D01*
X334408Y182250D01*
X334325Y182542D01*
X334033Y182750D01*
X333742Y182833D01*
X333367D01*
G01X333742D02*
X333992Y182958D01*
X334200Y183167D01*
X334283Y183417D01*
X334200Y183667D01*
X333992Y183875D01*
X333617Y184000D01*
X333242Y183958D01*
X332867Y183792D01*
G01X336467Y181500D02*
X336550Y182042D01*
X336675Y182500D01*
X336842Y182917D01*
X337050Y183375D01*
X337383Y184000D01*
X335717D01*
G01X340150Y181500D02*
Y184000D01*
X338608Y182208D01*
X340692D01*
G01X379300Y163000D02*
Y160500D01*
G01X378342Y163000D02*
X380258D01*
G01X381567Y160500D02*
Y163000D01*
X382567D01*
X382900Y162875D01*
X383150Y162583D01*
X383233Y162250D01*
X383150Y161917D01*
X382942Y161667D01*
X382567Y161542D01*
X381567D01*
G01X385500Y160500D02*
Y163000D01*
X385000Y162500D01*
G01Y160500D02*
X386000D01*
G01X387683Y160875D02*
X387933Y160667D01*
X388225Y160542D01*
X388600Y160500D01*
X388975Y160583D01*
X389267Y160750D01*
X389475Y161042D01*
X389517Y161375D01*
X389433Y161708D01*
X389225Y161917D01*
X388933Y162083D01*
X388642Y162125D01*
X388350Y162083D01*
X387975Y161917D01*
X388100Y163000D01*
X389225D01*
G01X391700Y160500D02*
Y163000D01*
X391200Y162500D01*
G01Y160500D02*
X392200D01*
G01X325850Y118500D02*
X325517Y118542D01*
X325225Y118708D01*
X324975Y118958D01*
X324808Y119250D01*
X324725Y119583D01*
Y119917D01*
X324808Y120250D01*
X324975Y120542D01*
X325225Y120792D01*
X325517Y120958D01*
X325850Y121000D01*
X326183Y120958D01*
X326475Y120792D01*
X326725Y120542D01*
X326892Y120250D01*
X326975Y119917D01*
Y119583D01*
X326892Y119250D01*
X326725Y118958D01*
X326475Y118708D01*
X326183Y118542D01*
X325850Y118500D01*
G01X326183Y119167D02*
X326683Y118500D01*
G01X328950D02*
Y121000D01*
X328450Y120500D01*
G01Y118500D02*
X329450D01*
G01X331258Y120583D02*
X331508Y120833D01*
X331800Y120958D01*
X332133Y121000D01*
X332550Y120917D01*
X332842Y120708D01*
X332925Y120458D01*
X332883Y120208D01*
X332717Y120000D01*
X331883Y119583D01*
X331508Y119292D01*
X331258Y118875D01*
X331175Y118500D01*
X332925D01*
G01X334442Y118792D02*
X334733Y118583D01*
X335067Y118500D01*
X335400Y118583D01*
X335692Y118833D01*
X335900Y119208D01*
X335983Y119583D01*
Y120042D01*
X335900Y120417D01*
X335692Y120750D01*
X335442Y120917D01*
X335150Y121000D01*
X334817Y120917D01*
X334567Y120750D01*
X334400Y120500D01*
X334317Y120167D01*
X334400Y119875D01*
X334608Y119583D01*
X334858Y119417D01*
X335150Y119375D01*
X335483Y119458D01*
X335733Y119667D01*
X335983Y120042D01*
G01X340700Y101500D02*
X338600Y103300D01*
X340700Y105500D01*
G01X340800Y109100D02*
X321600D01*
Y97900D01*
X340800D01*
Y109100D01*
X340400D01*
G01X294000Y117850D02*
X293958Y117517D01*
X293792Y117225D01*
X293542Y116975D01*
X293250Y116808D01*
X292917Y116725D01*
X292583D01*
X292250Y116808D01*
X291958Y116975D01*
X291708Y117225D01*
X291542Y117517D01*
X291500Y117850D01*
X291542Y118183D01*
X291708Y118475D01*
X291958Y118725D01*
X292250Y118892D01*
X292583Y118975D01*
X292917D01*
X293250Y118892D01*
X293542Y118725D01*
X293792Y118475D01*
X293958Y118183D01*
X294000Y117850D01*
G01X293333Y118183D02*
X294000Y118683D01*
G01Y120950D02*
X291500D01*
X292000Y120450D01*
G01X294000D02*
Y121450D01*
G01X293500Y123133D02*
X293792Y123383D01*
X293958Y123717D01*
X294000Y124092D01*
X293958Y124425D01*
X293750Y124758D01*
X293500Y124967D01*
X293250Y125008D01*
X292958Y124925D01*
X292750Y124633D01*
X292667Y124342D01*
Y123967D01*
G01Y124342D02*
X292542Y124592D01*
X292333Y124800D01*
X292083Y124883D01*
X291833Y124800D01*
X291625Y124592D01*
X291500Y124217D01*
X291542Y123842D01*
X291708Y123467D01*
G01X291917Y126358D02*
X291667Y126608D01*
X291542Y126900D01*
X291500Y127233D01*
X291583Y127650D01*
X291792Y127942D01*
X292042Y128025D01*
X292292Y127983D01*
X292500Y127817D01*
X292917Y126983D01*
X293208Y126608D01*
X293625Y126358D01*
X294000Y126275D01*
Y128025D01*
G01X296300Y123500D02*
X298400Y121700D01*
X296300Y119500D01*
G01X296200Y115900D02*
X315400D01*
Y127100D01*
X296200D01*
Y115900D01*
X296600D01*
G01X320767Y151953D02*
X320517Y152078D01*
X320225Y152161D01*
X319892D01*
X319517Y152036D01*
X319225Y151828D01*
X319017Y151578D01*
X318850Y151161D01*
X318808Y150786D01*
X318892Y150411D01*
X319017Y150161D01*
X319267Y149911D01*
X319558Y149744D01*
X319850Y149661D01*
X320142D01*
X320433Y149744D01*
X320683Y149869D01*
X320892Y150036D01*
G01X322033Y150161D02*
X322283Y149869D01*
X322617Y149703D01*
X322992Y149661D01*
X323325Y149703D01*
X323658Y149911D01*
X323867Y150161D01*
X323908Y150411D01*
X323825Y150703D01*
X323533Y150911D01*
X323242Y150994D01*
X322867D01*
G01X323242D02*
X323492Y151119D01*
X323700Y151328D01*
X323783Y151578D01*
X323700Y151828D01*
X323492Y152036D01*
X323117Y152161D01*
X322742Y152119D01*
X322367Y151953D01*
G01X325258Y150703D02*
X325550Y150994D01*
X325800Y151161D01*
X326133Y151244D01*
X326425Y151161D01*
X326633Y150994D01*
X326800Y150744D01*
X326842Y150453D01*
X326800Y150203D01*
X326633Y149953D01*
X326383Y149744D01*
X326092Y149661D01*
X325758Y149744D01*
X325467Y149994D01*
X325300Y150369D01*
X325258Y150786D01*
X325342Y151328D01*
X325467Y151619D01*
X325675Y151911D01*
X325967Y152119D01*
X326258Y152161D01*
X326550Y152078D01*
X326758Y151869D01*
G01X328442Y149953D02*
X328733Y149744D01*
X329067Y149661D01*
X329400Y149744D01*
X329692Y149994D01*
X329900Y150369D01*
X329983Y150744D01*
Y151203D01*
X329900Y151578D01*
X329692Y151911D01*
X329442Y152078D01*
X329150Y152161D01*
X328817Y152078D01*
X328567Y151911D01*
X328400Y151661D01*
X328317Y151328D01*
X328400Y151036D01*
X328608Y150744D01*
X328858Y150578D01*
X329150Y150536D01*
X329483Y150619D01*
X329733Y150828D01*
X329983Y151203D01*
G01X336300Y122000D02*
X330800D01*
G01X336300Y130000D02*
Y122000D01*
G01X330800Y130000D02*
X336300D01*
G01X318700D02*
X324200D01*
G01X318700Y122000D02*
Y130000D01*
G01X324200Y122000D02*
X318700D01*
G01X343500Y141017D02*
X341000D01*
Y142058D01*
X341125Y142392D01*
X341292Y142600D01*
X341625Y142683D01*
X341958Y142600D01*
X342167Y142350D01*
X342292Y142058D01*
Y141017D01*
G01Y142058D02*
X343500Y142683D01*
G01X342458Y144158D02*
X342167Y144450D01*
X342000Y144700D01*
X341917Y145033D01*
X342000Y145325D01*
X342167Y145533D01*
X342417Y145700D01*
X342708Y145742D01*
X342958Y145700D01*
X343208Y145533D01*
X343417Y145283D01*
X343500Y144992D01*
X343417Y144658D01*
X343167Y144367D01*
X342792Y144200D01*
X342375Y144158D01*
X341833Y144242D01*
X341542Y144367D01*
X341250Y144575D01*
X341042Y144867D01*
X341000Y145158D01*
X341083Y145450D01*
X341292Y145658D01*
G01X342458Y147258D02*
X342167Y147550D01*
X342000Y147800D01*
X341917Y148133D01*
X342000Y148425D01*
X342167Y148633D01*
X342417Y148800D01*
X342708Y148842D01*
X342958Y148800D01*
X343208Y148633D01*
X343417Y148383D01*
X343500Y148092D01*
X343417Y147758D01*
X343167Y147467D01*
X342792Y147300D01*
X342375Y147258D01*
X341833Y147342D01*
X341542Y147467D01*
X341250Y147675D01*
X341042Y147967D01*
X341000Y148258D01*
X341083Y148550D01*
X341292Y148758D01*
G01X343500Y151067D02*
X342958Y151150D01*
X342500Y151275D01*
X342083Y151442D01*
X341625Y151650D01*
X341000Y151983D01*
Y150317D01*
G01X338000Y139800D02*
X346000D01*
Y122200D01*
X338000D01*
Y139800D01*
G01X319517Y157500D02*
Y160000D01*
X320558D01*
X320892Y159875D01*
X321100Y159708D01*
X321183Y159375D01*
X321100Y159042D01*
X320850Y158833D01*
X320558Y158708D01*
X319517D01*
G01X320558D02*
X321183Y157500D01*
G01X322658Y158542D02*
X322950Y158833D01*
X323200Y159000D01*
X323533Y159083D01*
X323825Y159000D01*
X324033Y158833D01*
X324200Y158583D01*
X324242Y158292D01*
X324200Y158042D01*
X324033Y157792D01*
X323783Y157583D01*
X323492Y157500D01*
X323158Y157583D01*
X322867Y157833D01*
X322700Y158208D01*
X322658Y158625D01*
X322742Y159167D01*
X322867Y159458D01*
X323075Y159750D01*
X323367Y159958D01*
X323658Y160000D01*
X323950Y159917D01*
X324158Y159708D01*
G01X325758Y158542D02*
X326050Y158833D01*
X326300Y159000D01*
X326633Y159083D01*
X326925Y159000D01*
X327133Y158833D01*
X327300Y158583D01*
X327342Y158292D01*
X327300Y158042D01*
X327133Y157792D01*
X326883Y157583D01*
X326592Y157500D01*
X326258Y157583D01*
X325967Y157833D01*
X325800Y158208D01*
X325758Y158625D01*
X325842Y159167D01*
X325967Y159458D01*
X326175Y159750D01*
X326467Y159958D01*
X326758Y160000D01*
X327050Y159917D01*
X327258Y159708D01*
G01X328942Y157792D02*
X329233Y157583D01*
X329567Y157500D01*
X329900Y157583D01*
X330192Y157833D01*
X330400Y158208D01*
X330483Y158583D01*
Y159042D01*
X330400Y159417D01*
X330192Y159750D01*
X329942Y159917D01*
X329650Y160000D01*
X329317Y159917D01*
X329067Y159750D01*
X328900Y159500D01*
X328817Y159167D01*
X328900Y158875D01*
X329108Y158583D01*
X329358Y158417D01*
X329650Y158375D01*
X329983Y158458D01*
X330233Y158667D01*
X330483Y159042D01*
G01X314200Y136500D02*
Y144500D01*
X331800D01*
Y136500D01*
X314200D01*
G01X303267Y147792D02*
X303017Y147917D01*
X302725Y148000D01*
X302392D01*
X302017Y147875D01*
X301725Y147667D01*
X301517Y147417D01*
X301350Y147000D01*
X301308Y146625D01*
X301392Y146250D01*
X301517Y146000D01*
X301767Y145750D01*
X302058Y145583D01*
X302350Y145500D01*
X302642D01*
X302933Y145583D01*
X303183Y145708D01*
X303392Y145875D01*
G01X304533Y146000D02*
X304783Y145708D01*
X305117Y145542D01*
X305492Y145500D01*
X305825Y145542D01*
X306158Y145750D01*
X306367Y146000D01*
X306408Y146250D01*
X306325Y146542D01*
X306033Y146750D01*
X305742Y146833D01*
X305367D01*
G01X305742D02*
X305992Y146958D01*
X306200Y147167D01*
X306283Y147417D01*
X306200Y147667D01*
X305992Y147875D01*
X305617Y148000D01*
X305242Y147958D01*
X304867Y147792D01*
G01X308467Y145500D02*
X308550Y146042D01*
X308675Y146500D01*
X308842Y146917D01*
X309050Y147375D01*
X309383Y148000D01*
X307717D01*
G01X310858Y147583D02*
X311108Y147833D01*
X311400Y147958D01*
X311733Y148000D01*
X312150Y147917D01*
X312442Y147708D01*
X312525Y147458D01*
X312483Y147208D01*
X312317Y147000D01*
X311483Y146583D01*
X311108Y146292D01*
X310858Y145875D01*
X310775Y145500D01*
X312525D01*
G01X327767Y173292D02*
X327517Y173417D01*
X327225Y173500D01*
X326892D01*
X326517Y173375D01*
X326225Y173167D01*
X326017Y172917D01*
X325850Y172500D01*
X325808Y172125D01*
X325892Y171750D01*
X326017Y171500D01*
X326267Y171250D01*
X326558Y171083D01*
X326850Y171000D01*
X327142D01*
X327433Y171083D01*
X327683Y171208D01*
X327892Y171375D01*
G01X329033Y171500D02*
X329283Y171208D01*
X329617Y171042D01*
X329992Y171000D01*
X330325Y171042D01*
X330658Y171250D01*
X330867Y171500D01*
X330908Y171750D01*
X330825Y172042D01*
X330533Y172250D01*
X330242Y172333D01*
X329867D01*
G01X330242D02*
X330492Y172458D01*
X330700Y172667D01*
X330783Y172917D01*
X330700Y173167D01*
X330492Y173375D01*
X330117Y173500D01*
X329742Y173458D01*
X329367Y173292D01*
G01X332967Y171000D02*
X333050Y171542D01*
X333175Y172000D01*
X333342Y172417D01*
X333550Y172875D01*
X333883Y173500D01*
X332217D01*
G01X335233Y171500D02*
X335483Y171208D01*
X335817Y171042D01*
X336192Y171000D01*
X336525Y171042D01*
X336858Y171250D01*
X337067Y171500D01*
X337108Y171750D01*
X337025Y172042D01*
X336733Y172250D01*
X336442Y172333D01*
X336067D01*
G01X336442D02*
X336692Y172458D01*
X336900Y172667D01*
X336983Y172917D01*
X336900Y173167D01*
X336692Y173375D01*
X336317Y173500D01*
X335942Y173458D01*
X335567Y173292D01*
G01X347775Y210000D02*
Y212500D01*
G01X349525D02*
Y210000D01*
G01Y211250D02*
X347775D01*
G01X350833Y210000D02*
Y212500D01*
X351667D01*
X352000Y212375D01*
X352250Y212208D01*
X352458Y211958D01*
X352625Y211667D01*
X352667Y211250D01*
X352625Y210833D01*
X352458Y210542D01*
X352250Y210292D01*
X352000Y210125D01*
X351667Y210000D01*
X350833D01*
G01X353933D02*
Y212500D01*
X354767D01*
X355100Y212375D01*
X355350Y212208D01*
X355558Y211958D01*
X355725Y211667D01*
X355767Y211250D01*
X355725Y210833D01*
X355558Y210542D01*
X355350Y210292D01*
X355100Y210125D01*
X354767Y210000D01*
X353933D01*
G01X357075Y210333D02*
X357408Y210125D01*
X357783Y210000D01*
X358117D01*
X358450Y210125D01*
X358700Y210333D01*
X358825Y210625D01*
X358742Y210917D01*
X358533Y211167D01*
X358158Y211333D01*
X357658Y211417D01*
X357367Y211583D01*
X357242Y211875D01*
X357325Y212167D01*
X357533Y212375D01*
X357825Y212500D01*
X358117D01*
X358408Y212417D01*
X358658Y212208D01*
G01X360008Y210000D02*
X361050Y212500D01*
X362092Y210000D01*
G01X361717Y210875D02*
X360383D01*
G01X363275Y210333D02*
X363608Y210125D01*
X363983Y210000D01*
X364317D01*
X364650Y210125D01*
X364900Y210333D01*
X365025Y210625D01*
X364942Y210917D01*
X364733Y211167D01*
X364358Y211333D01*
X363858Y211417D01*
X363567Y211583D01*
X363442Y211875D01*
X363525Y212167D01*
X363733Y212375D01*
X364025Y212500D01*
X364317D01*
X364608Y212417D01*
X364858Y212208D01*
G01X366458Y212083D02*
X366708Y212333D01*
X367000Y212458D01*
X367333Y212500D01*
X367750Y212417D01*
X368042Y212208D01*
X368125Y211958D01*
X368083Y211708D01*
X367917Y211500D01*
X367083Y211083D01*
X366708Y210792D01*
X366458Y210375D01*
X366375Y210000D01*
X368125D01*
G01X369558Y211042D02*
X369850Y211333D01*
X370100Y211500D01*
X370433Y211583D01*
X370725Y211500D01*
X370933Y211333D01*
X371100Y211083D01*
X371142Y210792D01*
X371100Y210542D01*
X370933Y210292D01*
X370683Y210083D01*
X370392Y210000D01*
X370058Y210083D01*
X369767Y210333D01*
X369600Y210708D01*
X369558Y211125D01*
X369642Y211667D01*
X369767Y211958D01*
X369975Y212250D01*
X370267Y212458D01*
X370558Y212500D01*
X370850Y212417D01*
X371058Y212208D01*
G01X312967Y269000D02*
Y266500D01*
X314633D01*
G01X317733D02*
X316067D01*
Y269000D01*
X317733D01*
G01X317067Y267792D02*
X316067D01*
G01X319083Y266500D02*
Y269000D01*
X319917D01*
X320250Y268875D01*
X320500Y268708D01*
X320708Y268458D01*
X320875Y268167D01*
X320917Y267750D01*
X320875Y267333D01*
X320708Y267042D01*
X320500Y266792D01*
X320250Y266625D01*
X319917Y266500D01*
X319083D01*
G01X323100D02*
Y269000D01*
X322600Y268500D01*
G01Y266500D02*
X323600D01*
G01X325283Y266875D02*
X325533Y266667D01*
X325825Y266542D01*
X326200Y266500D01*
X326575Y266583D01*
X326867Y266750D01*
X327075Y267042D01*
X327117Y267375D01*
X327033Y267708D01*
X326825Y267917D01*
X326533Y268083D01*
X326242Y268125D01*
X325950Y268083D01*
X325575Y267917D01*
X325700Y269000D01*
X326825D01*
G01X314104Y251880D02*
Y263080D01*
X322904D01*
Y251880D01*
X314104D01*
G01X342549Y560075D02*
X347599D01*
Y658775D01*
X372249D01*
Y474375D01*
X347599D01*
Y533075D01*
X342549D01*
Y560075D01*
G01X300017Y407000D02*
Y409500D01*
X301058D01*
X301392Y409375D01*
X301600Y409208D01*
X301683Y408875D01*
X301600Y408542D01*
X301350Y408333D01*
X301058Y408208D01*
X300017D01*
G01X301058D02*
X301683Y407000D01*
G01X303033Y407500D02*
X303283Y407208D01*
X303617Y407042D01*
X303992Y407000D01*
X304325Y407042D01*
X304658Y407250D01*
X304867Y407500D01*
X304908Y407750D01*
X304825Y408042D01*
X304533Y408250D01*
X304242Y408333D01*
X303867D01*
G01X304242D02*
X304492Y408458D01*
X304700Y408667D01*
X304783Y408917D01*
X304700Y409167D01*
X304492Y409375D01*
X304117Y409500D01*
X303742Y409458D01*
X303367Y409292D01*
G01X306967Y407000D02*
X307050Y407542D01*
X307175Y408000D01*
X307342Y408417D01*
X307550Y408875D01*
X307883Y409500D01*
X306217D01*
G01X309358Y409083D02*
X309608Y409333D01*
X309900Y409458D01*
X310233Y409500D01*
X310650Y409417D01*
X310942Y409208D01*
X311025Y408958D01*
X310983Y408708D01*
X310817Y408500D01*
X309983Y408083D01*
X309608Y407792D01*
X309358Y407375D01*
X309275Y407000D01*
X311025D01*
G01X311225Y401259D02*
Y405259D01*
X303825D01*
G01X317400Y400017D02*
X314900D01*
Y401058D01*
X315025Y401392D01*
X315192Y401600D01*
X315525Y401683D01*
X315858Y401600D01*
X316067Y401350D01*
X316192Y401058D01*
Y400017D01*
G01Y401058D02*
X317400Y401683D01*
G01Y404450D02*
X314900D01*
X316692Y402908D01*
Y404992D01*
G01X314900Y407050D02*
X314983Y406717D01*
X315192Y406467D01*
X315442Y406300D01*
X315775Y406175D01*
X316150Y406133D01*
X316525Y406175D01*
X316858Y406300D01*
X317108Y406467D01*
X317317Y406717D01*
X317400Y407050D01*
X317317Y407383D01*
X317108Y407633D01*
X316858Y407800D01*
X316525Y407925D01*
X316150Y407967D01*
X315775Y407925D01*
X315442Y407800D01*
X315192Y407633D01*
X314983Y407383D01*
X314900Y407050D01*
G01X315317Y409358D02*
X315067Y409608D01*
X314942Y409900D01*
X314900Y410233D01*
X314983Y410650D01*
X315192Y410942D01*
X315442Y411025D01*
X315692Y410983D01*
X315900Y410817D01*
X316317Y409983D01*
X316608Y409608D01*
X317025Y409358D01*
X317400Y409275D01*
Y411025D01*
G01X321400Y400017D02*
X318900D01*
Y401058D01*
X319025Y401392D01*
X319192Y401600D01*
X319525Y401683D01*
X319858Y401600D01*
X320067Y401350D01*
X320192Y401058D01*
Y400017D01*
G01Y401058D02*
X321400Y401683D01*
G01Y404450D02*
X318900D01*
X320692Y402908D01*
Y404992D01*
G01X318900Y407050D02*
X318983Y406717D01*
X319192Y406467D01*
X319442Y406300D01*
X319775Y406175D01*
X320150Y406133D01*
X320525Y406175D01*
X320858Y406300D01*
X321108Y406467D01*
X321317Y406717D01*
X321400Y407050D01*
X321317Y407383D01*
X321108Y407633D01*
X320858Y407800D01*
X320525Y407925D01*
X320150Y407967D01*
X319775Y407925D01*
X319442Y407800D01*
X319192Y407633D01*
X318983Y407383D01*
X318900Y407050D01*
G01X321025Y409233D02*
X321233Y409483D01*
X321358Y409775D01*
X321400Y410150D01*
X321317Y410525D01*
X321150Y410817D01*
X320858Y411025D01*
X320525Y411067D01*
X320192Y410983D01*
X319983Y410775D01*
X319817Y410483D01*
X319775Y410192D01*
X319817Y409900D01*
X319983Y409525D01*
X318900Y409650D01*
Y410775D01*
G01X303850Y381500D02*
X303517Y381542D01*
X303225Y381708D01*
X302975Y381958D01*
X302808Y382250D01*
X302725Y382583D01*
Y382917D01*
X302808Y383250D01*
X302975Y383542D01*
X303225Y383792D01*
X303517Y383958D01*
X303850Y384000D01*
X304183Y383958D01*
X304475Y383792D01*
X304725Y383542D01*
X304892Y383250D01*
X304975Y382917D01*
Y382583D01*
X304892Y382250D01*
X304725Y381958D01*
X304475Y381708D01*
X304183Y381542D01*
X303850Y381500D01*
G01X304183Y382167D02*
X304683Y381500D01*
G01X306158Y383583D02*
X306408Y383833D01*
X306700Y383958D01*
X307033Y384000D01*
X307450Y383917D01*
X307742Y383708D01*
X307825Y383458D01*
X307783Y383208D01*
X307617Y383000D01*
X306783Y382583D01*
X306408Y382292D01*
X306158Y381875D01*
X306075Y381500D01*
X307825D01*
G01X309133Y382000D02*
X309383Y381708D01*
X309717Y381542D01*
X310092Y381500D01*
X310425Y381542D01*
X310758Y381750D01*
X310967Y382000D01*
X311008Y382250D01*
X310925Y382542D01*
X310633Y382750D01*
X310342Y382833D01*
X309967D01*
G01X310342D02*
X310592Y382958D01*
X310800Y383167D01*
X310883Y383417D01*
X310800Y383667D01*
X310592Y383875D01*
X310217Y384000D01*
X309842Y383958D01*
X309467Y383792D01*
G01X312233Y382000D02*
X312483Y381708D01*
X312817Y381542D01*
X313192Y381500D01*
X313525Y381542D01*
X313858Y381750D01*
X314067Y382000D01*
X314108Y382250D01*
X314025Y382542D01*
X313733Y382750D01*
X313442Y382833D01*
X313067D01*
G01X313442D02*
X313692Y382958D01*
X313900Y383167D01*
X313983Y383417D01*
X313900Y383667D01*
X313692Y383875D01*
X313317Y384000D01*
X312942Y383958D01*
X312567Y383792D01*
G01X311900Y385800D02*
Y399800D01*
G01X298900Y385800D02*
X311900D01*
G01X298900Y399800D02*
Y385800D01*
G01X311900Y399800D02*
X298900D01*
G01X297792Y386707D02*
Y399707D01*
G01X299767Y545453D02*
X299517Y545578D01*
X299225Y545661D01*
X298892D01*
X298517Y545536D01*
X298225Y545328D01*
X298017Y545078D01*
X297850Y544661D01*
X297808Y544286D01*
X297892Y543911D01*
X298017Y543661D01*
X298267Y543411D01*
X298558Y543244D01*
X298850Y543161D01*
X299142D01*
X299433Y543244D01*
X299683Y543369D01*
X299892Y543536D01*
G01X301158Y545244D02*
X301408Y545494D01*
X301700Y545619D01*
X302033Y545661D01*
X302450Y545578D01*
X302742Y545369D01*
X302825Y545119D01*
X302783Y544869D01*
X302617Y544661D01*
X301783Y544244D01*
X301408Y543953D01*
X301158Y543536D01*
X301075Y543161D01*
X302825D01*
G01X304258Y545244D02*
X304508Y545494D01*
X304800Y545619D01*
X305133Y545661D01*
X305550Y545578D01*
X305842Y545369D01*
X305925Y545119D01*
X305883Y544869D01*
X305717Y544661D01*
X304883Y544244D01*
X304508Y543953D01*
X304258Y543536D01*
X304175Y543161D01*
X305925D01*
G01X308150Y545661D02*
X307817Y545578D01*
X307567Y545369D01*
X307400Y545119D01*
X307275Y544786D01*
X307233Y544411D01*
X307275Y544036D01*
X307400Y543703D01*
X307567Y543453D01*
X307817Y543244D01*
X308150Y543161D01*
X308483Y543244D01*
X308733Y543453D01*
X308900Y543703D01*
X309025Y544036D01*
X309067Y544411D01*
X309025Y544786D01*
X308900Y545119D01*
X308733Y545369D01*
X308483Y545578D01*
X308150Y545661D01*
G01X298017Y539161D02*
Y541661D01*
X299058D01*
X299392Y541536D01*
X299600Y541369D01*
X299683Y541036D01*
X299600Y540703D01*
X299350Y540494D01*
X299058Y540369D01*
X298017D01*
G01X299058D02*
X299683Y539161D01*
G01X301033Y539661D02*
X301283Y539369D01*
X301617Y539203D01*
X301992Y539161D01*
X302325Y539203D01*
X302658Y539411D01*
X302867Y539661D01*
X302908Y539911D01*
X302825Y540203D01*
X302533Y540411D01*
X302242Y540494D01*
X301867D01*
G01X302242D02*
X302492Y540619D01*
X302700Y540828D01*
X302783Y541078D01*
X302700Y541328D01*
X302492Y541536D01*
X302117Y541661D01*
X301742Y541619D01*
X301367Y541453D01*
G01X304342Y539453D02*
X304633Y539244D01*
X304967Y539161D01*
X305300Y539244D01*
X305592Y539494D01*
X305800Y539869D01*
X305883Y540244D01*
Y540703D01*
X305800Y541078D01*
X305592Y541411D01*
X305342Y541578D01*
X305050Y541661D01*
X304717Y541578D01*
X304467Y541411D01*
X304300Y541161D01*
X304217Y540828D01*
X304300Y540536D01*
X304508Y540244D01*
X304758Y540078D01*
X305050Y540036D01*
X305383Y540119D01*
X305633Y540328D01*
X305883Y540703D01*
G01X307442Y539453D02*
X307733Y539244D01*
X308067Y539161D01*
X308400Y539244D01*
X308692Y539494D01*
X308900Y539869D01*
X308983Y540244D01*
Y540703D01*
X308900Y541078D01*
X308692Y541411D01*
X308442Y541578D01*
X308150Y541661D01*
X307817Y541578D01*
X307567Y541411D01*
X307400Y541161D01*
X307317Y540828D01*
X307400Y540536D01*
X307608Y540244D01*
X307858Y540078D01*
X308150Y540036D01*
X308483Y540119D01*
X308733Y540328D01*
X308983Y540703D01*
G01X310800Y545500D02*
Y541500D01*
X318200D01*
G01X332017Y506000D02*
Y508500D01*
X333058D01*
X333392Y508375D01*
X333600Y508208D01*
X333683Y507875D01*
X333600Y507542D01*
X333350Y507333D01*
X333058Y507208D01*
X332017D01*
G01X333058D02*
X333683Y506000D01*
G01X336450D02*
Y508500D01*
X334908Y506708D01*
X336992D01*
G01X339050Y508500D02*
X338717Y508417D01*
X338467Y508208D01*
X338300Y507958D01*
X338175Y507625D01*
X338133Y507250D01*
X338175Y506875D01*
X338300Y506542D01*
X338467Y506292D01*
X338717Y506083D01*
X339050Y506000D01*
X339383Y506083D01*
X339633Y506292D01*
X339800Y506542D01*
X339925Y506875D01*
X339967Y507250D01*
X339925Y507625D01*
X339800Y507958D01*
X339633Y508208D01*
X339383Y508417D01*
X339050Y508500D01*
G01X342150D02*
X341817Y508417D01*
X341567Y508208D01*
X341400Y507958D01*
X341275Y507625D01*
X341233Y507250D01*
X341275Y506875D01*
X341400Y506542D01*
X341567Y506292D01*
X341817Y506083D01*
X342150Y506000D01*
X342483Y506083D01*
X342733Y506292D01*
X342900Y506542D01*
X343025Y506875D01*
X343067Y507250D01*
X343025Y507625D01*
X342900Y507958D01*
X342733Y508208D01*
X342483Y508417D01*
X342150Y508500D01*
G01X342700Y523300D02*
Y527300D01*
X335300D01*
G01X332017Y502000D02*
Y504500D01*
X333058D01*
X333392Y504375D01*
X333600Y504208D01*
X333683Y503875D01*
X333600Y503542D01*
X333350Y503333D01*
X333058Y503208D01*
X332017D01*
G01X333058D02*
X333683Y502000D01*
G01X336450D02*
Y504500D01*
X334908Y502708D01*
X336992D01*
G01X339050Y504500D02*
X338717Y504417D01*
X338467Y504208D01*
X338300Y503958D01*
X338175Y503625D01*
X338133Y503250D01*
X338175Y502875D01*
X338300Y502542D01*
X338467Y502292D01*
X338717Y502083D01*
X339050Y502000D01*
X339383Y502083D01*
X339633Y502292D01*
X339800Y502542D01*
X339925Y502875D01*
X339967Y503250D01*
X339925Y503625D01*
X339800Y503958D01*
X339633Y504208D01*
X339383Y504417D01*
X339050Y504500D01*
G01X341233Y502500D02*
X341483Y502208D01*
X341817Y502042D01*
X342192Y502000D01*
X342525Y502042D01*
X342858Y502250D01*
X343067Y502500D01*
X343108Y502750D01*
X343025Y503042D01*
X342733Y503250D01*
X342442Y503333D01*
X342067D01*
G01X342442D02*
X342692Y503458D01*
X342900Y503667D01*
X342983Y503917D01*
X342900Y504167D01*
X342692Y504375D01*
X342317Y504500D01*
X341942Y504458D01*
X341567Y504292D01*
G01X340500Y514800D02*
Y518800D01*
X333100D01*
G01X332017Y510000D02*
Y512500D01*
X333058D01*
X333392Y512375D01*
X333600Y512208D01*
X333683Y511875D01*
X333600Y511542D01*
X333350Y511333D01*
X333058Y511208D01*
X332017D01*
G01X333058D02*
X333683Y510000D01*
G01X336450D02*
Y512500D01*
X334908Y510708D01*
X336992D01*
G01X339050Y512500D02*
X338717Y512417D01*
X338467Y512208D01*
X338300Y511958D01*
X338175Y511625D01*
X338133Y511250D01*
X338175Y510875D01*
X338300Y510542D01*
X338467Y510292D01*
X338717Y510083D01*
X339050Y510000D01*
X339383Y510083D01*
X339633Y510292D01*
X339800Y510542D01*
X339925Y510875D01*
X339967Y511250D01*
X339925Y511625D01*
X339800Y511958D01*
X339633Y512208D01*
X339383Y512417D01*
X339050Y512500D01*
G01X342650Y510000D02*
Y512500D01*
X341108Y510708D01*
X343192D01*
G01X335300Y531500D02*
Y527500D01*
X342700D01*
G01X299017Y511500D02*
Y514000D01*
X300058D01*
X300392Y513875D01*
X300600Y513708D01*
X300683Y513375D01*
X300600Y513042D01*
X300350Y512833D01*
X300058Y512708D01*
X299017D01*
G01X300058D02*
X300683Y511500D01*
G01X303450D02*
Y514000D01*
X301908Y512208D01*
X303992D01*
G01X306050Y514000D02*
X305717Y513917D01*
X305467Y513708D01*
X305300Y513458D01*
X305175Y513125D01*
X305133Y512750D01*
X305175Y512375D01*
X305300Y512042D01*
X305467Y511792D01*
X305717Y511583D01*
X306050Y511500D01*
X306383Y511583D01*
X306633Y511792D01*
X306800Y512042D01*
X306925Y512375D01*
X306967Y512750D01*
X306925Y513125D01*
X306800Y513458D01*
X306633Y513708D01*
X306383Y513917D01*
X306050Y514000D01*
G01X308358Y512542D02*
X308650Y512833D01*
X308900Y513000D01*
X309233Y513083D01*
X309525Y513000D01*
X309733Y512833D01*
X309900Y512583D01*
X309942Y512292D01*
X309900Y512042D01*
X309733Y511792D01*
X309483Y511583D01*
X309192Y511500D01*
X308858Y511583D01*
X308567Y511833D01*
X308400Y512208D01*
X308358Y512625D01*
X308442Y513167D01*
X308567Y513458D01*
X308775Y513750D01*
X309067Y513958D01*
X309358Y514000D01*
X309650Y513917D01*
X309858Y513708D01*
G01X303300Y520000D02*
Y516000D01*
X310700D01*
G01Y547000D02*
Y551000D01*
X303300D01*
G01X305000Y521517D02*
X302500D01*
Y522558D01*
X302625Y522892D01*
X302792Y523100D01*
X303125Y523183D01*
X303458Y523100D01*
X303667Y522850D01*
X303792Y522558D01*
Y521517D01*
G01Y522558D02*
X305000Y523183D01*
G01Y525950D02*
X302500D01*
X304292Y524408D01*
Y526492D01*
G01X302500Y528550D02*
X302583Y528217D01*
X302792Y527967D01*
X303042Y527800D01*
X303375Y527675D01*
X303750Y527633D01*
X304125Y527675D01*
X304458Y527800D01*
X304708Y527967D01*
X304917Y528217D01*
X305000Y528550D01*
X304917Y528883D01*
X304708Y529133D01*
X304458Y529300D01*
X304125Y529425D01*
X303750Y529467D01*
X303375Y529425D01*
X303042Y529300D01*
X302792Y529133D01*
X302583Y528883D01*
X302500Y528550D01*
G01X305000Y531650D02*
X304958Y531942D01*
X304833Y532275D01*
X304625Y532483D01*
X304333Y532567D01*
X304042Y532483D01*
X303792Y532233D01*
X303667Y531858D01*
Y531442D01*
X303583Y531192D01*
X303375Y530983D01*
X303083Y530900D01*
X302792Y531025D01*
X302583Y531317D01*
X302500Y531650D01*
X302583Y531983D01*
X302792Y532275D01*
X303083Y532400D01*
X303375Y532317D01*
X303583Y532108D01*
X303667Y531858D01*
Y531442D01*
X303792Y531067D01*
X304042Y530817D01*
X304333Y530733D01*
X304625Y530817D01*
X304833Y531025D01*
X304958Y531358D01*
X305000Y531650D01*
G01X306500Y520300D02*
X310500D01*
Y527700D01*
G01X322000Y501517D02*
X319500D01*
Y502558D01*
X319625Y502892D01*
X319792Y503100D01*
X320125Y503183D01*
X320458Y503100D01*
X320667Y502850D01*
X320792Y502558D01*
Y501517D01*
G01Y502558D02*
X322000Y503183D01*
G01Y505950D02*
X319500D01*
X321292Y504408D01*
Y506492D01*
G01X319500Y508550D02*
X319583Y508217D01*
X319792Y507967D01*
X320042Y507800D01*
X320375Y507675D01*
X320750Y507633D01*
X321125Y507675D01*
X321458Y507800D01*
X321708Y507967D01*
X321917Y508217D01*
X322000Y508550D01*
X321917Y508883D01*
X321708Y509133D01*
X321458Y509300D01*
X321125Y509425D01*
X320750Y509467D01*
X320375Y509425D01*
X320042Y509300D01*
X319792Y509133D01*
X319583Y508883D01*
X319500Y508550D01*
G01X321708Y510942D02*
X321917Y511233D01*
X322000Y511567D01*
X321917Y511900D01*
X321667Y512192D01*
X321292Y512400D01*
X320917Y512483D01*
X320458D01*
X320083Y512400D01*
X319750Y512192D01*
X319583Y511942D01*
X319500Y511650D01*
X319583Y511317D01*
X319750Y511067D01*
X320000Y510900D01*
X320333Y510817D01*
X320625Y510900D01*
X320917Y511108D01*
X321083Y511358D01*
X321125Y511650D01*
X321042Y511983D01*
X320833Y512233D01*
X320458Y512483D01*
G01X323000Y521700D02*
X319000D01*
Y514300D01*
G01X327400Y571000D02*
X327067Y571042D01*
X326775Y571208D01*
X326525Y571458D01*
X326358Y571750D01*
X326275Y572083D01*
Y572417D01*
X326358Y572750D01*
X326525Y573042D01*
X326775Y573292D01*
X327067Y573458D01*
X327400Y573500D01*
X327733Y573458D01*
X328025Y573292D01*
X328275Y573042D01*
X328442Y572750D01*
X328525Y572417D01*
Y572083D01*
X328442Y571750D01*
X328275Y571458D01*
X328025Y571208D01*
X327733Y571042D01*
X327400Y571000D01*
G01X327733Y571667D02*
X328233Y571000D01*
G01X329583Y571375D02*
X329833Y571167D01*
X330125Y571042D01*
X330500Y571000D01*
X330875Y571083D01*
X331167Y571250D01*
X331375Y571542D01*
X331417Y571875D01*
X331333Y572208D01*
X331125Y572417D01*
X330833Y572583D01*
X330542Y572625D01*
X330250Y572583D01*
X329875Y572417D01*
X330000Y573500D01*
X331125D01*
G01X333517Y571000D02*
X333600Y571542D01*
X333725Y572000D01*
X333892Y572417D01*
X334100Y572875D01*
X334433Y573500D01*
X332767D01*
G01X340700Y554000D02*
X338600Y555800D01*
X340700Y558000D01*
G01X340800Y561600D02*
X321600D01*
Y550400D01*
X340800D01*
Y561600D01*
X340400D01*
G01X296200Y568400D02*
X315400D01*
Y579600D01*
X296200D01*
Y568400D01*
X296600D01*
G01X316000Y501983D02*
X313500D01*
Y502817D01*
X313625Y503150D01*
X313792Y503400D01*
X314042Y503608D01*
X314333Y503775D01*
X314750Y503817D01*
X315167Y503775D01*
X315458Y503608D01*
X315708Y503400D01*
X315875Y503150D01*
X316000Y502817D01*
Y501983D01*
G01Y506000D02*
X313500D01*
X314000Y505500D01*
G01X316000D02*
Y506500D01*
G01Y509600D02*
X313500D01*
X315292Y508058D01*
Y510142D01*
G01X318500Y530500D02*
Y514400D01*
G01X311500Y530500D02*
X318500D01*
G01X311500Y514400D02*
Y530500D01*
G01X318500Y514400D02*
X311500D01*
G01X315400Y536200D02*
X315067Y536242D01*
X314775Y536408D01*
X314525Y536658D01*
X314358Y536950D01*
X314275Y537283D01*
Y537617D01*
X314358Y537950D01*
X314525Y538242D01*
X314775Y538492D01*
X315067Y538658D01*
X315400Y538700D01*
X315733Y538658D01*
X316025Y538492D01*
X316275Y538242D01*
X316442Y537950D01*
X316525Y537617D01*
Y537283D01*
X316442Y536950D01*
X316275Y536658D01*
X316025Y536408D01*
X315733Y536242D01*
X315400Y536200D01*
G01X315733Y536867D02*
X316233Y536200D01*
G01X317583Y536575D02*
X317833Y536367D01*
X318125Y536242D01*
X318500Y536200D01*
X318875Y536283D01*
X319167Y536450D01*
X319375Y536742D01*
X319417Y537075D01*
X319333Y537408D01*
X319125Y537617D01*
X318833Y537783D01*
X318542Y537825D01*
X318250Y537783D01*
X317875Y537617D01*
X318000Y538700D01*
X319125D01*
G01X320892Y536492D02*
X321183Y536283D01*
X321517Y536200D01*
X321850Y536283D01*
X322142Y536533D01*
X322350Y536908D01*
X322433Y537283D01*
Y537742D01*
X322350Y538117D01*
X322142Y538450D01*
X321892Y538617D01*
X321600Y538700D01*
X321267Y538617D01*
X321017Y538450D01*
X320850Y538200D01*
X320767Y537867D01*
X320850Y537575D01*
X321058Y537283D01*
X321308Y537117D01*
X321600Y537075D01*
X321933Y537158D01*
X322183Y537367D01*
X322433Y537742D01*
G01X334700Y536200D02*
X323300D01*
G01X334700Y522800D02*
Y536200D01*
G01X323300Y522800D02*
X334700D01*
G01X323300Y536200D02*
Y522800D01*
G01X348275Y662000D02*
Y664500D01*
G01X350025D02*
Y662000D01*
G01Y663250D02*
X348275D01*
G01X351333Y662000D02*
Y664500D01*
X352167D01*
X352500Y664375D01*
X352750Y664208D01*
X352958Y663958D01*
X353125Y663667D01*
X353167Y663250D01*
X353125Y662833D01*
X352958Y662542D01*
X352750Y662292D01*
X352500Y662125D01*
X352167Y662000D01*
X351333D01*
G01X354433D02*
Y664500D01*
X355267D01*
X355600Y664375D01*
X355850Y664208D01*
X356058Y663958D01*
X356225Y663667D01*
X356267Y663250D01*
X356225Y662833D01*
X356058Y662542D01*
X355850Y662292D01*
X355600Y662125D01*
X355267Y662000D01*
X354433D01*
G01X357575Y662333D02*
X357908Y662125D01*
X358283Y662000D01*
X358617D01*
X358950Y662125D01*
X359200Y662333D01*
X359325Y662625D01*
X359242Y662917D01*
X359033Y663167D01*
X358658Y663333D01*
X358158Y663417D01*
X357867Y663583D01*
X357742Y663875D01*
X357825Y664167D01*
X358033Y664375D01*
X358325Y664500D01*
X358617D01*
X358908Y664417D01*
X359158Y664208D01*
G01X360508Y662000D02*
X361550Y664500D01*
X362592Y662000D01*
G01X362217Y662875D02*
X360883D01*
G01X363775Y662333D02*
X364108Y662125D01*
X364483Y662000D01*
X364817D01*
X365150Y662125D01*
X365400Y662333D01*
X365525Y662625D01*
X365442Y662917D01*
X365233Y663167D01*
X364858Y663333D01*
X364358Y663417D01*
X364067Y663583D01*
X363942Y663875D01*
X364025Y664167D01*
X364233Y664375D01*
X364525Y664500D01*
X364817D01*
X365108Y664417D01*
X365358Y664208D01*
G01X367750Y662000D02*
Y664500D01*
X367250Y664000D01*
G01Y662000D02*
X368250D01*
G01X371350D02*
Y664500D01*
X369808Y662708D01*
X371892D01*
G01X391200Y581000D02*
Y585000D01*
X383800D01*
G01X320867Y609292D02*
X320617Y609417D01*
X320325Y609500D01*
X319992D01*
X319617Y609375D01*
X319325Y609167D01*
X319117Y608917D01*
X318950Y608500D01*
X318908Y608125D01*
X318992Y607750D01*
X319117Y607500D01*
X319367Y607250D01*
X319658Y607083D01*
X319950Y607000D01*
X320242D01*
X320533Y607083D01*
X320783Y607208D01*
X320992Y607375D01*
G01X322258Y609083D02*
X322508Y609333D01*
X322800Y609458D01*
X323133Y609500D01*
X323550Y609417D01*
X323842Y609208D01*
X323925Y608958D01*
X323883Y608708D01*
X323717Y608500D01*
X322883Y608083D01*
X322508Y607792D01*
X322258Y607375D01*
X322175Y607000D01*
X323925D01*
G01X326150D02*
Y609500D01*
X325650Y609000D01*
G01Y607000D02*
X326650D01*
G01X328458Y609083D02*
X328708Y609333D01*
X329000Y609458D01*
X329333Y609500D01*
X329750Y609417D01*
X330042Y609208D01*
X330125Y608958D01*
X330083Y608708D01*
X329917Y608500D01*
X329083Y608083D01*
X328708Y607792D01*
X328458Y607375D01*
X328375Y607000D01*
X330125D01*
G01X337708Y632767D02*
X337583Y632517D01*
X337500Y632225D01*
Y631892D01*
X337625Y631517D01*
X337833Y631225D01*
X338083Y631017D01*
X338500Y630850D01*
X338875Y630808D01*
X339250Y630892D01*
X339500Y631017D01*
X339750Y631267D01*
X339917Y631558D01*
X340000Y631850D01*
Y632142D01*
X339917Y632433D01*
X339792Y632683D01*
X339625Y632892D01*
G01X337917Y634158D02*
X337667Y634408D01*
X337542Y634700D01*
X337500Y635033D01*
X337583Y635450D01*
X337792Y635742D01*
X338042Y635825D01*
X338292Y635783D01*
X338500Y635617D01*
X338917Y634783D01*
X339208Y634408D01*
X339625Y634158D01*
X340000Y634075D01*
Y635825D01*
G01Y638050D02*
X337500D01*
X338000Y637550D01*
G01X340000D02*
Y638550D01*
G01X339708Y640442D02*
X339917Y640733D01*
X340000Y641067D01*
X339917Y641400D01*
X339667Y641692D01*
X339292Y641900D01*
X338917Y641983D01*
X338458D01*
X338083Y641900D01*
X337750Y641692D01*
X337583Y641442D01*
X337500Y641150D01*
X337583Y640817D01*
X337750Y640567D01*
X338000Y640400D01*
X338333Y640317D01*
X338625Y640400D01*
X338917Y640608D01*
X339083Y640858D01*
X339125Y641150D01*
X339042Y641483D01*
X338833Y641733D01*
X338458Y641983D01*
G01X380850Y616000D02*
Y613500D01*
G01X379892Y616000D02*
X381808D01*
G01X383117Y613500D02*
Y616000D01*
X384117D01*
X384450Y615875D01*
X384700Y615583D01*
X384783Y615250D01*
X384700Y614917D01*
X384492Y614667D01*
X384117Y614542D01*
X383117D01*
G01X386342Y613792D02*
X386633Y613583D01*
X386967Y613500D01*
X387300Y613583D01*
X387592Y613833D01*
X387800Y614208D01*
X387883Y614583D01*
Y615042D01*
X387800Y615417D01*
X387592Y615750D01*
X387342Y615917D01*
X387050Y616000D01*
X386717Y615917D01*
X386467Y615750D01*
X386300Y615500D01*
X386217Y615167D01*
X386300Y614875D01*
X386508Y614583D01*
X386758Y614417D01*
X387050Y614375D01*
X387383Y614458D01*
X387633Y614667D01*
X387883Y615042D01*
G01X390150Y613500D02*
Y616000D01*
X389650Y615500D01*
G01Y613500D02*
X390650D01*
G01X296300Y576000D02*
X298400Y574200D01*
X296300Y572000D01*
G01X383517Y598000D02*
Y600500D01*
X384558D01*
X384892Y600375D01*
X385100Y600208D01*
X385183Y599875D01*
X385100Y599542D01*
X384850Y599333D01*
X384558Y599208D01*
X383517D01*
G01X384558D02*
X385183Y598000D01*
G01X386533Y598500D02*
X386783Y598208D01*
X387117Y598042D01*
X387492Y598000D01*
X387825Y598042D01*
X388158Y598250D01*
X388367Y598500D01*
X388408Y598750D01*
X388325Y599042D01*
X388033Y599250D01*
X387742Y599333D01*
X387367D01*
G01X387742D02*
X387992Y599458D01*
X388200Y599667D01*
X388283Y599917D01*
X388200Y600167D01*
X387992Y600375D01*
X387617Y600500D01*
X387242Y600458D01*
X386867Y600292D01*
G01X389842Y598292D02*
X390133Y598083D01*
X390467Y598000D01*
X390800Y598083D01*
X391092Y598333D01*
X391300Y598708D01*
X391383Y599083D01*
Y599542D01*
X391300Y599917D01*
X391092Y600250D01*
X390842Y600417D01*
X390550Y600500D01*
X390217Y600417D01*
X389967Y600250D01*
X389800Y600000D01*
X389717Y599667D01*
X389800Y599375D01*
X390008Y599083D01*
X390258Y598917D01*
X390550Y598875D01*
X390883Y598958D01*
X391133Y599167D01*
X391383Y599542D01*
G01X392858Y599042D02*
X393150Y599333D01*
X393400Y599500D01*
X393733Y599583D01*
X394025Y599500D01*
X394233Y599333D01*
X394400Y599083D01*
X394442Y598792D01*
X394400Y598542D01*
X394233Y598292D01*
X393983Y598083D01*
X393692Y598000D01*
X393358Y598083D01*
X393067Y598333D01*
X392900Y598708D01*
X392858Y599125D01*
X392942Y599667D01*
X393067Y599958D01*
X393275Y600250D01*
X393567Y600458D01*
X393858Y600500D01*
X394150Y600417D01*
X394358Y600208D01*
G01X320767Y604953D02*
X320517Y605078D01*
X320225Y605161D01*
X319892D01*
X319517Y605036D01*
X319225Y604828D01*
X319017Y604578D01*
X318850Y604161D01*
X318808Y603786D01*
X318892Y603411D01*
X319017Y603161D01*
X319267Y602911D01*
X319558Y602744D01*
X319850Y602661D01*
X320142D01*
X320433Y602744D01*
X320683Y602869D01*
X320892Y603036D01*
G01X322158Y604744D02*
X322408Y604994D01*
X322700Y605119D01*
X323033Y605161D01*
X323450Y605078D01*
X323742Y604869D01*
X323825Y604619D01*
X323783Y604369D01*
X323617Y604161D01*
X322783Y603744D01*
X322408Y603453D01*
X322158Y603036D01*
X322075Y602661D01*
X323825D01*
G01X326050D02*
Y605161D01*
X325550Y604661D01*
G01Y602661D02*
X326550D01*
G01X328233Y603161D02*
X328483Y602869D01*
X328817Y602703D01*
X329192Y602661D01*
X329525Y602703D01*
X329858Y602911D01*
X330067Y603161D01*
X330108Y603411D01*
X330025Y603703D01*
X329733Y603911D01*
X329442Y603994D01*
X329067D01*
G01X329442D02*
X329692Y604119D01*
X329900Y604328D01*
X329983Y604578D01*
X329900Y604828D01*
X329692Y605036D01*
X329317Y605161D01*
X328942Y605119D01*
X328567Y604953D01*
G01X336300Y574500D02*
X330800D01*
G01X336300Y582500D02*
Y574500D01*
G01X330800Y582500D02*
X336300D01*
G01X318700D02*
X324200D01*
G01X318700Y574500D02*
Y582500D01*
G01X324200Y574500D02*
X318700D01*
G01X343000Y594017D02*
X340500D01*
Y595058D01*
X340625Y595392D01*
X340792Y595600D01*
X341125Y595683D01*
X341458Y595600D01*
X341667Y595350D01*
X341792Y595058D01*
Y594017D01*
G01Y595058D02*
X343000Y595683D01*
G01X342500Y597033D02*
X342792Y597283D01*
X342958Y597617D01*
X343000Y597992D01*
X342958Y598325D01*
X342750Y598658D01*
X342500Y598867D01*
X342250Y598908D01*
X341958Y598825D01*
X341750Y598533D01*
X341667Y598242D01*
Y597867D01*
G01Y598242D02*
X341542Y598492D01*
X341333Y598700D01*
X341083Y598783D01*
X340833Y598700D01*
X340625Y598492D01*
X340500Y598117D01*
X340542Y597742D01*
X340708Y597367D01*
G01X342708Y600342D02*
X342917Y600633D01*
X343000Y600967D01*
X342917Y601300D01*
X342667Y601592D01*
X342292Y601800D01*
X341917Y601883D01*
X341458D01*
X341083Y601800D01*
X340750Y601592D01*
X340583Y601342D01*
X340500Y601050D01*
X340583Y600717D01*
X340750Y600467D01*
X341000Y600300D01*
X341333Y600217D01*
X341625Y600300D01*
X341917Y600508D01*
X342083Y600758D01*
X342125Y601050D01*
X342042Y601383D01*
X341833Y601633D01*
X341458Y601883D01*
G01X343000Y604150D02*
X340500D01*
X341000Y603650D01*
G01X343000D02*
Y604650D01*
G01X338000Y592300D02*
X346000D01*
Y574700D01*
X338000D01*
Y592300D01*
G01X319517Y611000D02*
Y613500D01*
X320558D01*
X320892Y613375D01*
X321100Y613208D01*
X321183Y612875D01*
X321100Y612542D01*
X320850Y612333D01*
X320558Y612208D01*
X319517D01*
G01X320558D02*
X321183Y611000D01*
G01X322533Y611500D02*
X322783Y611208D01*
X323117Y611042D01*
X323492Y611000D01*
X323825Y611042D01*
X324158Y611250D01*
X324367Y611500D01*
X324408Y611750D01*
X324325Y612042D01*
X324033Y612250D01*
X323742Y612333D01*
X323367D01*
G01X323742D02*
X323992Y612458D01*
X324200Y612667D01*
X324283Y612917D01*
X324200Y613167D01*
X323992Y613375D01*
X323617Y613500D01*
X323242Y613458D01*
X322867Y613292D01*
G01X325842Y611292D02*
X326133Y611083D01*
X326467Y611000D01*
X326800Y611083D01*
X327092Y611333D01*
X327300Y611708D01*
X327383Y612083D01*
Y612542D01*
X327300Y612917D01*
X327092Y613250D01*
X326842Y613417D01*
X326550Y613500D01*
X326217Y613417D01*
X325967Y613250D01*
X325800Y613000D01*
X325717Y612667D01*
X325800Y612375D01*
X326008Y612083D01*
X326258Y611917D01*
X326550Y611875D01*
X326883Y611958D01*
X327133Y612167D01*
X327383Y612542D01*
G01X328733Y611500D02*
X328983Y611208D01*
X329317Y611042D01*
X329692Y611000D01*
X330025Y611042D01*
X330358Y611250D01*
X330567Y611500D01*
X330608Y611750D01*
X330525Y612042D01*
X330233Y612250D01*
X329942Y612333D01*
X329567D01*
G01X329942D02*
X330192Y612458D01*
X330400Y612667D01*
X330483Y612917D01*
X330400Y613167D01*
X330192Y613375D01*
X329817Y613500D01*
X329442Y613458D01*
X329067Y613292D01*
G01X314200Y589000D02*
Y597000D01*
X331800D01*
Y589000D01*
X314200D01*
G01X302267Y601292D02*
X302017Y601417D01*
X301725Y601500D01*
X301392D01*
X301017Y601375D01*
X300725Y601167D01*
X300517Y600917D01*
X300350Y600500D01*
X300308Y600125D01*
X300392Y599750D01*
X300517Y599500D01*
X300767Y599250D01*
X301058Y599083D01*
X301350Y599000D01*
X301642D01*
X301933Y599083D01*
X302183Y599208D01*
X302392Y599375D01*
G01X303658Y601083D02*
X303908Y601333D01*
X304200Y601458D01*
X304533Y601500D01*
X304950Y601417D01*
X305242Y601208D01*
X305325Y600958D01*
X305283Y600708D01*
X305117Y600500D01*
X304283Y600083D01*
X303908Y599792D01*
X303658Y599375D01*
X303575Y599000D01*
X305325D01*
G01X307550D02*
Y601500D01*
X307050Y601000D01*
G01Y599000D02*
X308050D01*
G01X309858Y600042D02*
X310150Y600333D01*
X310400Y600500D01*
X310733Y600583D01*
X311025Y600500D01*
X311233Y600333D01*
X311400Y600083D01*
X311442Y599792D01*
X311400Y599542D01*
X311233Y599292D01*
X310983Y599083D01*
X310692Y599000D01*
X310358Y599083D01*
X310067Y599333D01*
X309900Y599708D01*
X309858Y600125D01*
X309942Y600667D01*
X310067Y600958D01*
X310275Y601250D01*
X310567Y601458D01*
X310858Y601500D01*
X311150Y601417D01*
X311358Y601208D01*
G01X334708Y619267D02*
X334583Y619017D01*
X334500Y618725D01*
Y618392D01*
X334625Y618017D01*
X334833Y617725D01*
X335083Y617517D01*
X335500Y617350D01*
X335875Y617308D01*
X336250Y617392D01*
X336500Y617517D01*
X336750Y617767D01*
X336917Y618058D01*
X337000Y618350D01*
Y618642D01*
X336917Y618933D01*
X336792Y619183D01*
X336625Y619392D01*
G01X334917Y620658D02*
X334667Y620908D01*
X334542Y621200D01*
X334500Y621533D01*
X334583Y621950D01*
X334792Y622242D01*
X335042Y622325D01*
X335292Y622283D01*
X335500Y622117D01*
X335917Y621283D01*
X336208Y620908D01*
X336625Y620658D01*
X337000Y620575D01*
Y622325D01*
G01Y624550D02*
X334500D01*
X335000Y624050D01*
G01X337000D02*
Y625050D01*
G01Y627567D02*
X336458Y627650D01*
X336000Y627775D01*
X335583Y627942D01*
X335125Y628150D01*
X334500Y628483D01*
Y626817D01*
G01X312517Y721000D02*
Y718500D01*
X314183D01*
G01X317283D02*
X315617D01*
Y721000D01*
X317283D01*
G01X316617Y719792D02*
X315617D01*
G01X318633Y718500D02*
Y721000D01*
X319467D01*
X319800Y720875D01*
X320050Y720708D01*
X320258Y720458D01*
X320425Y720167D01*
X320467Y719750D01*
X320425Y719333D01*
X320258Y719042D01*
X320050Y718792D01*
X319800Y718625D01*
X319467Y718500D01*
X318633D01*
G01X321733Y719000D02*
X321983Y718708D01*
X322317Y718542D01*
X322692Y718500D01*
X323025Y718542D01*
X323358Y718750D01*
X323567Y719000D01*
X323608Y719250D01*
X323525Y719542D01*
X323233Y719750D01*
X322942Y719833D01*
X322567D01*
G01X322942D02*
X323192Y719958D01*
X323400Y720167D01*
X323483Y720417D01*
X323400Y720667D01*
X323192Y720875D01*
X322817Y721000D01*
X322442Y720958D01*
X322067Y720792D01*
G01X314104Y704636D02*
Y715836D01*
X322904D01*
Y704636D01*
X314104D01*
G01X311225Y853959D02*
Y857959D01*
X303825D01*
G01X317000Y852517D02*
X314500D01*
Y853558D01*
X314625Y853892D01*
X314792Y854100D01*
X315125Y854183D01*
X315458Y854100D01*
X315667Y853850D01*
X315792Y853558D01*
Y852517D01*
G01Y853558D02*
X317000Y854183D01*
G01X314917Y855658D02*
X314667Y855908D01*
X314542Y856200D01*
X314500Y856533D01*
X314583Y856950D01*
X314792Y857242D01*
X315042Y857325D01*
X315292Y857283D01*
X315500Y857117D01*
X315917Y856283D01*
X316208Y855908D01*
X316625Y855658D01*
X317000Y855575D01*
Y857325D01*
G01X316500Y858633D02*
X316792Y858883D01*
X316958Y859217D01*
X317000Y859592D01*
X316958Y859925D01*
X316750Y860258D01*
X316500Y860467D01*
X316250Y860508D01*
X315958Y860425D01*
X315750Y860133D01*
X315667Y859842D01*
Y859467D01*
G01Y859842D02*
X315542Y860092D01*
X315333Y860300D01*
X315083Y860383D01*
X314833Y860300D01*
X314625Y860092D01*
X314500Y859717D01*
X314542Y859342D01*
X314708Y858967D01*
G01X315958Y861858D02*
X315667Y862150D01*
X315500Y862400D01*
X315417Y862733D01*
X315500Y863025D01*
X315667Y863233D01*
X315917Y863400D01*
X316208Y863442D01*
X316458Y863400D01*
X316708Y863233D01*
X316917Y862983D01*
X317000Y862692D01*
X316917Y862358D01*
X316667Y862067D01*
X316292Y861900D01*
X315875Y861858D01*
X315333Y861942D01*
X315042Y862067D01*
X314750Y862275D01*
X314542Y862567D01*
X314500Y862858D01*
X314583Y863150D01*
X314792Y863358D01*
G01X321000Y852517D02*
X318500D01*
Y853558D01*
X318625Y853892D01*
X318792Y854100D01*
X319125Y854183D01*
X319458Y854100D01*
X319667Y853850D01*
X319792Y853558D01*
Y852517D01*
G01Y853558D02*
X321000Y854183D01*
G01X318917Y855658D02*
X318667Y855908D01*
X318542Y856200D01*
X318500Y856533D01*
X318583Y856950D01*
X318792Y857242D01*
X319042Y857325D01*
X319292Y857283D01*
X319500Y857117D01*
X319917Y856283D01*
X320208Y855908D01*
X320625Y855658D01*
X321000Y855575D01*
Y857325D01*
G01X320500Y858633D02*
X320792Y858883D01*
X320958Y859217D01*
X321000Y859592D01*
X320958Y859925D01*
X320750Y860258D01*
X320500Y860467D01*
X320250Y860508D01*
X319958Y860425D01*
X319750Y860133D01*
X319667Y859842D01*
Y859467D01*
G01Y859842D02*
X319542Y860092D01*
X319333Y860300D01*
X319083Y860383D01*
X318833Y860300D01*
X318625Y860092D01*
X318500Y859717D01*
X318542Y859342D01*
X318708Y858967D01*
G01X321000Y862567D02*
X320458Y862650D01*
X320000Y862775D01*
X319583Y862942D01*
X319125Y863150D01*
X318500Y863483D01*
Y861817D01*
G01X303850Y834000D02*
X303517Y834042D01*
X303225Y834208D01*
X302975Y834458D01*
X302808Y834750D01*
X302725Y835083D01*
Y835417D01*
X302808Y835750D01*
X302975Y836042D01*
X303225Y836292D01*
X303517Y836458D01*
X303850Y836500D01*
X304183Y836458D01*
X304475Y836292D01*
X304725Y836042D01*
X304892Y835750D01*
X304975Y835417D01*
Y835083D01*
X304892Y834750D01*
X304725Y834458D01*
X304475Y834208D01*
X304183Y834042D01*
X303850Y834000D01*
G01X304183Y834667D02*
X304683Y834000D01*
G01X306158Y836083D02*
X306408Y836333D01*
X306700Y836458D01*
X307033Y836500D01*
X307450Y836417D01*
X307742Y836208D01*
X307825Y835958D01*
X307783Y835708D01*
X307617Y835500D01*
X306783Y835083D01*
X306408Y834792D01*
X306158Y834375D01*
X306075Y834000D01*
X307825D01*
G01X309258Y836083D02*
X309508Y836333D01*
X309800Y836458D01*
X310133Y836500D01*
X310550Y836417D01*
X310842Y836208D01*
X310925Y835958D01*
X310883Y835708D01*
X310717Y835500D01*
X309883Y835083D01*
X309508Y834792D01*
X309258Y834375D01*
X309175Y834000D01*
X310925D01*
G01X313150D02*
Y836500D01*
X312650Y836000D01*
G01Y834000D02*
X313650D01*
G01X311900Y838500D02*
Y852500D01*
G01X298900Y838500D02*
X311900D01*
G01X298900Y852500D02*
Y838500D01*
G01X311900Y852500D02*
X298900D01*
G01X297792Y839407D02*
Y852407D01*
G01X342549Y1012831D02*
X347599D01*
Y1111531D01*
X372249D01*
Y927131D01*
X347599D01*
Y985831D01*
X342549D01*
Y1012831D01*
G01X301517Y860000D02*
Y862500D01*
X302558D01*
X302892Y862375D01*
X303100Y862208D01*
X303183Y861875D01*
X303100Y861542D01*
X302850Y861333D01*
X302558Y861208D01*
X301517D01*
G01X302558D02*
X303183Y860000D01*
G01X305450D02*
Y862500D01*
X304950Y862000D01*
G01Y860000D02*
X305950D01*
G01X308467D02*
X308550Y860542D01*
X308675Y861000D01*
X308842Y861417D01*
X309050Y861875D01*
X309383Y862500D01*
X307717D01*
G01X311650Y860000D02*
Y862500D01*
X311150Y862000D01*
G01Y860000D02*
X312150D01*
G01X387551Y963184D02*
X387301Y963309D01*
X387009Y963392D01*
X386676D01*
X386301Y963267D01*
X386009Y963059D01*
X385801Y962809D01*
X385634Y962392D01*
X385592Y962017D01*
X385676Y961642D01*
X385801Y961392D01*
X386051Y961142D01*
X386342Y960975D01*
X386634Y960892D01*
X386926D01*
X387217Y960975D01*
X387467Y961100D01*
X387676Y961267D01*
G01X388817D02*
X389067Y961059D01*
X389359Y960934D01*
X389734Y960892D01*
X390109Y960975D01*
X390401Y961142D01*
X390609Y961434D01*
X390651Y961767D01*
X390567Y962100D01*
X390359Y962309D01*
X390067Y962475D01*
X389776Y962517D01*
X389484Y962475D01*
X389109Y962309D01*
X389234Y963392D01*
X390359D01*
G01X391917Y961267D02*
X392167Y961059D01*
X392459Y960934D01*
X392834Y960892D01*
X393209Y960975D01*
X393501Y961142D01*
X393709Y961434D01*
X393751Y961767D01*
X393667Y962100D01*
X393459Y962309D01*
X393167Y962475D01*
X392876Y962517D01*
X392584Y962475D01*
X392209Y962309D01*
X392334Y963392D01*
X393459D01*
G01X387817Y967292D02*
X387567Y967417D01*
X387275Y967500D01*
X386942D01*
X386567Y967375D01*
X386275Y967167D01*
X386067Y966917D01*
X385900Y966500D01*
X385858Y966125D01*
X385942Y965750D01*
X386067Y965500D01*
X386317Y965250D01*
X386608Y965083D01*
X386900Y965000D01*
X387192D01*
X387483Y965083D01*
X387733Y965208D01*
X387942Y965375D01*
G01X389083D02*
X389333Y965167D01*
X389625Y965042D01*
X390000Y965000D01*
X390375Y965083D01*
X390667Y965250D01*
X390875Y965542D01*
X390917Y965875D01*
X390833Y966208D01*
X390625Y966417D01*
X390333Y966583D01*
X390042Y966625D01*
X389750Y966583D01*
X389375Y966417D01*
X389500Y967500D01*
X390625D01*
G01X393600Y965000D02*
Y967500D01*
X392058Y965708D01*
X394142D01*
G01X293317Y1008292D02*
X293067Y1008417D01*
X292775Y1008500D01*
X292442D01*
X292067Y1008375D01*
X291775Y1008167D01*
X291567Y1007917D01*
X291400Y1007500D01*
X291358Y1007125D01*
X291442Y1006750D01*
X291567Y1006500D01*
X291817Y1006250D01*
X292108Y1006083D01*
X292400Y1006000D01*
X292692D01*
X292983Y1006083D01*
X293233Y1006208D01*
X293442Y1006375D01*
G01X294708Y1007042D02*
X295000Y1007333D01*
X295250Y1007500D01*
X295583Y1007583D01*
X295875Y1007500D01*
X296083Y1007333D01*
X296250Y1007083D01*
X296292Y1006792D01*
X296250Y1006542D01*
X296083Y1006292D01*
X295833Y1006083D01*
X295542Y1006000D01*
X295208Y1006083D01*
X294917Y1006333D01*
X294750Y1006708D01*
X294708Y1007125D01*
X294792Y1007667D01*
X294917Y1007958D01*
X295125Y1008250D01*
X295417Y1008458D01*
X295708Y1008500D01*
X296000Y1008417D01*
X296208Y1008208D01*
G01X297683Y1006375D02*
X297933Y1006167D01*
X298225Y1006042D01*
X298600Y1006000D01*
X298975Y1006083D01*
X299267Y1006250D01*
X299475Y1006542D01*
X299517Y1006875D01*
X299433Y1007208D01*
X299225Y1007417D01*
X298933Y1007583D01*
X298642Y1007625D01*
X298350Y1007583D01*
X297975Y1007417D01*
X298100Y1008500D01*
X299225D01*
G01X300317Y998792D02*
X300067Y998917D01*
X299775Y999000D01*
X299442D01*
X299067Y998875D01*
X298775Y998667D01*
X298567Y998417D01*
X298400Y998000D01*
X298358Y997625D01*
X298442Y997250D01*
X298567Y997000D01*
X298817Y996750D01*
X299108Y996583D01*
X299400Y996500D01*
X299692D01*
X299983Y996583D01*
X300233Y996708D01*
X300442Y996875D01*
G01X301708Y997542D02*
X302000Y997833D01*
X302250Y998000D01*
X302583Y998083D01*
X302875Y998000D01*
X303083Y997833D01*
X303250Y997583D01*
X303292Y997292D01*
X303250Y997042D01*
X303083Y996792D01*
X302833Y996583D01*
X302542Y996500D01*
X302208Y996583D01*
X301917Y996833D01*
X301750Y997208D01*
X301708Y997625D01*
X301792Y998167D01*
X301917Y998458D01*
X302125Y998750D01*
X302417Y998958D01*
X302708Y999000D01*
X303000Y998917D01*
X303208Y998708D01*
G01X306100Y996500D02*
Y999000D01*
X304558Y997208D01*
X306642D01*
G01X299017Y965500D02*
Y968000D01*
X300058D01*
X300392Y967875D01*
X300600Y967708D01*
X300683Y967375D01*
X300600Y967042D01*
X300350Y966833D01*
X300058Y966708D01*
X299017D01*
G01X300058D02*
X300683Y965500D01*
G01X302158Y967583D02*
X302408Y967833D01*
X302700Y967958D01*
X303033Y968000D01*
X303450Y967917D01*
X303742Y967708D01*
X303825Y967458D01*
X303783Y967208D01*
X303617Y967000D01*
X302783Y966583D01*
X302408Y966292D01*
X302158Y965875D01*
X302075Y965500D01*
X303825D01*
G01X306050Y968000D02*
X305717Y967917D01*
X305467Y967708D01*
X305300Y967458D01*
X305175Y967125D01*
X305133Y966750D01*
X305175Y966375D01*
X305300Y966042D01*
X305467Y965792D01*
X305717Y965583D01*
X306050Y965500D01*
X306383Y965583D01*
X306633Y965792D01*
X306800Y966042D01*
X306925Y966375D01*
X306967Y966750D01*
X306925Y967125D01*
X306800Y967458D01*
X306633Y967708D01*
X306383Y967917D01*
X306050Y968000D01*
G01X309150D02*
X308817Y967917D01*
X308567Y967708D01*
X308400Y967458D01*
X308275Y967125D01*
X308233Y966750D01*
X308275Y966375D01*
X308400Y966042D01*
X308567Y965792D01*
X308817Y965583D01*
X309150Y965500D01*
X309483Y965583D01*
X309733Y965792D01*
X309900Y966042D01*
X310025Y966375D01*
X310067Y966750D01*
X310025Y967125D01*
X309900Y967458D01*
X309733Y967708D01*
X309483Y967917D01*
X309150Y968000D01*
G01X303300Y973000D02*
Y969000D01*
X310700D01*
G01X291517Y1001661D02*
Y1004161D01*
X292558D01*
X292892Y1004036D01*
X293100Y1003869D01*
X293183Y1003536D01*
X293100Y1003203D01*
X292850Y1002994D01*
X292558Y1002869D01*
X291517D01*
G01X292558D02*
X293183Y1001661D01*
G01X294658Y1003744D02*
X294908Y1003994D01*
X295200Y1004119D01*
X295533Y1004161D01*
X295950Y1004078D01*
X296242Y1003869D01*
X296325Y1003619D01*
X296283Y1003369D01*
X296117Y1003161D01*
X295283Y1002744D01*
X294908Y1002453D01*
X294658Y1002036D01*
X294575Y1001661D01*
X296325D01*
G01X298550Y1004161D02*
X298217Y1004078D01*
X297967Y1003869D01*
X297800Y1003619D01*
X297675Y1003286D01*
X297633Y1002911D01*
X297675Y1002536D01*
X297800Y1002203D01*
X297967Y1001953D01*
X298217Y1001744D01*
X298550Y1001661D01*
X298883Y1001744D01*
X299133Y1001953D01*
X299300Y1002203D01*
X299425Y1002536D01*
X299467Y1002911D01*
X299425Y1003286D01*
X299300Y1003619D01*
X299133Y1003869D01*
X298883Y1004078D01*
X298550Y1004161D01*
G01X301650Y1001661D02*
Y1004161D01*
X301150Y1003661D01*
G01Y1001661D02*
X302150D01*
G01X310700Y1000000D02*
Y1004000D01*
X303300D01*
G01X299000Y975017D02*
X296500D01*
Y976058D01*
X296625Y976392D01*
X296792Y976600D01*
X297125Y976683D01*
X297458Y976600D01*
X297667Y976350D01*
X297792Y976058D01*
Y975017D01*
G01Y976058D02*
X299000Y976683D01*
G01X296917Y978158D02*
X296667Y978408D01*
X296542Y978700D01*
X296500Y979033D01*
X296583Y979450D01*
X296792Y979742D01*
X297042Y979825D01*
X297292Y979783D01*
X297500Y979617D01*
X297917Y978783D01*
X298208Y978408D01*
X298625Y978158D01*
X299000Y978075D01*
Y979825D01*
G01X296500Y982050D02*
X296583Y981717D01*
X296792Y981467D01*
X297042Y981300D01*
X297375Y981175D01*
X297750Y981133D01*
X298125Y981175D01*
X298458Y981300D01*
X298708Y981467D01*
X298917Y981717D01*
X299000Y982050D01*
X298917Y982383D01*
X298708Y982633D01*
X298458Y982800D01*
X298125Y982925D01*
X297750Y982967D01*
X297375Y982925D01*
X297042Y982800D01*
X296792Y982633D01*
X296583Y982383D01*
X296500Y982050D01*
G01X296917Y984358D02*
X296667Y984608D01*
X296542Y984900D01*
X296500Y985233D01*
X296583Y985650D01*
X296792Y985942D01*
X297042Y986025D01*
X297292Y985983D01*
X297500Y985817D01*
X297917Y984983D01*
X298208Y984608D01*
X298625Y984358D01*
X299000Y984275D01*
Y986025D01*
G01X306500Y973300D02*
X310500D01*
Y980700D01*
G01X322500Y955017D02*
X320000D01*
Y956058D01*
X320125Y956392D01*
X320292Y956600D01*
X320625Y956683D01*
X320958Y956600D01*
X321167Y956350D01*
X321292Y956058D01*
Y955017D01*
G01Y956058D02*
X322500Y956683D01*
G01X320417Y958158D02*
X320167Y958408D01*
X320042Y958700D01*
X320000Y959033D01*
X320083Y959450D01*
X320292Y959742D01*
X320542Y959825D01*
X320792Y959783D01*
X321000Y959617D01*
X321417Y958783D01*
X321708Y958408D01*
X322125Y958158D01*
X322500Y958075D01*
Y959825D01*
G01X320000Y962050D02*
X320083Y961717D01*
X320292Y961467D01*
X320542Y961300D01*
X320875Y961175D01*
X321250Y961133D01*
X321625Y961175D01*
X321958Y961300D01*
X322208Y961467D01*
X322417Y961717D01*
X322500Y962050D01*
X322417Y962383D01*
X322208Y962633D01*
X321958Y962800D01*
X321625Y962925D01*
X321250Y962967D01*
X320875Y962925D01*
X320542Y962800D01*
X320292Y962633D01*
X320083Y962383D01*
X320000Y962050D01*
G01X322000Y964233D02*
X322292Y964483D01*
X322458Y964817D01*
X322500Y965192D01*
X322458Y965525D01*
X322250Y965858D01*
X322000Y966067D01*
X321750Y966108D01*
X321458Y966025D01*
X321250Y965733D01*
X321167Y965442D01*
Y965067D01*
G01Y965442D02*
X321042Y965692D01*
X320833Y965900D01*
X320583Y965983D01*
X320333Y965900D01*
X320125Y965692D01*
X320000Y965317D01*
X320042Y964942D01*
X320208Y964567D01*
G01X323000Y974700D02*
X319000D01*
Y967300D01*
G01X334017Y954000D02*
Y956500D01*
X335058D01*
X335392Y956375D01*
X335600Y956208D01*
X335683Y955875D01*
X335600Y955542D01*
X335350Y955333D01*
X335058Y955208D01*
X334017D01*
G01X335058D02*
X335683Y954000D01*
G01X337950D02*
Y956500D01*
X337450Y956000D01*
G01Y954000D02*
X338450D01*
G01X340342Y954292D02*
X340633Y954083D01*
X340967Y954000D01*
X341300Y954083D01*
X341592Y954333D01*
X341800Y954708D01*
X341883Y955083D01*
Y955542D01*
X341800Y955917D01*
X341592Y956250D01*
X341342Y956417D01*
X341050Y956500D01*
X340717Y956417D01*
X340467Y956250D01*
X340300Y956000D01*
X340217Y955667D01*
X340300Y955375D01*
X340508Y955083D01*
X340758Y954917D01*
X341050Y954875D01*
X341383Y954958D01*
X341633Y955167D01*
X341883Y955542D01*
G01X344150Y954000D02*
X344442Y954042D01*
X344775Y954167D01*
X344983Y954375D01*
X345067Y954667D01*
X344983Y954958D01*
X344733Y955208D01*
X344358Y955333D01*
X343942D01*
X343692Y955417D01*
X343483Y955625D01*
X343400Y955917D01*
X343525Y956208D01*
X343817Y956417D01*
X344150Y956500D01*
X344483Y956417D01*
X344775Y956208D01*
X344900Y955917D01*
X344817Y955625D01*
X344608Y955417D01*
X344358Y955333D01*
X343942D01*
X343567Y955208D01*
X343317Y954958D01*
X343233Y954667D01*
X343317Y954375D01*
X343525Y954167D01*
X343858Y954042D01*
X344150Y954000D01*
G01X340200Y967400D02*
Y971400D01*
X332800D01*
G01X334017Y958000D02*
Y960500D01*
X335058D01*
X335392Y960375D01*
X335600Y960208D01*
X335683Y959875D01*
X335600Y959542D01*
X335350Y959333D01*
X335058Y959208D01*
X334017D01*
G01X335058D02*
X335683Y958000D01*
G01X337950D02*
Y960500D01*
X337450Y960000D01*
G01Y958000D02*
X338450D01*
G01X340342Y958292D02*
X340633Y958083D01*
X340967Y958000D01*
X341300Y958083D01*
X341592Y958333D01*
X341800Y958708D01*
X341883Y959083D01*
Y959542D01*
X341800Y959917D01*
X341592Y960250D01*
X341342Y960417D01*
X341050Y960500D01*
X340717Y960417D01*
X340467Y960250D01*
X340300Y960000D01*
X340217Y959667D01*
X340300Y959375D01*
X340508Y959083D01*
X340758Y958917D01*
X341050Y958875D01*
X341383Y958958D01*
X341633Y959167D01*
X341883Y959542D01*
G01X343358Y959042D02*
X343650Y959333D01*
X343900Y959500D01*
X344233Y959583D01*
X344525Y959500D01*
X344733Y959333D01*
X344900Y959083D01*
X344942Y958792D01*
X344900Y958542D01*
X344733Y958292D01*
X344483Y958083D01*
X344192Y958000D01*
X343858Y958083D01*
X343567Y958333D01*
X343400Y958708D01*
X343358Y959125D01*
X343442Y959667D01*
X343567Y959958D01*
X343775Y960250D01*
X344067Y960458D01*
X344358Y960500D01*
X344650Y960417D01*
X344858Y960208D01*
G01X342600Y976200D02*
Y980200D01*
X335200D01*
G01X334017Y962000D02*
Y964500D01*
X335058D01*
X335392Y964375D01*
X335600Y964208D01*
X335683Y963875D01*
X335600Y963542D01*
X335350Y963333D01*
X335058Y963208D01*
X334017D01*
G01X335058D02*
X335683Y962000D01*
G01X337950D02*
Y964500D01*
X337450Y964000D01*
G01Y962000D02*
X338450D01*
G01X340342Y962292D02*
X340633Y962083D01*
X340967Y962000D01*
X341300Y962083D01*
X341592Y962333D01*
X341800Y962708D01*
X341883Y963083D01*
Y963542D01*
X341800Y963917D01*
X341592Y964250D01*
X341342Y964417D01*
X341050Y964500D01*
X340717Y964417D01*
X340467Y964250D01*
X340300Y964000D01*
X340217Y963667D01*
X340300Y963375D01*
X340508Y963083D01*
X340758Y962917D01*
X341050Y962875D01*
X341383Y962958D01*
X341633Y963167D01*
X341883Y963542D01*
G01X343442Y962292D02*
X343733Y962083D01*
X344067Y962000D01*
X344400Y962083D01*
X344692Y962333D01*
X344900Y962708D01*
X344983Y963083D01*
Y963542D01*
X344900Y963917D01*
X344692Y964250D01*
X344442Y964417D01*
X344150Y964500D01*
X343817Y964417D01*
X343567Y964250D01*
X343400Y964000D01*
X343317Y963667D01*
X343400Y963375D01*
X343608Y963083D01*
X343858Y962917D01*
X344150Y962875D01*
X344483Y962958D01*
X344733Y963167D01*
X344983Y963542D01*
G01X335300Y984500D02*
Y980500D01*
X342700D01*
G01X298517Y992161D02*
Y994661D01*
X299558D01*
X299892Y994536D01*
X300100Y994369D01*
X300183Y994036D01*
X300100Y993703D01*
X299850Y993494D01*
X299558Y993369D01*
X298517D01*
G01X299558D02*
X300183Y992161D01*
G01X302450D02*
Y994661D01*
X301950Y994161D01*
G01Y992161D02*
X302950D01*
G01X304842Y992453D02*
X305133Y992244D01*
X305467Y992161D01*
X305800Y992244D01*
X306092Y992494D01*
X306300Y992869D01*
X306383Y993244D01*
Y993703D01*
X306300Y994078D01*
X306092Y994411D01*
X305842Y994578D01*
X305550Y994661D01*
X305217Y994578D01*
X304967Y994411D01*
X304800Y994161D01*
X304717Y993828D01*
X304800Y993536D01*
X305008Y993244D01*
X305258Y993078D01*
X305550Y993036D01*
X305883Y993119D01*
X306133Y993328D01*
X306383Y993703D01*
G01X307733Y992536D02*
X307983Y992328D01*
X308275Y992203D01*
X308650Y992161D01*
X309025Y992244D01*
X309317Y992411D01*
X309525Y992703D01*
X309567Y993036D01*
X309483Y993369D01*
X309275Y993578D01*
X308983Y993744D01*
X308692Y993786D01*
X308400Y993744D01*
X308025Y993578D01*
X308150Y994661D01*
X309275D01*
G01X310800Y998500D02*
Y994500D01*
X318200D01*
G01X391200Y1034000D02*
Y1038000D01*
X383800D01*
G01X327450Y1024000D02*
X327117Y1024042D01*
X326825Y1024208D01*
X326575Y1024458D01*
X326408Y1024750D01*
X326325Y1025083D01*
Y1025417D01*
X326408Y1025750D01*
X326575Y1026042D01*
X326825Y1026292D01*
X327117Y1026458D01*
X327450Y1026500D01*
X327783Y1026458D01*
X328075Y1026292D01*
X328325Y1026042D01*
X328492Y1025750D01*
X328575Y1025417D01*
Y1025083D01*
X328492Y1024750D01*
X328325Y1024458D01*
X328075Y1024208D01*
X327783Y1024042D01*
X327450Y1024000D01*
G01X327783Y1024667D02*
X328283Y1024000D01*
G01X329758Y1025042D02*
X330050Y1025333D01*
X330300Y1025500D01*
X330633Y1025583D01*
X330925Y1025500D01*
X331133Y1025333D01*
X331300Y1025083D01*
X331342Y1024792D01*
X331300Y1024542D01*
X331133Y1024292D01*
X330883Y1024083D01*
X330592Y1024000D01*
X330258Y1024083D01*
X329967Y1024333D01*
X329800Y1024708D01*
X329758Y1025125D01*
X329842Y1025667D01*
X329967Y1025958D01*
X330175Y1026250D01*
X330467Y1026458D01*
X330758Y1026500D01*
X331050Y1026417D01*
X331258Y1026208D01*
G01X340700Y1007000D02*
X338600Y1008800D01*
X340700Y1011000D01*
G01X340800Y1014600D02*
X321600D01*
Y1003400D01*
X340800D01*
Y1014600D01*
X340400D01*
G01X295000Y1026450D02*
X294958Y1026117D01*
X294792Y1025825D01*
X294542Y1025575D01*
X294250Y1025408D01*
X293917Y1025325D01*
X293583D01*
X293250Y1025408D01*
X292958Y1025575D01*
X292708Y1025825D01*
X292542Y1026117D01*
X292500Y1026450D01*
X292542Y1026783D01*
X292708Y1027075D01*
X292958Y1027325D01*
X293250Y1027492D01*
X293583Y1027575D01*
X293917D01*
X294250Y1027492D01*
X294542Y1027325D01*
X294792Y1027075D01*
X294958Y1026783D01*
X295000Y1026450D01*
G01X294333Y1026783D02*
X295000Y1027283D01*
G01Y1029550D02*
X294958Y1029842D01*
X294833Y1030175D01*
X294625Y1030383D01*
X294333Y1030467D01*
X294042Y1030383D01*
X293792Y1030133D01*
X293667Y1029758D01*
Y1029342D01*
X293583Y1029092D01*
X293375Y1028883D01*
X293083Y1028800D01*
X292792Y1028925D01*
X292583Y1029217D01*
X292500Y1029550D01*
X292583Y1029883D01*
X292792Y1030175D01*
X293083Y1030300D01*
X293375Y1030217D01*
X293583Y1030008D01*
X293667Y1029758D01*
Y1029342D01*
X293792Y1028967D01*
X294042Y1028717D01*
X294333Y1028633D01*
X294625Y1028717D01*
X294833Y1028925D01*
X294958Y1029258D01*
X295000Y1029550D01*
G01X296300Y1029000D02*
X298400Y1027200D01*
X296300Y1025000D01*
G01X296200Y1021400D02*
X315400D01*
Y1032600D01*
X296200D01*
Y1021400D01*
X296600D01*
G01X336300Y1027500D02*
X330800D01*
G01X336300Y1035500D02*
Y1027500D01*
G01X330800Y1035500D02*
X336300D01*
G01X318700D02*
X324200D01*
G01X318700Y1027500D02*
Y1035500D01*
G01X324200Y1027500D02*
X318700D01*
G01X315500Y961033D02*
X313000D01*
Y961867D01*
X313125Y962200D01*
X313292Y962450D01*
X313542Y962658D01*
X313833Y962825D01*
X314250Y962867D01*
X314667Y962825D01*
X314958Y962658D01*
X315208Y962450D01*
X315375Y962200D01*
X315500Y961867D01*
Y961033D01*
G01X313417Y964258D02*
X313167Y964508D01*
X313042Y964800D01*
X313000Y965133D01*
X313083Y965550D01*
X313292Y965842D01*
X313542Y965925D01*
X313792Y965883D01*
X314000Y965717D01*
X314417Y964883D01*
X314708Y964508D01*
X315125Y964258D01*
X315500Y964175D01*
Y965925D01*
G01X318500Y983500D02*
Y967400D01*
G01X311500Y983500D02*
X318500D01*
G01X311500Y967400D02*
Y983500D01*
G01X318500Y967400D02*
X311500D01*
G01X322134Y982050D02*
X322092Y981717D01*
X321926Y981425D01*
X321676Y981175D01*
X321384Y981008D01*
X321051Y980925D01*
X320717D01*
X320384Y981008D01*
X320092Y981175D01*
X319842Y981425D01*
X319676Y981717D01*
X319634Y982050D01*
X319676Y982383D01*
X319842Y982675D01*
X320092Y982925D01*
X320384Y983092D01*
X320717Y983175D01*
X321051D01*
X321384Y983092D01*
X321676Y982925D01*
X321926Y982675D01*
X322092Y982383D01*
X322134Y982050D01*
G01X321467Y982383D02*
X322134Y982883D01*
G01Y985067D02*
X321592Y985150D01*
X321134Y985275D01*
X320717Y985442D01*
X320259Y985650D01*
X319634Y985983D01*
Y984317D01*
G01X334700Y989200D02*
X323300D01*
G01X334700Y975800D02*
Y989200D01*
G01X323300Y975800D02*
X334700D01*
G01X323300Y989200D02*
Y975800D01*
G01X342500Y1046517D02*
X340000D01*
Y1047558D01*
X340125Y1047892D01*
X340292Y1048100D01*
X340625Y1048183D01*
X340958Y1048100D01*
X341167Y1047850D01*
X341292Y1047558D01*
Y1046517D01*
G01Y1047558D02*
X342500Y1048183D01*
G01Y1050450D02*
X340000D01*
X340500Y1049950D01*
G01X342500D02*
Y1050950D01*
G01X342208Y1052842D02*
X342417Y1053133D01*
X342500Y1053467D01*
X342417Y1053800D01*
X342167Y1054092D01*
X341792Y1054300D01*
X341417Y1054383D01*
X340958D01*
X340583Y1054300D01*
X340250Y1054092D01*
X340083Y1053842D01*
X340000Y1053550D01*
X340083Y1053217D01*
X340250Y1052967D01*
X340500Y1052800D01*
X340833Y1052717D01*
X341125Y1052800D01*
X341417Y1053008D01*
X341583Y1053258D01*
X341625Y1053550D01*
X341542Y1053883D01*
X341333Y1054133D01*
X340958Y1054383D01*
G01X340000Y1056650D02*
X340083Y1056317D01*
X340292Y1056067D01*
X340542Y1055900D01*
X340875Y1055775D01*
X341250Y1055733D01*
X341625Y1055775D01*
X341958Y1055900D01*
X342208Y1056067D01*
X342417Y1056317D01*
X342500Y1056650D01*
X342417Y1056983D01*
X342208Y1057233D01*
X341958Y1057400D01*
X341625Y1057525D01*
X341250Y1057567D01*
X340875Y1057525D01*
X340542Y1057400D01*
X340292Y1057233D01*
X340083Y1056983D01*
X340000Y1056650D01*
G01X338000Y1045300D02*
X346000D01*
Y1027700D01*
X338000D01*
Y1045300D01*
G01X314200Y1042000D02*
Y1050000D01*
X331800D01*
Y1042000D01*
X314200D01*
G01X346825Y1113500D02*
Y1116000D01*
G01X348575D02*
Y1113500D01*
G01Y1114750D02*
X346825D01*
G01X349883Y1113500D02*
Y1116000D01*
X350717D01*
X351050Y1115875D01*
X351300Y1115708D01*
X351508Y1115458D01*
X351675Y1115167D01*
X351717Y1114750D01*
X351675Y1114333D01*
X351508Y1114042D01*
X351300Y1113792D01*
X351050Y1113625D01*
X350717Y1113500D01*
X349883D01*
G01X352983D02*
Y1116000D01*
X353817D01*
X354150Y1115875D01*
X354400Y1115708D01*
X354608Y1115458D01*
X354775Y1115167D01*
X354817Y1114750D01*
X354775Y1114333D01*
X354608Y1114042D01*
X354400Y1113792D01*
X354150Y1113625D01*
X353817Y1113500D01*
X352983D01*
G01X356125Y1113833D02*
X356458Y1113625D01*
X356833Y1113500D01*
X357167D01*
X357500Y1113625D01*
X357750Y1113833D01*
X357875Y1114125D01*
X357792Y1114417D01*
X357583Y1114667D01*
X357208Y1114833D01*
X356708Y1114917D01*
X356417Y1115083D01*
X356292Y1115375D01*
X356375Y1115667D01*
X356583Y1115875D01*
X356875Y1116000D01*
X357167D01*
X357458Y1115917D01*
X357708Y1115708D01*
G01X359058Y1113500D02*
X360100Y1116000D01*
X361142Y1113500D01*
G01X360767Y1114375D02*
X359433D01*
G01X362325Y1113833D02*
X362658Y1113625D01*
X363033Y1113500D01*
X363367D01*
X363700Y1113625D01*
X363950Y1113833D01*
X364075Y1114125D01*
X363992Y1114417D01*
X363783Y1114667D01*
X363408Y1114833D01*
X362908Y1114917D01*
X362617Y1115083D01*
X362492Y1115375D01*
X362575Y1115667D01*
X362783Y1115875D01*
X363075Y1116000D01*
X363367D01*
X363658Y1115917D01*
X363908Y1115708D01*
G01X365508Y1115583D02*
X365758Y1115833D01*
X366050Y1115958D01*
X366383Y1116000D01*
X366800Y1115917D01*
X367092Y1115708D01*
X367175Y1115458D01*
X367133Y1115208D01*
X366967Y1115000D01*
X366133Y1114583D01*
X365758Y1114292D01*
X365508Y1113875D01*
X365425Y1113500D01*
X367175D01*
G01X322217Y1058453D02*
X321967Y1058578D01*
X321675Y1058661D01*
X321342D01*
X320967Y1058536D01*
X320675Y1058328D01*
X320467Y1058078D01*
X320300Y1057661D01*
X320258Y1057286D01*
X320342Y1056911D01*
X320467Y1056661D01*
X320717Y1056411D01*
X321008Y1056244D01*
X321300Y1056161D01*
X321592D01*
X321883Y1056244D01*
X322133Y1056369D01*
X322342Y1056536D01*
G01X323483D02*
X323733Y1056328D01*
X324025Y1056203D01*
X324400Y1056161D01*
X324775Y1056244D01*
X325067Y1056411D01*
X325275Y1056703D01*
X325317Y1057036D01*
X325233Y1057369D01*
X325025Y1057578D01*
X324733Y1057744D01*
X324442Y1057786D01*
X324150Y1057744D01*
X323775Y1057578D01*
X323900Y1058661D01*
X325025D01*
G01X326708Y1057203D02*
X327000Y1057494D01*
X327250Y1057661D01*
X327583Y1057744D01*
X327875Y1057661D01*
X328083Y1057494D01*
X328250Y1057244D01*
X328292Y1056953D01*
X328250Y1056703D01*
X328083Y1056453D01*
X327833Y1056244D01*
X327542Y1056161D01*
X327208Y1056244D01*
X326917Y1056494D01*
X326750Y1056869D01*
X326708Y1057286D01*
X326792Y1057828D01*
X326917Y1058119D01*
X327125Y1058411D01*
X327417Y1058619D01*
X327708Y1058661D01*
X328000Y1058578D01*
X328208Y1058369D01*
G01X337708Y1082817D02*
X337583Y1082567D01*
X337500Y1082275D01*
Y1081942D01*
X337625Y1081567D01*
X337833Y1081275D01*
X338083Y1081067D01*
X338500Y1080900D01*
X338875Y1080858D01*
X339250Y1080942D01*
X339500Y1081067D01*
X339750Y1081317D01*
X339917Y1081608D01*
X340000Y1081900D01*
Y1082192D01*
X339917Y1082483D01*
X339792Y1082733D01*
X339625Y1082942D01*
G01X338958Y1084208D02*
X338667Y1084500D01*
X338500Y1084750D01*
X338417Y1085083D01*
X338500Y1085375D01*
X338667Y1085583D01*
X338917Y1085750D01*
X339208Y1085792D01*
X339458Y1085750D01*
X339708Y1085583D01*
X339917Y1085333D01*
X340000Y1085042D01*
X339917Y1084708D01*
X339667Y1084417D01*
X339292Y1084250D01*
X338875Y1084208D01*
X338333Y1084292D01*
X338042Y1084417D01*
X337750Y1084625D01*
X337542Y1084917D01*
X337500Y1085208D01*
X337583Y1085500D01*
X337792Y1085708D01*
G01X337917Y1087308D02*
X337667Y1087558D01*
X337542Y1087850D01*
X337500Y1088183D01*
X337583Y1088600D01*
X337792Y1088892D01*
X338042Y1088975D01*
X338292Y1088933D01*
X338500Y1088767D01*
X338917Y1087933D01*
X339208Y1087558D01*
X339625Y1087308D01*
X340000Y1087225D01*
Y1088975D01*
G01X380350Y1068000D02*
Y1065500D01*
G01X379392Y1068000D02*
X381308D01*
G01X382617Y1065500D02*
Y1068000D01*
X383617D01*
X383950Y1067875D01*
X384200Y1067583D01*
X384283Y1067250D01*
X384200Y1066917D01*
X383992Y1066667D01*
X383617Y1066542D01*
X382617D01*
G01X385633Y1066000D02*
X385883Y1065708D01*
X386217Y1065542D01*
X386592Y1065500D01*
X386925Y1065542D01*
X387258Y1065750D01*
X387467Y1066000D01*
X387508Y1066250D01*
X387425Y1066542D01*
X387133Y1066750D01*
X386842Y1066833D01*
X386467D01*
G01X386842D02*
X387092Y1066958D01*
X387300Y1067167D01*
X387383Y1067417D01*
X387300Y1067667D01*
X387092Y1067875D01*
X386717Y1068000D01*
X386342Y1067958D01*
X385967Y1067792D01*
G01X389650Y1065500D02*
Y1068000D01*
X389150Y1067500D01*
G01Y1065500D02*
X390150D01*
G01X384017Y1051500D02*
Y1054000D01*
X385058D01*
X385392Y1053875D01*
X385600Y1053708D01*
X385683Y1053375D01*
X385600Y1053042D01*
X385350Y1052833D01*
X385058Y1052708D01*
X384017D01*
G01X385058D02*
X385683Y1051500D01*
G01X387950D02*
Y1054000D01*
X387450Y1053500D01*
G01Y1051500D02*
X388450D01*
G01X390342Y1051792D02*
X390633Y1051583D01*
X390967Y1051500D01*
X391300Y1051583D01*
X391592Y1051833D01*
X391800Y1052208D01*
X391883Y1052583D01*
Y1053042D01*
X391800Y1053417D01*
X391592Y1053750D01*
X391342Y1053917D01*
X391050Y1054000D01*
X390717Y1053917D01*
X390467Y1053750D01*
X390300Y1053500D01*
X390217Y1053167D01*
X390300Y1052875D01*
X390508Y1052583D01*
X390758Y1052417D01*
X391050Y1052375D01*
X391383Y1052458D01*
X391633Y1052667D01*
X391883Y1053042D01*
G01X393233Y1052000D02*
X393483Y1051708D01*
X393817Y1051542D01*
X394192Y1051500D01*
X394525Y1051542D01*
X394858Y1051750D01*
X395067Y1052000D01*
X395108Y1052250D01*
X395025Y1052542D01*
X394733Y1052750D01*
X394442Y1052833D01*
X394067D01*
G01X394442D02*
X394692Y1052958D01*
X394900Y1053167D01*
X394983Y1053417D01*
X394900Y1053667D01*
X394692Y1053875D01*
X394317Y1054000D01*
X393942Y1053958D01*
X393567Y1053792D01*
G01X322317Y1054453D02*
X322067Y1054578D01*
X321775Y1054661D01*
X321442D01*
X321067Y1054536D01*
X320775Y1054328D01*
X320567Y1054078D01*
X320400Y1053661D01*
X320358Y1053286D01*
X320442Y1052911D01*
X320567Y1052661D01*
X320817Y1052411D01*
X321108Y1052244D01*
X321400Y1052161D01*
X321692D01*
X321983Y1052244D01*
X322233Y1052369D01*
X322442Y1052536D01*
G01X323583D02*
X323833Y1052328D01*
X324125Y1052203D01*
X324500Y1052161D01*
X324875Y1052244D01*
X325167Y1052411D01*
X325375Y1052703D01*
X325417Y1053036D01*
X325333Y1053369D01*
X325125Y1053578D01*
X324833Y1053744D01*
X324542Y1053786D01*
X324250Y1053744D01*
X323875Y1053578D01*
X324000Y1054661D01*
X325125D01*
G01X327517Y1052161D02*
X327600Y1052703D01*
X327725Y1053161D01*
X327892Y1053578D01*
X328100Y1054036D01*
X328433Y1054661D01*
X326767D01*
G01X320517Y1060000D02*
Y1062500D01*
X321558D01*
X321892Y1062375D01*
X322100Y1062208D01*
X322183Y1061875D01*
X322100Y1061542D01*
X321850Y1061333D01*
X321558Y1061208D01*
X320517D01*
G01X321558D02*
X322183Y1060000D01*
G01X324450D02*
Y1062500D01*
X323950Y1062000D01*
G01Y1060000D02*
X324950D01*
G01X326842Y1060292D02*
X327133Y1060083D01*
X327467Y1060000D01*
X327800Y1060083D01*
X328092Y1060333D01*
X328300Y1060708D01*
X328383Y1061083D01*
Y1061542D01*
X328300Y1061917D01*
X328092Y1062250D01*
X327842Y1062417D01*
X327550Y1062500D01*
X327217Y1062417D01*
X326967Y1062250D01*
X326800Y1062000D01*
X326717Y1061667D01*
X326800Y1061375D01*
X327008Y1061083D01*
X327258Y1060917D01*
X327550Y1060875D01*
X327883Y1060958D01*
X328133Y1061167D01*
X328383Y1061542D01*
G01X329858Y1062083D02*
X330108Y1062333D01*
X330400Y1062458D01*
X330733Y1062500D01*
X331150Y1062417D01*
X331442Y1062208D01*
X331525Y1061958D01*
X331483Y1061708D01*
X331317Y1061500D01*
X330483Y1061083D01*
X330108Y1060792D01*
X329858Y1060375D01*
X329775Y1060000D01*
X331525D01*
G01X304317Y1053792D02*
X304067Y1053917D01*
X303775Y1054000D01*
X303442D01*
X303067Y1053875D01*
X302775Y1053667D01*
X302567Y1053417D01*
X302400Y1053000D01*
X302358Y1052625D01*
X302442Y1052250D01*
X302567Y1052000D01*
X302817Y1051750D01*
X303108Y1051583D01*
X303400Y1051500D01*
X303692D01*
X303983Y1051583D01*
X304233Y1051708D01*
X304442Y1051875D01*
G01X305708Y1052542D02*
X306000Y1052833D01*
X306250Y1053000D01*
X306583Y1053083D01*
X306875Y1053000D01*
X307083Y1052833D01*
X307250Y1052583D01*
X307292Y1052292D01*
X307250Y1052042D01*
X307083Y1051792D01*
X306833Y1051583D01*
X306542Y1051500D01*
X306208Y1051583D01*
X305917Y1051833D01*
X305750Y1052208D01*
X305708Y1052625D01*
X305792Y1053167D01*
X305917Y1053458D01*
X306125Y1053750D01*
X306417Y1053958D01*
X306708Y1054000D01*
X307000Y1053917D01*
X307208Y1053708D01*
G01X309600Y1054000D02*
X309267Y1053917D01*
X309017Y1053708D01*
X308850Y1053458D01*
X308725Y1053125D01*
X308683Y1052750D01*
X308725Y1052375D01*
X308850Y1052042D01*
X309017Y1051792D01*
X309267Y1051583D01*
X309600Y1051500D01*
X309933Y1051583D01*
X310183Y1051792D01*
X310350Y1052042D01*
X310475Y1052375D01*
X310517Y1052750D01*
X310475Y1053125D01*
X310350Y1053458D01*
X310183Y1053708D01*
X309933Y1053917D01*
X309600Y1054000D01*
G01X335708Y1072317D02*
X335583Y1072067D01*
X335500Y1071775D01*
Y1071442D01*
X335625Y1071067D01*
X335833Y1070775D01*
X336083Y1070567D01*
X336500Y1070400D01*
X336875Y1070358D01*
X337250Y1070442D01*
X337500Y1070567D01*
X337750Y1070817D01*
X337917Y1071108D01*
X338000Y1071400D01*
Y1071692D01*
X337917Y1071983D01*
X337792Y1072233D01*
X337625Y1072442D01*
G01X336958Y1073708D02*
X336667Y1074000D01*
X336500Y1074250D01*
X336417Y1074583D01*
X336500Y1074875D01*
X336667Y1075083D01*
X336917Y1075250D01*
X337208Y1075292D01*
X337458Y1075250D01*
X337708Y1075083D01*
X337917Y1074833D01*
X338000Y1074542D01*
X337917Y1074208D01*
X337667Y1073917D01*
X337292Y1073750D01*
X336875Y1073708D01*
X336333Y1073792D01*
X336042Y1073917D01*
X335750Y1074125D01*
X335542Y1074417D01*
X335500Y1074708D01*
X335583Y1075000D01*
X335792Y1075208D01*
G01X338000Y1077600D02*
X335500D01*
X336000Y1077100D01*
G01X338000D02*
Y1078100D01*
G01X423513Y1410748D02*
Y1435948D01*
X385213D01*
Y1410748D01*
X423513D01*
G01X370502Y1355272D02*
Y1359272D01*
X372102D01*
X372635Y1359072D01*
X373035Y1358605D01*
X373168Y1358072D01*
X373035Y1357539D01*
X372702Y1357139D01*
X372102Y1356939D01*
X370502D01*
G01X375502Y1355272D02*
Y1357939D01*
G01Y1357405D02*
X375835Y1357672D01*
X376168Y1357872D01*
X376635Y1357939D01*
X376968Y1357872D01*
X377368Y1357672D01*
G01X380035Y1357072D02*
X382168D01*
X381968Y1357539D01*
X381635Y1357805D01*
X381168Y1357939D01*
X380702Y1357872D01*
X380302Y1357672D01*
X380035Y1357205D01*
X379902Y1356805D01*
Y1356405D01*
X380035Y1356005D01*
X380368Y1355605D01*
X380768Y1355339D01*
X381235Y1355272D01*
X381702Y1355405D01*
X382168Y1355805D01*
G01X384635Y1355739D02*
X384968Y1355472D01*
X385435Y1355272D01*
X385835D01*
X386235Y1355405D01*
X386502Y1355605D01*
X386635Y1355872D01*
X386568Y1356272D01*
X386302Y1356472D01*
X385102Y1356872D01*
X384835Y1357339D01*
X384968Y1357672D01*
X385235Y1357872D01*
X385635Y1357939D01*
X386035Y1357872D01*
X386435Y1357672D01*
G01X389235Y1355739D02*
X389568Y1355472D01*
X390035Y1355272D01*
X390435D01*
X390835Y1355405D01*
X391102Y1355605D01*
X391235Y1355872D01*
X391168Y1356272D01*
X390902Y1356472D01*
X389702Y1356872D01*
X389435Y1357339D01*
X389568Y1357672D01*
X389835Y1357872D01*
X390235Y1357939D01*
X390635Y1357872D01*
X391035Y1357672D01*
G01X398168Y1355272D02*
Y1359272D01*
X400702D01*
G01X399768Y1357339D02*
X398168D01*
G01X404035Y1357939D02*
Y1355272D01*
G01Y1359005D02*
X403902Y1359072D01*
Y1359205D01*
X404035Y1359272D01*
X404168Y1359205D01*
Y1359072D01*
X404035Y1359005D01*
G01X408635Y1359272D02*
Y1355272D01*
G01X407702Y1357939D02*
X409568D01*
G01X466761Y107319D02*
X471811D01*
Y206019D01*
X496461D01*
Y21619D01*
X471811D01*
Y80319D01*
X466761D01*
Y107319D01*
G01X439447Y20767D02*
X439322Y20517D01*
X439239Y20225D01*
Y19892D01*
X439364Y19517D01*
X439572Y19225D01*
X439822Y19017D01*
X440239Y18850D01*
X440614Y18808D01*
X440989Y18892D01*
X441239Y19017D01*
X441489Y19267D01*
X441656Y19558D01*
X441739Y19850D01*
Y20142D01*
X441656Y20433D01*
X441531Y20683D01*
X441364Y20892D01*
G01X441239Y22033D02*
X441531Y22283D01*
X441697Y22617D01*
X441739Y22992D01*
X441697Y23325D01*
X441489Y23658D01*
X441239Y23867D01*
X440989Y23908D01*
X440697Y23825D01*
X440489Y23533D01*
X440406Y23242D01*
Y22867D01*
G01Y23242D02*
X440281Y23492D01*
X440072Y23700D01*
X439822Y23783D01*
X439572Y23700D01*
X439364Y23492D01*
X439239Y23117D01*
X439281Y22742D01*
X439447Y22367D01*
G01X441447Y25342D02*
X441656Y25633D01*
X441739Y25967D01*
X441656Y26300D01*
X441406Y26592D01*
X441031Y26800D01*
X440656Y26883D01*
X440197D01*
X439822Y26800D01*
X439489Y26592D01*
X439322Y26342D01*
X439239Y26050D01*
X439322Y25717D01*
X439489Y25467D01*
X439739Y25300D01*
X440072Y25217D01*
X440364Y25300D01*
X440656Y25508D01*
X440822Y25758D01*
X440864Y26050D01*
X440781Y26383D01*
X440572Y26633D01*
X440197Y26883D01*
G01X439239Y29150D02*
X439322Y28817D01*
X439531Y28567D01*
X439781Y28400D01*
X440114Y28275D01*
X440489Y28233D01*
X440864Y28275D01*
X441197Y28400D01*
X441447Y28567D01*
X441656Y28817D01*
X441739Y29150D01*
X441656Y29483D01*
X441447Y29733D01*
X441197Y29900D01*
X440864Y30025D01*
X440489Y30067D01*
X440114Y30025D01*
X439781Y29900D01*
X439531Y29733D01*
X439322Y29483D01*
X439239Y29150D01*
G01X466346Y60215D02*
X463846D01*
Y61256D01*
X463971Y61590D01*
X464138Y61798D01*
X464471Y61881D01*
X464804Y61798D01*
X465013Y61548D01*
X465138Y61256D01*
Y60215D01*
G01Y61256D02*
X466346Y61881D01*
G01X465304Y63356D02*
X465013Y63648D01*
X464846Y63898D01*
X464763Y64231D01*
X464846Y64523D01*
X465013Y64731D01*
X465263Y64898D01*
X465554Y64940D01*
X465804Y64898D01*
X466054Y64731D01*
X466263Y64481D01*
X466346Y64190D01*
X466263Y63856D01*
X466013Y63565D01*
X465638Y63398D01*
X465221Y63356D01*
X464679Y63440D01*
X464388Y63565D01*
X464096Y63773D01*
X463888Y64065D01*
X463846Y64356D01*
X463929Y64648D01*
X464138Y64856D01*
G01X466054Y66540D02*
X466263Y66831D01*
X466346Y67165D01*
X466263Y67498D01*
X466013Y67790D01*
X465638Y67998D01*
X465263Y68081D01*
X464804D01*
X464429Y67998D01*
X464096Y67790D01*
X463929Y67540D01*
X463846Y67248D01*
X463929Y66915D01*
X464096Y66665D01*
X464346Y66498D01*
X464679Y66415D01*
X464971Y66498D01*
X465263Y66706D01*
X465429Y66956D01*
X465471Y67248D01*
X465388Y67581D01*
X465179Y67831D01*
X464804Y68081D01*
G01X466054Y69640D02*
X466263Y69931D01*
X466346Y70265D01*
X466263Y70598D01*
X466013Y70890D01*
X465638Y71098D01*
X465263Y71181D01*
X464804D01*
X464429Y71098D01*
X464096Y70890D01*
X463929Y70640D01*
X463846Y70348D01*
X463929Y70015D01*
X464096Y69765D01*
X464346Y69598D01*
X464679Y69515D01*
X464971Y69598D01*
X465263Y69806D01*
X465429Y70056D01*
X465471Y70348D01*
X465388Y70681D01*
X465179Y70931D01*
X464804Y71181D01*
G01X466000Y79200D02*
X462000D01*
Y71800D01*
G01X470000Y60517D02*
X467500D01*
Y61558D01*
X467625Y61892D01*
X467792Y62100D01*
X468125Y62183D01*
X468458Y62100D01*
X468667Y61850D01*
X468792Y61558D01*
Y60517D01*
G01Y61558D02*
X470000Y62183D01*
G01Y64367D02*
X469458Y64450D01*
X469000Y64575D01*
X468583Y64742D01*
X468125Y64950D01*
X467500Y65283D01*
Y63617D01*
G01Y67550D02*
X467583Y67217D01*
X467792Y66967D01*
X468042Y66800D01*
X468375Y66675D01*
X468750Y66633D01*
X469125Y66675D01*
X469458Y66800D01*
X469708Y66967D01*
X469917Y67217D01*
X470000Y67550D01*
X469917Y67883D01*
X469708Y68133D01*
X469458Y68300D01*
X469125Y68425D01*
X468750Y68467D01*
X468375Y68425D01*
X468042Y68300D01*
X467792Y68133D01*
X467583Y67883D01*
X467500Y67550D01*
G01X470000Y70650D02*
X467500D01*
X468000Y70150D01*
G01X470000D02*
Y71150D01*
G01X470500Y79200D02*
X466500D01*
Y71800D01*
G01X441017Y84000D02*
Y86500D01*
X442058D01*
X442392Y86375D01*
X442600Y86208D01*
X442683Y85875D01*
X442600Y85542D01*
X442350Y85333D01*
X442058Y85208D01*
X441017D01*
G01X442058D02*
X442683Y84000D01*
G01X444867D02*
X444950Y84542D01*
X445075Y85000D01*
X445242Y85417D01*
X445450Y85875D01*
X445783Y86500D01*
X444117D01*
G01X448050D02*
X447717Y86417D01*
X447467Y86208D01*
X447300Y85958D01*
X447175Y85625D01*
X447133Y85250D01*
X447175Y84875D01*
X447300Y84542D01*
X447467Y84292D01*
X447717Y84083D01*
X448050Y84000D01*
X448383Y84083D01*
X448633Y84292D01*
X448800Y84542D01*
X448925Y84875D01*
X448967Y85250D01*
X448925Y85625D01*
X448800Y85958D01*
X448633Y86208D01*
X448383Y86417D01*
X448050Y86500D01*
G01X450233Y84500D02*
X450483Y84208D01*
X450817Y84042D01*
X451192Y84000D01*
X451525Y84042D01*
X451858Y84250D01*
X452067Y84500D01*
X452108Y84750D01*
X452025Y85042D01*
X451733Y85250D01*
X451442Y85333D01*
X451067D01*
G01X451442D02*
X451692Y85458D01*
X451900Y85667D01*
X451983Y85917D01*
X451900Y86167D01*
X451692Y86375D01*
X451317Y86500D01*
X450942Y86458D01*
X450567Y86292D01*
G01X452000Y75200D02*
X456000D01*
Y82600D01*
G01X467000Y24517D02*
X464500D01*
Y25558D01*
X464625Y25892D01*
X464792Y26100D01*
X465125Y26183D01*
X465458Y26100D01*
X465667Y25850D01*
X465792Y25558D01*
Y24517D01*
G01Y25558D02*
X467000Y26183D01*
G01Y28367D02*
X466458Y28450D01*
X466000Y28575D01*
X465583Y28742D01*
X465125Y28950D01*
X464500Y29283D01*
Y27617D01*
G01Y31550D02*
X464583Y31217D01*
X464792Y30967D01*
X465042Y30800D01*
X465375Y30675D01*
X465750Y30633D01*
X466125Y30675D01*
X466458Y30800D01*
X466708Y30967D01*
X466917Y31217D01*
X467000Y31550D01*
X466917Y31883D01*
X466708Y32133D01*
X466458Y32300D01*
X466125Y32425D01*
X465750Y32467D01*
X465375Y32425D01*
X465042Y32300D01*
X464792Y32133D01*
X464583Y31883D01*
X464500Y31550D01*
G01X466625Y33733D02*
X466833Y33983D01*
X466958Y34275D01*
X467000Y34650D01*
X466917Y35025D01*
X466750Y35317D01*
X466458Y35525D01*
X466125Y35567D01*
X465792Y35483D01*
X465583Y35275D01*
X465417Y34983D01*
X465375Y34692D01*
X465417Y34400D01*
X465583Y34025D01*
X464500Y34150D01*
Y35275D01*
G01X463500Y39800D02*
X467500D01*
Y47200D01*
G01X445739Y19017D02*
X443239D01*
Y20058D01*
X443364Y20392D01*
X443531Y20600D01*
X443864Y20683D01*
X444197Y20600D01*
X444406Y20350D01*
X444531Y20058D01*
Y19017D01*
G01Y20058D02*
X445739Y20683D01*
G01Y22867D02*
X445197Y22950D01*
X444739Y23075D01*
X444322Y23242D01*
X443864Y23450D01*
X443239Y23783D01*
Y22117D01*
G01Y26050D02*
X443322Y25717D01*
X443531Y25467D01*
X443781Y25300D01*
X444114Y25175D01*
X444489Y25133D01*
X444864Y25175D01*
X445197Y25300D01*
X445447Y25467D01*
X445656Y25717D01*
X445739Y26050D01*
X445656Y26383D01*
X445447Y26633D01*
X445197Y26800D01*
X444864Y26925D01*
X444489Y26967D01*
X444114Y26925D01*
X443781Y26800D01*
X443531Y26633D01*
X443322Y26383D01*
X443239Y26050D01*
G01X444697Y28358D02*
X444406Y28650D01*
X444239Y28900D01*
X444156Y29233D01*
X444239Y29525D01*
X444406Y29733D01*
X444656Y29900D01*
X444947Y29942D01*
X445197Y29900D01*
X445447Y29733D01*
X445656Y29483D01*
X445739Y29192D01*
X445656Y28858D01*
X445406Y28567D01*
X445031Y28400D01*
X444614Y28358D01*
X444072Y28442D01*
X443781Y28567D01*
X443489Y28775D01*
X443281Y29067D01*
X443239Y29358D01*
X443322Y29650D01*
X443531Y29858D01*
G01X446400Y41200D02*
X442400D01*
Y33800D01*
G01X451017Y38500D02*
Y41000D01*
X452058D01*
X452392Y40875D01*
X452600Y40708D01*
X452683Y40375D01*
X452600Y40042D01*
X452350Y39833D01*
X452058Y39708D01*
X451017D01*
G01X452058D02*
X452683Y38500D01*
G01X454867D02*
X454950Y39042D01*
X455075Y39500D01*
X455242Y39917D01*
X455450Y40375D01*
X455783Y41000D01*
X454117D01*
G01X458050D02*
X457717Y40917D01*
X457467Y40708D01*
X457300Y40458D01*
X457175Y40125D01*
X457133Y39750D01*
X457175Y39375D01*
X457300Y39042D01*
X457467Y38792D01*
X457717Y38583D01*
X458050Y38500D01*
X458383Y38583D01*
X458633Y38792D01*
X458800Y39042D01*
X458925Y39375D01*
X458967Y39750D01*
X458925Y40125D01*
X458800Y40458D01*
X458633Y40708D01*
X458383Y40917D01*
X458050Y41000D01*
G01X461067Y38500D02*
X461150Y39042D01*
X461275Y39500D01*
X461442Y39917D01*
X461650Y40375D01*
X461983Y41000D01*
X460317D01*
G01X457400Y42500D02*
Y46500D01*
X450000D01*
G01X446017Y56000D02*
Y58500D01*
X447058D01*
X447392Y58375D01*
X447600Y58208D01*
X447683Y57875D01*
X447600Y57542D01*
X447350Y57333D01*
X447058Y57208D01*
X446017D01*
G01X447058D02*
X447683Y56000D01*
G01X449867D02*
X449950Y56542D01*
X450075Y57000D01*
X450242Y57417D01*
X450450Y57875D01*
X450783Y58500D01*
X449117D01*
G01X453050D02*
X452717Y58417D01*
X452467Y58208D01*
X452300Y57958D01*
X452175Y57625D01*
X452133Y57250D01*
X452175Y56875D01*
X452300Y56542D01*
X452467Y56292D01*
X452717Y56083D01*
X453050Y56000D01*
X453383Y56083D01*
X453633Y56292D01*
X453800Y56542D01*
X453925Y56875D01*
X453967Y57250D01*
X453925Y57625D01*
X453800Y57958D01*
X453633Y58208D01*
X453383Y58417D01*
X453050Y58500D01*
G01X456150Y56000D02*
X456442Y56042D01*
X456775Y56167D01*
X456983Y56375D01*
X457067Y56667D01*
X456983Y56958D01*
X456733Y57208D01*
X456358Y57333D01*
X455942D01*
X455692Y57417D01*
X455483Y57625D01*
X455400Y57917D01*
X455525Y58208D01*
X455817Y58417D01*
X456150Y58500D01*
X456483Y58417D01*
X456775Y58208D01*
X456900Y57917D01*
X456817Y57625D01*
X456608Y57417D01*
X456358Y57333D01*
X455942D01*
X455567Y57208D01*
X455317Y56958D01*
X455233Y56667D01*
X455317Y56375D01*
X455525Y56167D01*
X455858Y56042D01*
X456150Y56000D01*
G01X461800Y59500D02*
Y55500D01*
X469200D01*
G01X421000Y52950D02*
X420958Y52617D01*
X420792Y52325D01*
X420542Y52075D01*
X420250Y51908D01*
X419917Y51825D01*
X419583D01*
X419250Y51908D01*
X418958Y52075D01*
X418708Y52325D01*
X418542Y52617D01*
X418500Y52950D01*
X418542Y53283D01*
X418708Y53575D01*
X418958Y53825D01*
X419250Y53992D01*
X419583Y54075D01*
X419917D01*
X420250Y53992D01*
X420542Y53825D01*
X420792Y53575D01*
X420958Y53283D01*
X421000Y52950D01*
G01X420333Y53283D02*
X421000Y53783D01*
G01Y56050D02*
X418500D01*
X419000Y55550D01*
G01X421000D02*
Y56550D01*
G01X420500Y58233D02*
X420792Y58483D01*
X420958Y58817D01*
X421000Y59192D01*
X420958Y59525D01*
X420750Y59858D01*
X420500Y60067D01*
X420250Y60108D01*
X419958Y60025D01*
X419750Y59733D01*
X419667Y59442D01*
Y59067D01*
G01Y59442D02*
X419542Y59692D01*
X419333Y59900D01*
X419083Y59983D01*
X418833Y59900D01*
X418625Y59692D01*
X418500Y59317D01*
X418542Y58942D01*
X418708Y58567D01*
G01X421000Y62250D02*
X420958Y62542D01*
X420833Y62875D01*
X420625Y63083D01*
X420333Y63167D01*
X420042Y63083D01*
X419792Y62833D01*
X419667Y62458D01*
Y62042D01*
X419583Y61792D01*
X419375Y61583D01*
X419083Y61500D01*
X418792Y61625D01*
X418583Y61917D01*
X418500Y62250D01*
X418583Y62583D01*
X418792Y62875D01*
X419083Y63000D01*
X419375Y62917D01*
X419583Y62708D01*
X419667Y62458D01*
Y62042D01*
X419792Y61667D01*
X420042Y61417D01*
X420333Y61333D01*
X420625Y61417D01*
X420833Y61625D01*
X420958Y61958D01*
X421000Y62250D01*
G01X422300Y58600D02*
X424400Y56800D01*
X422300Y54600D01*
G01X422200Y51000D02*
X441400D01*
Y62200D01*
X422200D01*
Y51000D01*
X422600D01*
G01X448500Y46483D02*
X446000D01*
Y47317D01*
X446125Y47650D01*
X446292Y47900D01*
X446542Y48108D01*
X446833Y48275D01*
X447250Y48317D01*
X447667Y48275D01*
X447958Y48108D01*
X448208Y47900D01*
X448375Y47650D01*
X448500Y47317D01*
Y46483D01*
G01X446417Y49708D02*
X446167Y49958D01*
X446042Y50250D01*
X446000Y50583D01*
X446083Y51000D01*
X446292Y51292D01*
X446542Y51375D01*
X446792Y51333D01*
X447000Y51167D01*
X447417Y50333D01*
X447708Y49958D01*
X448125Y49708D01*
X448500Y49625D01*
Y51375D01*
G01Y53517D02*
X447958Y53600D01*
X447500Y53725D01*
X447083Y53892D01*
X446625Y54100D01*
X446000Y54433D01*
Y52767D01*
G01X453000Y55000D02*
X469100D01*
G01X453000Y48000D02*
Y55000D01*
G01X469100Y48000D02*
X453000D01*
G01X469100Y55000D02*
Y48000D01*
G01X441350Y79500D02*
X441017Y79542D01*
X440725Y79708D01*
X440475Y79958D01*
X440308Y80250D01*
X440225Y80583D01*
Y80917D01*
X440308Y81250D01*
X440475Y81542D01*
X440725Y81792D01*
X441017Y81958D01*
X441350Y82000D01*
X441683Y81958D01*
X441975Y81792D01*
X442225Y81542D01*
X442392Y81250D01*
X442475Y80917D01*
Y80583D01*
X442392Y80250D01*
X442225Y79958D01*
X441975Y79708D01*
X441683Y79542D01*
X441350Y79500D01*
G01X441683Y80167D02*
X442183Y79500D01*
G01X444450D02*
Y82000D01*
X443950Y81500D01*
G01Y79500D02*
X444950D01*
G01X446633Y80000D02*
X446883Y79708D01*
X447217Y79542D01*
X447592Y79500D01*
X447925Y79542D01*
X448258Y79750D01*
X448467Y80000D01*
X448508Y80250D01*
X448425Y80542D01*
X448133Y80750D01*
X447842Y80833D01*
X447467D01*
G01X447842D02*
X448092Y80958D01*
X448300Y81167D01*
X448383Y81417D01*
X448300Y81667D01*
X448092Y81875D01*
X447717Y82000D01*
X447342Y81958D01*
X446967Y81792D01*
G01X450567Y79500D02*
X450650Y80042D01*
X450775Y80500D01*
X450942Y80917D01*
X451150Y81375D01*
X451483Y82000D01*
X449817D01*
G01X447300Y71200D02*
Y59800D01*
G01X460700Y71200D02*
X447300D01*
G01X460700Y59800D02*
Y71200D01*
G01X447300Y59800D02*
X460700D01*
G01X425718Y119867D02*
X425593Y119617D01*
X425510Y119325D01*
Y118992D01*
X425635Y118617D01*
X425843Y118325D01*
X426093Y118117D01*
X426510Y117950D01*
X426885Y117908D01*
X427260Y117992D01*
X427510Y118117D01*
X427760Y118367D01*
X427927Y118658D01*
X428010Y118950D01*
Y119242D01*
X427927Y119533D01*
X427802Y119783D01*
X427635Y119992D01*
G01X427510Y121133D02*
X427802Y121383D01*
X427968Y121717D01*
X428010Y122092D01*
X427968Y122425D01*
X427760Y122758D01*
X427510Y122967D01*
X427260Y123008D01*
X426968Y122925D01*
X426760Y122633D01*
X426677Y122342D01*
Y121967D01*
G01Y122342D02*
X426552Y122592D01*
X426343Y122800D01*
X426093Y122883D01*
X425843Y122800D01*
X425635Y122592D01*
X425510Y122217D01*
X425552Y121842D01*
X425718Y121467D01*
G01X428010Y125150D02*
X427968Y125442D01*
X427843Y125775D01*
X427635Y125983D01*
X427343Y126067D01*
X427052Y125983D01*
X426802Y125733D01*
X426677Y125358D01*
Y124942D01*
X426593Y124692D01*
X426385Y124483D01*
X426093Y124400D01*
X425802Y124525D01*
X425593Y124817D01*
X425510Y125150D01*
X425593Y125483D01*
X425802Y125775D01*
X426093Y125900D01*
X426385Y125817D01*
X426593Y125608D01*
X426677Y125358D01*
Y124942D01*
X426802Y124567D01*
X427052Y124317D01*
X427343Y124233D01*
X427635Y124317D01*
X427843Y124525D01*
X427968Y124858D01*
X428010Y125150D01*
G01X427718Y127542D02*
X427927Y127833D01*
X428010Y128167D01*
X427927Y128500D01*
X427677Y128792D01*
X427302Y129000D01*
X426927Y129083D01*
X426468D01*
X426093Y129000D01*
X425760Y128792D01*
X425593Y128542D01*
X425510Y128250D01*
X425593Y127917D01*
X425760Y127667D01*
X426010Y127500D01*
X426343Y127417D01*
X426635Y127500D01*
X426927Y127708D01*
X427093Y127958D01*
X427135Y128250D01*
X427052Y128583D01*
X426843Y128833D01*
X426468Y129083D01*
G01X423839Y117917D02*
X421339D01*
Y118958D01*
X421464Y119292D01*
X421631Y119500D01*
X421964Y119583D01*
X422297Y119500D01*
X422506Y119250D01*
X422631Y118958D01*
Y117917D01*
G01Y118958D02*
X423839Y119583D01*
G01X422797Y121058D02*
X422506Y121350D01*
X422339Y121600D01*
X422256Y121933D01*
X422339Y122225D01*
X422506Y122433D01*
X422756Y122600D01*
X423047Y122642D01*
X423297Y122600D01*
X423547Y122433D01*
X423756Y122183D01*
X423839Y121892D01*
X423756Y121558D01*
X423506Y121267D01*
X423131Y121100D01*
X422714Y121058D01*
X422172Y121142D01*
X421881Y121267D01*
X421589Y121475D01*
X421381Y121767D01*
X421339Y122058D01*
X421422Y122350D01*
X421631Y122558D01*
G01X423547Y124242D02*
X423756Y124533D01*
X423839Y124867D01*
X423756Y125200D01*
X423506Y125492D01*
X423131Y125700D01*
X422756Y125783D01*
X422297D01*
X421922Y125700D01*
X421589Y125492D01*
X421422Y125242D01*
X421339Y124950D01*
X421422Y124617D01*
X421589Y124367D01*
X421839Y124200D01*
X422172Y124117D01*
X422464Y124200D01*
X422756Y124408D01*
X422922Y124658D01*
X422964Y124950D01*
X422881Y125283D01*
X422672Y125533D01*
X422297Y125783D01*
G01X423839Y128050D02*
X423797Y128342D01*
X423672Y128675D01*
X423464Y128883D01*
X423172Y128967D01*
X422881Y128883D01*
X422631Y128633D01*
X422506Y128258D01*
Y127842D01*
X422422Y127592D01*
X422214Y127383D01*
X421922Y127300D01*
X421631Y127425D01*
X421422Y127717D01*
X421339Y128050D01*
X421422Y128383D01*
X421631Y128675D01*
X421922Y128800D01*
X422214Y128717D01*
X422422Y128508D01*
X422506Y128258D01*
Y127842D01*
X422631Y127467D01*
X422881Y127217D01*
X423172Y127133D01*
X423464Y127217D01*
X423672Y127425D01*
X423797Y127758D01*
X423839Y128050D01*
G01X437100Y124300D02*
X433100D01*
Y116900D01*
G01X445867Y156292D02*
X445617Y156417D01*
X445325Y156500D01*
X444992D01*
X444617Y156375D01*
X444325Y156167D01*
X444117Y155917D01*
X443950Y155500D01*
X443908Y155125D01*
X443992Y154750D01*
X444117Y154500D01*
X444367Y154250D01*
X444658Y154083D01*
X444950Y154000D01*
X445242D01*
X445533Y154083D01*
X445783Y154208D01*
X445992Y154375D01*
G01X447133Y154500D02*
X447383Y154208D01*
X447717Y154042D01*
X448092Y154000D01*
X448425Y154042D01*
X448758Y154250D01*
X448967Y154500D01*
X449008Y154750D01*
X448925Y155042D01*
X448633Y155250D01*
X448342Y155333D01*
X447967D01*
G01X448342D02*
X448592Y155458D01*
X448800Y155667D01*
X448883Y155917D01*
X448800Y156167D01*
X448592Y156375D01*
X448217Y156500D01*
X447842Y156458D01*
X447467Y156292D01*
G01X451150Y154000D02*
X451442Y154042D01*
X451775Y154167D01*
X451983Y154375D01*
X452067Y154667D01*
X451983Y154958D01*
X451733Y155208D01*
X451358Y155333D01*
X450942D01*
X450692Y155417D01*
X450483Y155625D01*
X450400Y155917D01*
X450525Y156208D01*
X450817Y156417D01*
X451150Y156500D01*
X451483Y156417D01*
X451775Y156208D01*
X451900Y155917D01*
X451817Y155625D01*
X451608Y155417D01*
X451358Y155333D01*
X450942D01*
X450567Y155208D01*
X450317Y154958D01*
X450233Y154667D01*
X450317Y154375D01*
X450525Y154167D01*
X450858Y154042D01*
X451150Y154000D01*
G01X454250D02*
Y156500D01*
X453750Y156000D01*
G01Y154000D02*
X454750D01*
G01X454767Y183792D02*
X454517Y183917D01*
X454225Y184000D01*
X453892D01*
X453517Y183875D01*
X453225Y183667D01*
X453017Y183417D01*
X452850Y183000D01*
X452808Y182625D01*
X452892Y182250D01*
X453017Y182000D01*
X453267Y181750D01*
X453558Y181583D01*
X453850Y181500D01*
X454142D01*
X454433Y181583D01*
X454683Y181708D01*
X454892Y181875D01*
G01X456033Y182000D02*
X456283Y181708D01*
X456617Y181542D01*
X456992Y181500D01*
X457325Y181542D01*
X457658Y181750D01*
X457867Y182000D01*
X457908Y182250D01*
X457825Y182542D01*
X457533Y182750D01*
X457242Y182833D01*
X456867D01*
G01X457242D02*
X457492Y182958D01*
X457700Y183167D01*
X457783Y183417D01*
X457700Y183667D01*
X457492Y183875D01*
X457117Y184000D01*
X456742Y183958D01*
X456367Y183792D01*
G01X460050Y181500D02*
X460342Y181542D01*
X460675Y181667D01*
X460883Y181875D01*
X460967Y182167D01*
X460883Y182458D01*
X460633Y182708D01*
X460258Y182833D01*
X459842D01*
X459592Y182917D01*
X459383Y183125D01*
X459300Y183417D01*
X459425Y183708D01*
X459717Y183917D01*
X460050Y184000D01*
X460383Y183917D01*
X460675Y183708D01*
X460800Y183417D01*
X460717Y183125D01*
X460508Y182917D01*
X460258Y182833D01*
X459842D01*
X459467Y182708D01*
X459217Y182458D01*
X459133Y182167D01*
X459217Y181875D01*
X459425Y181667D01*
X459758Y181542D01*
X460050Y181500D01*
G01X463067D02*
X463150Y182042D01*
X463275Y182500D01*
X463442Y182917D01*
X463650Y183375D01*
X463983Y184000D01*
X462317D01*
G01X469000Y110350D02*
X468958Y110017D01*
X468792Y109725D01*
X468542Y109475D01*
X468250Y109308D01*
X467917Y109225D01*
X467583D01*
X467250Y109308D01*
X466958Y109475D01*
X466708Y109725D01*
X466542Y110017D01*
X466500Y110350D01*
X466542Y110683D01*
X466708Y110975D01*
X466958Y111225D01*
X467250Y111392D01*
X467583Y111475D01*
X467917D01*
X468250Y111392D01*
X468542Y111225D01*
X468792Y110975D01*
X468958Y110683D01*
X469000Y110350D01*
G01X468333Y110683D02*
X469000Y111183D01*
G01Y113450D02*
X466500D01*
X467000Y112950D01*
G01X469000D02*
Y113950D01*
G01X468500Y115633D02*
X468792Y115883D01*
X468958Y116217D01*
X469000Y116592D01*
X468958Y116925D01*
X468750Y117258D01*
X468500Y117467D01*
X468250Y117508D01*
X467958Y117425D01*
X467750Y117133D01*
X467667Y116842D01*
Y116467D01*
G01Y116842D02*
X467542Y117092D01*
X467333Y117300D01*
X467083Y117383D01*
X466833Y117300D01*
X466625Y117092D01*
X466500Y116717D01*
X466542Y116342D01*
X466708Y115967D01*
G01X468625Y118733D02*
X468833Y118983D01*
X468958Y119275D01*
X469000Y119650D01*
X468917Y120025D01*
X468750Y120317D01*
X468458Y120525D01*
X468125Y120567D01*
X467792Y120483D01*
X467583Y120275D01*
X467417Y119983D01*
X467375Y119692D01*
X467417Y119400D01*
X467583Y119025D01*
X466500Y119150D01*
Y120275D01*
G01X465100Y105100D02*
X463000Y106900D01*
X465100Y109100D01*
G01X465200Y112700D02*
X446000D01*
Y101500D01*
X465200D01*
Y112700D01*
X464800D01*
G01X390500Y136017D02*
X388000D01*
Y137058D01*
X388125Y137392D01*
X388292Y137600D01*
X388625Y137683D01*
X388958Y137600D01*
X389167Y137350D01*
X389292Y137058D01*
Y136017D01*
G01Y137058D02*
X390500Y137683D01*
G01X389458Y139158D02*
X389167Y139450D01*
X389000Y139700D01*
X388917Y140033D01*
X389000Y140325D01*
X389167Y140533D01*
X389417Y140700D01*
X389708Y140742D01*
X389958Y140700D01*
X390208Y140533D01*
X390417Y140283D01*
X390500Y139992D01*
X390417Y139658D01*
X390167Y139367D01*
X389792Y139200D01*
X389375Y139158D01*
X388833Y139242D01*
X388542Y139367D01*
X388250Y139575D01*
X388042Y139867D01*
X388000Y140158D01*
X388083Y140450D01*
X388292Y140658D01*
G01X390500Y142967D02*
X389958Y143050D01*
X389500Y143175D01*
X389083Y143342D01*
X388625Y143550D01*
X388000Y143883D01*
Y142217D01*
G01X388417Y145358D02*
X388167Y145608D01*
X388042Y145900D01*
X388000Y146233D01*
X388083Y146650D01*
X388292Y146942D01*
X388542Y147025D01*
X388792Y146983D01*
X389000Y146817D01*
X389417Y145983D01*
X389708Y145608D01*
X390125Y145358D01*
X390500Y145275D01*
Y147025D01*
G01X445767Y152292D02*
X445517Y152417D01*
X445225Y152500D01*
X444892D01*
X444517Y152375D01*
X444225Y152167D01*
X444017Y151917D01*
X443850Y151500D01*
X443808Y151125D01*
X443892Y150750D01*
X444017Y150500D01*
X444267Y150250D01*
X444558Y150083D01*
X444850Y150000D01*
X445142D01*
X445433Y150083D01*
X445683Y150208D01*
X445892Y150375D01*
G01X447033Y150500D02*
X447283Y150208D01*
X447617Y150042D01*
X447992Y150000D01*
X448325Y150042D01*
X448658Y150250D01*
X448867Y150500D01*
X448908Y150750D01*
X448825Y151042D01*
X448533Y151250D01*
X448242Y151333D01*
X447867D01*
G01X448242D02*
X448492Y151458D01*
X448700Y151667D01*
X448783Y151917D01*
X448700Y152167D01*
X448492Y152375D01*
X448117Y152500D01*
X447742Y152458D01*
X447367Y152292D01*
G01X451050Y150000D02*
X451342Y150042D01*
X451675Y150167D01*
X451883Y150375D01*
X451967Y150667D01*
X451883Y150958D01*
X451633Y151208D01*
X451258Y151333D01*
X450842D01*
X450592Y151417D01*
X450383Y151625D01*
X450300Y151917D01*
X450425Y152208D01*
X450717Y152417D01*
X451050Y152500D01*
X451383Y152417D01*
X451675Y152208D01*
X451800Y151917D01*
X451717Y151625D01*
X451508Y151417D01*
X451258Y151333D01*
X450842D01*
X450467Y151208D01*
X450217Y150958D01*
X450133Y150667D01*
X450217Y150375D01*
X450425Y150167D01*
X450758Y150042D01*
X451050Y150000D01*
G01X453358Y152083D02*
X453608Y152333D01*
X453900Y152458D01*
X454233Y152500D01*
X454650Y152417D01*
X454942Y152208D01*
X455025Y151958D01*
X454983Y151708D01*
X454817Y151500D01*
X453983Y151083D01*
X453608Y150792D01*
X453358Y150375D01*
X453275Y150000D01*
X455025D01*
G01X460300Y122000D02*
X454800D01*
G01X460300Y130000D02*
Y122000D01*
G01X454800Y130000D02*
X460300D01*
G01X442700D02*
X448200D01*
G01X442700Y122000D02*
Y130000D01*
G01X448200Y122000D02*
X442700D01*
G01X467500Y142017D02*
X465000D01*
Y143058D01*
X465125Y143392D01*
X465292Y143600D01*
X465625Y143683D01*
X465958Y143600D01*
X466167Y143350D01*
X466292Y143058D01*
Y142017D01*
G01Y143058D02*
X467500Y143683D01*
G01X466458Y145158D02*
X466167Y145450D01*
X466000Y145700D01*
X465917Y146033D01*
X466000Y146325D01*
X466167Y146533D01*
X466417Y146700D01*
X466708Y146742D01*
X466958Y146700D01*
X467208Y146533D01*
X467417Y146283D01*
X467500Y145992D01*
X467417Y145658D01*
X467167Y145367D01*
X466792Y145200D01*
X466375Y145158D01*
X465833Y145242D01*
X465542Y145367D01*
X465250Y145575D01*
X465042Y145867D01*
X465000Y146158D01*
X465083Y146450D01*
X465292Y146658D01*
G01X467208Y148342D02*
X467417Y148633D01*
X467500Y148967D01*
X467417Y149300D01*
X467167Y149592D01*
X466792Y149800D01*
X466417Y149883D01*
X465958D01*
X465583Y149800D01*
X465250Y149592D01*
X465083Y149342D01*
X465000Y149050D01*
X465083Y148717D01*
X465250Y148467D01*
X465500Y148300D01*
X465833Y148217D01*
X466125Y148300D01*
X466417Y148508D01*
X466583Y148758D01*
X466625Y149050D01*
X466542Y149383D01*
X466333Y149633D01*
X465958Y149883D01*
G01X465000Y152150D02*
X465083Y151817D01*
X465292Y151567D01*
X465542Y151400D01*
X465875Y151275D01*
X466250Y151233D01*
X466625Y151275D01*
X466958Y151400D01*
X467208Y151567D01*
X467417Y151817D01*
X467500Y152150D01*
X467417Y152483D01*
X467208Y152733D01*
X466958Y152900D01*
X466625Y153025D01*
X466250Y153067D01*
X465875Y153025D01*
X465542Y152900D01*
X465292Y152733D01*
X465083Y152483D01*
X465000Y152150D01*
G01X462000Y139800D02*
X470000D01*
Y122200D01*
X462000D01*
Y139800D01*
G01X444017Y158000D02*
Y160500D01*
X445058D01*
X445392Y160375D01*
X445600Y160208D01*
X445683Y159875D01*
X445600Y159542D01*
X445350Y159333D01*
X445058Y159208D01*
X444017D01*
G01X445058D02*
X445683Y158000D01*
G01X447158Y159042D02*
X447450Y159333D01*
X447700Y159500D01*
X448033Y159583D01*
X448325Y159500D01*
X448533Y159333D01*
X448700Y159083D01*
X448742Y158792D01*
X448700Y158542D01*
X448533Y158292D01*
X448283Y158083D01*
X447992Y158000D01*
X447658Y158083D01*
X447367Y158333D01*
X447200Y158708D01*
X447158Y159125D01*
X447242Y159667D01*
X447367Y159958D01*
X447575Y160250D01*
X447867Y160458D01*
X448158Y160500D01*
X448450Y160417D01*
X448658Y160208D01*
G01X450342Y158292D02*
X450633Y158083D01*
X450967Y158000D01*
X451300Y158083D01*
X451592Y158333D01*
X451800Y158708D01*
X451883Y159083D01*
Y159542D01*
X451800Y159917D01*
X451592Y160250D01*
X451342Y160417D01*
X451050Y160500D01*
X450717Y160417D01*
X450467Y160250D01*
X450300Y160000D01*
X450217Y159667D01*
X450300Y159375D01*
X450508Y159083D01*
X450758Y158917D01*
X451050Y158875D01*
X451383Y158958D01*
X451633Y159167D01*
X451883Y159542D01*
G01X453358Y160083D02*
X453608Y160333D01*
X453900Y160458D01*
X454233Y160500D01*
X454650Y160417D01*
X454942Y160208D01*
X455025Y159958D01*
X454983Y159708D01*
X454817Y159500D01*
X453983Y159083D01*
X453608Y158792D01*
X453358Y158375D01*
X453275Y158000D01*
X455025D01*
G01X438200Y136500D02*
Y144500D01*
X455800D01*
Y136500D01*
X438200D01*
G01X426767Y148292D02*
X426517Y148417D01*
X426225Y148500D01*
X425892D01*
X425517Y148375D01*
X425225Y148167D01*
X425017Y147917D01*
X424850Y147500D01*
X424808Y147125D01*
X424892Y146750D01*
X425017Y146500D01*
X425267Y146250D01*
X425558Y146083D01*
X425850Y146000D01*
X426142D01*
X426433Y146083D01*
X426683Y146208D01*
X426892Y146375D01*
G01X428033Y146500D02*
X428283Y146208D01*
X428617Y146042D01*
X428992Y146000D01*
X429325Y146042D01*
X429658Y146250D01*
X429867Y146500D01*
X429908Y146750D01*
X429825Y147042D01*
X429533Y147250D01*
X429242Y147333D01*
X428867D01*
G01X429242D02*
X429492Y147458D01*
X429700Y147667D01*
X429783Y147917D01*
X429700Y148167D01*
X429492Y148375D01*
X429117Y148500D01*
X428742Y148458D01*
X428367Y148292D01*
G01X432050Y146000D02*
X432342Y146042D01*
X432675Y146167D01*
X432883Y146375D01*
X432967Y146667D01*
X432883Y146958D01*
X432633Y147208D01*
X432258Y147333D01*
X431842D01*
X431592Y147417D01*
X431383Y147625D01*
X431300Y147917D01*
X431425Y148208D01*
X431717Y148417D01*
X432050Y148500D01*
X432383Y148417D01*
X432675Y148208D01*
X432800Y147917D01*
X432717Y147625D01*
X432508Y147417D01*
X432258Y147333D01*
X431842D01*
X431467Y147208D01*
X431217Y146958D01*
X431133Y146667D01*
X431217Y146375D01*
X431425Y146167D01*
X431758Y146042D01*
X432050Y146000D01*
G01X434233Y146375D02*
X434483Y146167D01*
X434775Y146042D01*
X435150Y146000D01*
X435525Y146083D01*
X435817Y146250D01*
X436025Y146542D01*
X436067Y146875D01*
X435983Y147208D01*
X435775Y147417D01*
X435483Y147583D01*
X435192Y147625D01*
X434900Y147583D01*
X434525Y147417D01*
X434650Y148500D01*
X435775D01*
G01X452267Y173292D02*
X452017Y173417D01*
X451725Y173500D01*
X451392D01*
X451017Y173375D01*
X450725Y173167D01*
X450517Y172917D01*
X450350Y172500D01*
X450308Y172125D01*
X450392Y171750D01*
X450517Y171500D01*
X450767Y171250D01*
X451058Y171083D01*
X451350Y171000D01*
X451642D01*
X451933Y171083D01*
X452183Y171208D01*
X452392Y171375D01*
G01X453533Y171500D02*
X453783Y171208D01*
X454117Y171042D01*
X454492Y171000D01*
X454825Y171042D01*
X455158Y171250D01*
X455367Y171500D01*
X455408Y171750D01*
X455325Y172042D01*
X455033Y172250D01*
X454742Y172333D01*
X454367D01*
G01X454742D02*
X454992Y172458D01*
X455200Y172667D01*
X455283Y172917D01*
X455200Y173167D01*
X454992Y173375D01*
X454617Y173500D01*
X454242Y173458D01*
X453867Y173292D01*
G01X457550Y171000D02*
X457842Y171042D01*
X458175Y171167D01*
X458383Y171375D01*
X458467Y171667D01*
X458383Y171958D01*
X458133Y172208D01*
X457758Y172333D01*
X457342D01*
X457092Y172417D01*
X456883Y172625D01*
X456800Y172917D01*
X456925Y173208D01*
X457217Y173417D01*
X457550Y173500D01*
X457883Y173417D01*
X458175Y173208D01*
X458300Y172917D01*
X458217Y172625D01*
X458008Y172417D01*
X457758Y172333D01*
X457342D01*
X456967Y172208D01*
X456717Y171958D01*
X456633Y171667D01*
X456717Y171375D01*
X456925Y171167D01*
X457258Y171042D01*
X457550Y171000D01*
G01X459858Y172042D02*
X460150Y172333D01*
X460400Y172500D01*
X460733Y172583D01*
X461025Y172500D01*
X461233Y172333D01*
X461400Y172083D01*
X461442Y171792D01*
X461400Y171542D01*
X461233Y171292D01*
X460983Y171083D01*
X460692Y171000D01*
X460358Y171083D01*
X460067Y171333D01*
X459900Y171708D01*
X459858Y172125D01*
X459942Y172667D01*
X460067Y172958D01*
X460275Y173250D01*
X460567Y173458D01*
X460858Y173500D01*
X461150Y173417D01*
X461358Y173208D01*
G01X472275Y208500D02*
Y211000D01*
G01X474025D02*
Y208500D01*
G01Y209750D02*
X472275D01*
G01X475333Y208500D02*
Y211000D01*
X476167D01*
X476500Y210875D01*
X476750Y210708D01*
X476958Y210458D01*
X477125Y210167D01*
X477167Y209750D01*
X477125Y209333D01*
X476958Y209042D01*
X476750Y208792D01*
X476500Y208625D01*
X476167Y208500D01*
X475333D01*
G01X478433D02*
Y211000D01*
X479267D01*
X479600Y210875D01*
X479850Y210708D01*
X480058Y210458D01*
X480225Y210167D01*
X480267Y209750D01*
X480225Y209333D01*
X480058Y209042D01*
X479850Y208792D01*
X479600Y208625D01*
X479267Y208500D01*
X478433D01*
G01X481575Y208833D02*
X481908Y208625D01*
X482283Y208500D01*
X482617D01*
X482950Y208625D01*
X483200Y208833D01*
X483325Y209125D01*
X483242Y209417D01*
X483033Y209667D01*
X482658Y209833D01*
X482158Y209917D01*
X481867Y210083D01*
X481742Y210375D01*
X481825Y210667D01*
X482033Y210875D01*
X482325Y211000D01*
X482617D01*
X482908Y210917D01*
X483158Y210708D01*
G01X484508Y208500D02*
X485550Y211000D01*
X486592Y208500D01*
G01X486217Y209375D02*
X484883D01*
G01X487775Y208833D02*
X488108Y208625D01*
X488483Y208500D01*
X488817D01*
X489150Y208625D01*
X489400Y208833D01*
X489525Y209125D01*
X489442Y209417D01*
X489233Y209667D01*
X488858Y209833D01*
X488358Y209917D01*
X488067Y210083D01*
X487942Y210375D01*
X488025Y210667D01*
X488233Y210875D01*
X488525Y211000D01*
X488817D01*
X489108Y210917D01*
X489358Y210708D01*
G01X490958Y210583D02*
X491208Y210833D01*
X491500Y210958D01*
X491833Y211000D01*
X492250Y210917D01*
X492542Y210708D01*
X492625Y210458D01*
X492583Y210208D01*
X492417Y210000D01*
X491583Y209583D01*
X491208Y209292D01*
X490958Y208875D01*
X490875Y208500D01*
X492625D01*
G01X494767D02*
X494850Y209042D01*
X494975Y209500D01*
X495142Y209917D01*
X495350Y210375D01*
X495683Y211000D01*
X494017D01*
G01X436967Y269500D02*
Y267000D01*
X438633D01*
G01X441733D02*
X440067D01*
Y269500D01*
X441733D01*
G01X441067Y268292D02*
X440067D01*
G01X443083Y267000D02*
Y269500D01*
X443917D01*
X444250Y269375D01*
X444500Y269208D01*
X444708Y268958D01*
X444875Y268667D01*
X444917Y268250D01*
X444875Y267833D01*
X444708Y267542D01*
X444500Y267292D01*
X444250Y267125D01*
X443917Y267000D01*
X443083D01*
G01X447100D02*
Y269500D01*
X446600Y269000D01*
G01Y267000D02*
X447600D01*
G01X449408Y268042D02*
X449700Y268333D01*
X449950Y268500D01*
X450283Y268583D01*
X450575Y268500D01*
X450783Y268333D01*
X450950Y268083D01*
X450992Y267792D01*
X450950Y267542D01*
X450783Y267292D01*
X450533Y267083D01*
X450242Y267000D01*
X449908Y267083D01*
X449617Y267333D01*
X449450Y267708D01*
X449408Y268125D01*
X449492Y268667D01*
X449617Y268958D01*
X449825Y269250D01*
X450117Y269458D01*
X450408Y269500D01*
X450700Y269417D01*
X450908Y269208D01*
G01X438317Y251880D02*
Y263080D01*
X447117D01*
Y251880D01*
X438317D01*
G01X466761Y560075D02*
X471811D01*
Y658775D01*
X496461D01*
Y474375D01*
X471811D01*
Y533075D01*
X466761D01*
Y560075D01*
G01X400517Y382000D02*
Y384500D01*
X401558D01*
X401892Y384375D01*
X402100Y384208D01*
X402183Y383875D01*
X402100Y383542D01*
X401850Y383333D01*
X401558Y383208D01*
X400517D01*
G01X401558D02*
X402183Y382000D01*
G01X403533Y382500D02*
X403783Y382208D01*
X404117Y382042D01*
X404492Y382000D01*
X404825Y382042D01*
X405158Y382250D01*
X405367Y382500D01*
X405408Y382750D01*
X405325Y383042D01*
X405033Y383250D01*
X404742Y383333D01*
X404367D01*
G01X404742D02*
X404992Y383458D01*
X405200Y383667D01*
X405283Y383917D01*
X405200Y384167D01*
X404992Y384375D01*
X404617Y384500D01*
X404242Y384458D01*
X403867Y384292D01*
G01X407550Y382000D02*
X407842Y382042D01*
X408175Y382167D01*
X408383Y382375D01*
X408467Y382667D01*
X408383Y382958D01*
X408133Y383208D01*
X407758Y383333D01*
X407342D01*
X407092Y383417D01*
X406883Y383625D01*
X406800Y383917D01*
X406925Y384208D01*
X407217Y384417D01*
X407550Y384500D01*
X407883Y384417D01*
X408175Y384208D01*
X408300Y383917D01*
X408217Y383625D01*
X408008Y383417D01*
X407758Y383333D01*
X407342D01*
X406967Y383208D01*
X406717Y382958D01*
X406633Y382667D01*
X406717Y382375D01*
X406925Y382167D01*
X407258Y382042D01*
X407550Y382000D01*
G01X410650D02*
X410942Y382042D01*
X411275Y382167D01*
X411483Y382375D01*
X411567Y382667D01*
X411483Y382958D01*
X411233Y383208D01*
X410858Y383333D01*
X410442D01*
X410192Y383417D01*
X409983Y383625D01*
X409900Y383917D01*
X410025Y384208D01*
X410317Y384417D01*
X410650Y384500D01*
X410983Y384417D01*
X411275Y384208D01*
X411400Y383917D01*
X411317Y383625D01*
X411108Y383417D01*
X410858Y383333D01*
X410442D01*
X410067Y383208D01*
X409817Y382958D01*
X409733Y382667D01*
X409817Y382375D01*
X410025Y382167D01*
X410358Y382042D01*
X410650Y382000D01*
G01X420992Y381182D02*
Y385182D01*
X413592D01*
G01X422017Y406000D02*
Y408500D01*
X423058D01*
X423392Y408375D01*
X423600Y408208D01*
X423683Y407875D01*
X423600Y407542D01*
X423350Y407333D01*
X423058Y407208D01*
X422017D01*
G01X423058D02*
X423683Y406000D01*
G01X425033Y406500D02*
X425283Y406208D01*
X425617Y406042D01*
X425992Y406000D01*
X426325Y406042D01*
X426658Y406250D01*
X426867Y406500D01*
X426908Y406750D01*
X426825Y407042D01*
X426533Y407250D01*
X426242Y407333D01*
X425867D01*
G01X426242D02*
X426492Y407458D01*
X426700Y407667D01*
X426783Y407917D01*
X426700Y408167D01*
X426492Y408375D01*
X426117Y408500D01*
X425742Y408458D01*
X425367Y408292D01*
G01X428967Y406000D02*
X429050Y406542D01*
X429175Y407000D01*
X429342Y407417D01*
X429550Y407875D01*
X429883Y408500D01*
X428217D01*
G01X432150Y406000D02*
X432442Y406042D01*
X432775Y406167D01*
X432983Y406375D01*
X433067Y406667D01*
X432983Y406958D01*
X432733Y407208D01*
X432358Y407333D01*
X431942D01*
X431692Y407417D01*
X431483Y407625D01*
X431400Y407917D01*
X431525Y408208D01*
X431817Y408417D01*
X432150Y408500D01*
X432483Y408417D01*
X432775Y408208D01*
X432900Y407917D01*
X432817Y407625D01*
X432608Y407417D01*
X432358Y407333D01*
X431942D01*
X431567Y407208D01*
X431317Y406958D01*
X431233Y406667D01*
X431317Y406375D01*
X431525Y406167D01*
X431858Y406042D01*
X432150Y406000D01*
G01X435725Y400959D02*
Y404959D01*
X428325D01*
G01X441800Y400017D02*
X439300D01*
Y401058D01*
X439425Y401392D01*
X439592Y401600D01*
X439925Y401683D01*
X440258Y401600D01*
X440467Y401350D01*
X440592Y401058D01*
Y400017D01*
G01Y401058D02*
X441800Y401683D01*
G01Y404450D02*
X439300D01*
X441092Y402908D01*
Y404992D01*
G01X441800Y407050D02*
X439300D01*
X439800Y406550D01*
G01X441800D02*
Y407550D01*
G01X439300Y410150D02*
X439383Y409817D01*
X439592Y409567D01*
X439842Y409400D01*
X440175Y409275D01*
X440550Y409233D01*
X440925Y409275D01*
X441258Y409400D01*
X441508Y409567D01*
X441717Y409817D01*
X441800Y410150D01*
X441717Y410483D01*
X441508Y410733D01*
X441258Y410900D01*
X440925Y411025D01*
X440550Y411067D01*
X440175Y411025D01*
X439842Y410900D01*
X439592Y410733D01*
X439383Y410483D01*
X439300Y410150D01*
G01X445800Y400017D02*
X443300D01*
Y401058D01*
X443425Y401392D01*
X443592Y401600D01*
X443925Y401683D01*
X444258Y401600D01*
X444467Y401350D01*
X444592Y401058D01*
Y400017D01*
G01Y401058D02*
X445800Y401683D01*
G01Y404450D02*
X443300D01*
X445092Y402908D01*
Y404992D01*
G01X445800Y407050D02*
X443300D01*
X443800Y406550D01*
G01X445800D02*
Y407550D01*
G01X445300Y409233D02*
X445592Y409483D01*
X445758Y409817D01*
X445800Y410192D01*
X445758Y410525D01*
X445550Y410858D01*
X445300Y411067D01*
X445050Y411108D01*
X444758Y411025D01*
X444550Y410733D01*
X444467Y410442D01*
Y410067D01*
G01Y410442D02*
X444342Y410692D01*
X444133Y410900D01*
X443883Y410983D01*
X443633Y410900D01*
X443425Y410692D01*
X443300Y410317D01*
X443342Y409942D01*
X443508Y409567D01*
G01X425350Y381500D02*
X425017Y381542D01*
X424725Y381708D01*
X424475Y381958D01*
X424308Y382250D01*
X424225Y382583D01*
Y382917D01*
X424308Y383250D01*
X424475Y383542D01*
X424725Y383792D01*
X425017Y383958D01*
X425350Y384000D01*
X425683Y383958D01*
X425975Y383792D01*
X426225Y383542D01*
X426392Y383250D01*
X426475Y382917D01*
Y382583D01*
X426392Y382250D01*
X426225Y381958D01*
X425975Y381708D01*
X425683Y381542D01*
X425350Y381500D01*
G01X425683Y382167D02*
X426183Y381500D01*
G01X427658Y383583D02*
X427908Y383833D01*
X428200Y383958D01*
X428533Y384000D01*
X428950Y383917D01*
X429242Y383708D01*
X429325Y383458D01*
X429283Y383208D01*
X429117Y383000D01*
X428283Y382583D01*
X427908Y382292D01*
X427658Y381875D01*
X427575Y381500D01*
X429325D01*
G01X430633Y382000D02*
X430883Y381708D01*
X431217Y381542D01*
X431592Y381500D01*
X431925Y381542D01*
X432258Y381750D01*
X432467Y382000D01*
X432508Y382250D01*
X432425Y382542D01*
X432133Y382750D01*
X431842Y382833D01*
X431467D01*
G01X431842D02*
X432092Y382958D01*
X432300Y383167D01*
X432383Y383417D01*
X432300Y383667D01*
X432092Y383875D01*
X431717Y384000D01*
X431342Y383958D01*
X430967Y383792D01*
G01X435150Y381500D02*
Y384000D01*
X433608Y382208D01*
X435692D01*
G01X436400Y385600D02*
Y399600D01*
G01X423400Y385600D02*
X436400D01*
G01X423400Y399600D02*
Y385600D01*
G01X436400Y399600D02*
X423400D01*
G01X407350Y401500D02*
X407017Y401542D01*
X406725Y401708D01*
X406475Y401958D01*
X406308Y402250D01*
X406225Y402583D01*
Y402917D01*
X406308Y403250D01*
X406475Y403542D01*
X406725Y403792D01*
X407017Y403958D01*
X407350Y404000D01*
X407683Y403958D01*
X407975Y403792D01*
X408225Y403542D01*
X408392Y403250D01*
X408475Y402917D01*
Y402583D01*
X408392Y402250D01*
X408225Y401958D01*
X407975Y401708D01*
X407683Y401542D01*
X407350Y401500D01*
G01X407683Y402167D02*
X408183Y401500D01*
G01X409658Y403583D02*
X409908Y403833D01*
X410200Y403958D01*
X410533Y404000D01*
X410950Y403917D01*
X411242Y403708D01*
X411325Y403458D01*
X411283Y403208D01*
X411117Y403000D01*
X410283Y402583D01*
X409908Y402292D01*
X409658Y401875D01*
X409575Y401500D01*
X411325D01*
G01X412633Y401875D02*
X412883Y401667D01*
X413175Y401542D01*
X413550Y401500D01*
X413925Y401583D01*
X414217Y401750D01*
X414425Y402042D01*
X414467Y402375D01*
X414383Y402708D01*
X414175Y402917D01*
X413883Y403083D01*
X413592Y403125D01*
X413300Y403083D01*
X412925Y402917D01*
X413050Y404000D01*
X414175D01*
G01X416650Y401500D02*
X416942Y401542D01*
X417275Y401667D01*
X417483Y401875D01*
X417567Y402167D01*
X417483Y402458D01*
X417233Y402708D01*
X416858Y402833D01*
X416442D01*
X416192Y402917D01*
X415983Y403125D01*
X415900Y403417D01*
X416025Y403708D01*
X416317Y403917D01*
X416650Y404000D01*
X416983Y403917D01*
X417275Y403708D01*
X417400Y403417D01*
X417317Y403125D01*
X417108Y402917D01*
X416858Y402833D01*
X416442D01*
X416067Y402708D01*
X415817Y402458D01*
X415733Y402167D01*
X415817Y401875D01*
X416025Y401667D01*
X416358Y401542D01*
X416650Y401500D01*
G01X408292Y386407D02*
X422292D01*
G01X408292Y399407D02*
Y386407D01*
G01X422292Y399407D02*
X408292D01*
G01X422292Y386407D02*
Y399407D01*
G01X388267Y510792D02*
X388017Y510917D01*
X387725Y511000D01*
X387392D01*
X387017Y510875D01*
X386725Y510667D01*
X386517Y510417D01*
X386350Y510000D01*
X386308Y509625D01*
X386392Y509250D01*
X386517Y509000D01*
X386767Y508750D01*
X387058Y508583D01*
X387350Y508500D01*
X387642D01*
X387933Y508583D01*
X388183Y508708D01*
X388392Y508875D01*
G01X389658Y510583D02*
X389908Y510833D01*
X390200Y510958D01*
X390533Y511000D01*
X390950Y510917D01*
X391242Y510708D01*
X391325Y510458D01*
X391283Y510208D01*
X391117Y510000D01*
X390283Y509583D01*
X389908Y509292D01*
X389658Y508875D01*
X389575Y508500D01*
X391325D01*
G01X393550D02*
Y511000D01*
X393050Y510500D01*
G01Y508500D02*
X394050D01*
G01X396650D02*
Y511000D01*
X396150Y510500D01*
G01Y508500D02*
X397150D01*
G01X388267Y514792D02*
X388017Y514917D01*
X387725Y515000D01*
X387392D01*
X387017Y514875D01*
X386725Y514667D01*
X386517Y514417D01*
X386350Y514000D01*
X386308Y513625D01*
X386392Y513250D01*
X386517Y513000D01*
X386767Y512750D01*
X387058Y512583D01*
X387350Y512500D01*
X387642D01*
X387933Y512583D01*
X388183Y512708D01*
X388392Y512875D01*
G01X389658Y514583D02*
X389908Y514833D01*
X390200Y514958D01*
X390533Y515000D01*
X390950Y514917D01*
X391242Y514708D01*
X391325Y514458D01*
X391283Y514208D01*
X391117Y514000D01*
X390283Y513583D01*
X389908Y513292D01*
X389658Y512875D01*
X389575Y512500D01*
X391325D01*
G01X393550D02*
Y515000D01*
X393050Y514500D01*
G01Y512500D02*
X394050D01*
G01X396650Y515000D02*
X396317Y514917D01*
X396067Y514708D01*
X395900Y514458D01*
X395775Y514125D01*
X395733Y513750D01*
X395775Y513375D01*
X395900Y513042D01*
X396067Y512792D01*
X396317Y512583D01*
X396650Y512500D01*
X396983Y512583D01*
X397233Y512792D01*
X397400Y513042D01*
X397525Y513375D01*
X397567Y513750D01*
X397525Y514125D01*
X397400Y514458D01*
X397233Y514708D01*
X396983Y514917D01*
X396650Y515000D01*
G01X423267Y545453D02*
X423017Y545578D01*
X422725Y545661D01*
X422392D01*
X422017Y545536D01*
X421725Y545328D01*
X421517Y545078D01*
X421350Y544661D01*
X421308Y544286D01*
X421392Y543911D01*
X421517Y543661D01*
X421767Y543411D01*
X422058Y543244D01*
X422350Y543161D01*
X422642D01*
X422933Y543244D01*
X423183Y543369D01*
X423392Y543536D01*
G01X424658Y545244D02*
X424908Y545494D01*
X425200Y545619D01*
X425533Y545661D01*
X425950Y545578D01*
X426242Y545369D01*
X426325Y545119D01*
X426283Y544869D01*
X426117Y544661D01*
X425283Y544244D01*
X424908Y543953D01*
X424658Y543536D01*
X424575Y543161D01*
X426325D01*
G01X427633Y543661D02*
X427883Y543369D01*
X428217Y543203D01*
X428592Y543161D01*
X428925Y543203D01*
X429258Y543411D01*
X429467Y543661D01*
X429508Y543911D01*
X429425Y544203D01*
X429133Y544411D01*
X428842Y544494D01*
X428467D01*
G01X428842D02*
X429092Y544619D01*
X429300Y544828D01*
X429383Y545078D01*
X429300Y545328D01*
X429092Y545536D01*
X428717Y545661D01*
X428342Y545619D01*
X427967Y545453D01*
G01X430733Y543661D02*
X430983Y543369D01*
X431317Y543203D01*
X431692Y543161D01*
X432025Y543203D01*
X432358Y543411D01*
X432567Y543661D01*
X432608Y543911D01*
X432525Y544203D01*
X432233Y544411D01*
X431942Y544494D01*
X431567D01*
G01X431942D02*
X432192Y544619D01*
X432400Y544828D01*
X432483Y545078D01*
X432400Y545328D01*
X432192Y545536D01*
X431817Y545661D01*
X431442Y545619D01*
X431067Y545453D01*
G01X415767Y554453D02*
X415517Y554578D01*
X415225Y554661D01*
X414892D01*
X414517Y554536D01*
X414225Y554328D01*
X414017Y554078D01*
X413850Y553661D01*
X413808Y553286D01*
X413892Y552911D01*
X414017Y552661D01*
X414267Y552411D01*
X414558Y552244D01*
X414850Y552161D01*
X415142D01*
X415433Y552244D01*
X415683Y552369D01*
X415892Y552536D01*
G01X417158Y554244D02*
X417408Y554494D01*
X417700Y554619D01*
X418033Y554661D01*
X418450Y554578D01*
X418742Y554369D01*
X418825Y554119D01*
X418783Y553869D01*
X418617Y553661D01*
X417783Y553244D01*
X417408Y552953D01*
X417158Y552536D01*
X417075Y552161D01*
X418825D01*
G01X420133Y552661D02*
X420383Y552369D01*
X420717Y552203D01*
X421092Y552161D01*
X421425Y552203D01*
X421758Y552411D01*
X421967Y552661D01*
X422008Y552911D01*
X421925Y553203D01*
X421633Y553411D01*
X421342Y553494D01*
X420967D01*
G01X421342D02*
X421592Y553619D01*
X421800Y553828D01*
X421883Y554078D01*
X421800Y554328D01*
X421592Y554536D01*
X421217Y554661D01*
X420842Y554619D01*
X420467Y554453D01*
G01X424650Y552161D02*
Y554661D01*
X423108Y552869D01*
X425192D01*
G01X421517Y539161D02*
Y541661D01*
X422558D01*
X422892Y541536D01*
X423100Y541369D01*
X423183Y541036D01*
X423100Y540703D01*
X422850Y540494D01*
X422558Y540369D01*
X421517D01*
G01X422558D02*
X423183Y539161D01*
G01X425950D02*
Y541661D01*
X424408Y539869D01*
X426492D01*
G01X427758Y541244D02*
X428008Y541494D01*
X428300Y541619D01*
X428633Y541661D01*
X429050Y541578D01*
X429342Y541369D01*
X429425Y541119D01*
X429383Y540869D01*
X429217Y540661D01*
X428383Y540244D01*
X428008Y539953D01*
X427758Y539536D01*
X427675Y539161D01*
X429425D01*
G01X430858Y541244D02*
X431108Y541494D01*
X431400Y541619D01*
X431733Y541661D01*
X432150Y541578D01*
X432442Y541369D01*
X432525Y541119D01*
X432483Y540869D01*
X432317Y540661D01*
X431483Y540244D01*
X431108Y539953D01*
X430858Y539536D01*
X430775Y539161D01*
X432525D01*
G01X434800Y545500D02*
Y541500D01*
X442200D01*
G01X458017Y506000D02*
Y508500D01*
X459058D01*
X459392Y508375D01*
X459600Y508208D01*
X459683Y507875D01*
X459600Y507542D01*
X459350Y507333D01*
X459058Y507208D01*
X458017D01*
G01X459058D02*
X459683Y506000D01*
G01X462450D02*
Y508500D01*
X460908Y506708D01*
X462992D01*
G01X464258Y508083D02*
X464508Y508333D01*
X464800Y508458D01*
X465133Y508500D01*
X465550Y508417D01*
X465842Y508208D01*
X465925Y507958D01*
X465883Y507708D01*
X465717Y507500D01*
X464883Y507083D01*
X464508Y506792D01*
X464258Y506375D01*
X464175Y506000D01*
X465925D01*
G01X467233Y506500D02*
X467483Y506208D01*
X467817Y506042D01*
X468192Y506000D01*
X468525Y506042D01*
X468858Y506250D01*
X469067Y506500D01*
X469108Y506750D01*
X469025Y507042D01*
X468733Y507250D01*
X468442Y507333D01*
X468067D01*
G01X468442D02*
X468692Y507458D01*
X468900Y507667D01*
X468983Y507917D01*
X468900Y508167D01*
X468692Y508375D01*
X468317Y508500D01*
X467942Y508458D01*
X467567Y508292D01*
G01X466700Y523300D02*
Y527300D01*
X459300D01*
G01X458017Y501500D02*
Y504000D01*
X459058D01*
X459392Y503875D01*
X459600Y503708D01*
X459683Y503375D01*
X459600Y503042D01*
X459350Y502833D01*
X459058Y502708D01*
X458017D01*
G01X459058D02*
X459683Y501500D01*
G01X462450D02*
Y504000D01*
X460908Y502208D01*
X462992D01*
G01X464258Y503583D02*
X464508Y503833D01*
X464800Y503958D01*
X465133Y504000D01*
X465550Y503917D01*
X465842Y503708D01*
X465925Y503458D01*
X465883Y503208D01*
X465717Y503000D01*
X464883Y502583D01*
X464508Y502292D01*
X464258Y501875D01*
X464175Y501500D01*
X465925D01*
G01X467233Y501875D02*
X467483Y501667D01*
X467775Y501542D01*
X468150Y501500D01*
X468525Y501583D01*
X468817Y501750D01*
X469025Y502042D01*
X469067Y502375D01*
X468983Y502708D01*
X468775Y502917D01*
X468483Y503083D01*
X468192Y503125D01*
X467900Y503083D01*
X467525Y502917D01*
X467650Y504000D01*
X468775D01*
G01X464800Y514900D02*
Y518900D01*
X457400D01*
G01X458017Y510000D02*
Y512500D01*
X459058D01*
X459392Y512375D01*
X459600Y512208D01*
X459683Y511875D01*
X459600Y511542D01*
X459350Y511333D01*
X459058Y511208D01*
X458017D01*
G01X459058D02*
X459683Y510000D01*
G01X462450D02*
Y512500D01*
X460908Y510708D01*
X462992D01*
G01X464258Y512083D02*
X464508Y512333D01*
X464800Y512458D01*
X465133Y512500D01*
X465550Y512417D01*
X465842Y512208D01*
X465925Y511958D01*
X465883Y511708D01*
X465717Y511500D01*
X464883Y511083D01*
X464508Y510792D01*
X464258Y510375D01*
X464175Y510000D01*
X465925D01*
G01X468067D02*
X468150Y510542D01*
X468275Y511000D01*
X468442Y511417D01*
X468650Y511875D01*
X468983Y512500D01*
X467317D01*
G01X459300Y531500D02*
Y527500D01*
X466700D01*
G01X424517Y508500D02*
Y511000D01*
X425558D01*
X425892Y510875D01*
X426100Y510708D01*
X426183Y510375D01*
X426100Y510042D01*
X425850Y509833D01*
X425558Y509708D01*
X424517D01*
G01X425558D02*
X426183Y508500D01*
G01X428950D02*
Y511000D01*
X427408Y509208D01*
X429492D01*
G01X430758Y510583D02*
X431008Y510833D01*
X431300Y510958D01*
X431633Y511000D01*
X432050Y510917D01*
X432342Y510708D01*
X432425Y510458D01*
X432383Y510208D01*
X432217Y510000D01*
X431383Y509583D01*
X431008Y509292D01*
X430758Y508875D01*
X430675Y508500D01*
X432425D01*
G01X433942Y508792D02*
X434233Y508583D01*
X434567Y508500D01*
X434900Y508583D01*
X435192Y508833D01*
X435400Y509208D01*
X435483Y509583D01*
Y510042D01*
X435400Y510417D01*
X435192Y510750D01*
X434942Y510917D01*
X434650Y511000D01*
X434317Y510917D01*
X434067Y510750D01*
X433900Y510500D01*
X433817Y510167D01*
X433900Y509875D01*
X434108Y509583D01*
X434358Y509417D01*
X434650Y509375D01*
X434983Y509458D01*
X435233Y509667D01*
X435483Y510042D01*
G01X427300Y520000D02*
Y516000D01*
X434700D01*
G01X414017Y548161D02*
Y550661D01*
X415058D01*
X415392Y550536D01*
X415600Y550369D01*
X415683Y550036D01*
X415600Y549703D01*
X415350Y549494D01*
X415058Y549369D01*
X414017D01*
G01X415058D02*
X415683Y548161D01*
G01X418450D02*
Y550661D01*
X416908Y548869D01*
X418992D01*
G01X420133Y548661D02*
X420383Y548369D01*
X420717Y548203D01*
X421092Y548161D01*
X421425Y548203D01*
X421758Y548411D01*
X421967Y548661D01*
X422008Y548911D01*
X421925Y549203D01*
X421633Y549411D01*
X421342Y549494D01*
X420967D01*
G01X421342D02*
X421592Y549619D01*
X421800Y549828D01*
X421883Y550078D01*
X421800Y550328D01*
X421592Y550536D01*
X421217Y550661D01*
X420842Y550619D01*
X420467Y550453D01*
G01X424150Y550661D02*
X423817Y550578D01*
X423567Y550369D01*
X423400Y550119D01*
X423275Y549786D01*
X423233Y549411D01*
X423275Y549036D01*
X423400Y548703D01*
X423567Y548453D01*
X423817Y548244D01*
X424150Y548161D01*
X424483Y548244D01*
X424733Y548453D01*
X424900Y548703D01*
X425025Y549036D01*
X425067Y549411D01*
X425025Y549786D01*
X424900Y550119D01*
X424733Y550369D01*
X424483Y550578D01*
X424150Y550661D01*
G01X434700Y547000D02*
Y551000D01*
X427300D01*
G01X429000Y521517D02*
X426500D01*
Y522558D01*
X426625Y522892D01*
X426792Y523100D01*
X427125Y523183D01*
X427458Y523100D01*
X427667Y522850D01*
X427792Y522558D01*
Y521517D01*
G01Y522558D02*
X429000Y523183D01*
G01Y525950D02*
X426500D01*
X428292Y524408D01*
Y526492D01*
G01X428500Y527633D02*
X428792Y527883D01*
X428958Y528217D01*
X429000Y528592D01*
X428958Y528925D01*
X428750Y529258D01*
X428500Y529467D01*
X428250Y529508D01*
X427958Y529425D01*
X427750Y529133D01*
X427667Y528842D01*
Y528467D01*
G01Y528842D02*
X427542Y529092D01*
X427333Y529300D01*
X427083Y529383D01*
X426833Y529300D01*
X426625Y529092D01*
X426500Y528717D01*
X426542Y528342D01*
X426708Y527967D01*
G01X429000Y531650D02*
X426500D01*
X427000Y531150D01*
G01X429000D02*
Y532150D01*
G01X430500Y520300D02*
X434500D01*
Y527700D01*
G01X445500Y501517D02*
X443000D01*
Y502558D01*
X443125Y502892D01*
X443292Y503100D01*
X443625Y503183D01*
X443958Y503100D01*
X444167Y502850D01*
X444292Y502558D01*
Y501517D01*
G01Y502558D02*
X445500Y503183D01*
G01Y505950D02*
X443000D01*
X444792Y504408D01*
Y506492D01*
G01X445000Y507633D02*
X445292Y507883D01*
X445458Y508217D01*
X445500Y508592D01*
X445458Y508925D01*
X445250Y509258D01*
X445000Y509467D01*
X444750Y509508D01*
X444458Y509425D01*
X444250Y509133D01*
X444167Y508842D01*
Y508467D01*
G01Y508842D02*
X444042Y509092D01*
X443833Y509300D01*
X443583Y509383D01*
X443333Y509300D01*
X443125Y509092D01*
X443000Y508717D01*
X443042Y508342D01*
X443208Y507967D01*
G01X443417Y510858D02*
X443167Y511108D01*
X443042Y511400D01*
X443000Y511733D01*
X443083Y512150D01*
X443292Y512442D01*
X443542Y512525D01*
X443792Y512483D01*
X444000Y512317D01*
X444417Y511483D01*
X444708Y511108D01*
X445125Y510858D01*
X445500Y510775D01*
Y512525D01*
G01X447000Y521700D02*
X443000D01*
Y514300D01*
G01X450900Y571000D02*
X450567Y571042D01*
X450275Y571208D01*
X450025Y571458D01*
X449858Y571750D01*
X449775Y572083D01*
Y572417D01*
X449858Y572750D01*
X450025Y573042D01*
X450275Y573292D01*
X450567Y573458D01*
X450900Y573500D01*
X451233Y573458D01*
X451525Y573292D01*
X451775Y573042D01*
X451942Y572750D01*
X452025Y572417D01*
Y572083D01*
X451942Y571750D01*
X451775Y571458D01*
X451525Y571208D01*
X451233Y571042D01*
X450900Y571000D01*
G01X451233Y571667D02*
X451733Y571000D01*
G01X453208Y572042D02*
X453500Y572333D01*
X453750Y572500D01*
X454083Y572583D01*
X454375Y572500D01*
X454583Y572333D01*
X454750Y572083D01*
X454792Y571792D01*
X454750Y571542D01*
X454583Y571292D01*
X454333Y571083D01*
X454042Y571000D01*
X453708Y571083D01*
X453417Y571333D01*
X453250Y571708D01*
X453208Y572125D01*
X453292Y572667D01*
X453417Y572958D01*
X453625Y573250D01*
X453917Y573458D01*
X454208Y573500D01*
X454500Y573417D01*
X454708Y573208D01*
G01X456183Y571500D02*
X456433Y571208D01*
X456767Y571042D01*
X457142Y571000D01*
X457475Y571042D01*
X457808Y571250D01*
X458017Y571500D01*
X458058Y571750D01*
X457975Y572042D01*
X457683Y572250D01*
X457392Y572333D01*
X457017D01*
G01X457392D02*
X457642Y572458D01*
X457850Y572667D01*
X457933Y572917D01*
X457850Y573167D01*
X457642Y573375D01*
X457267Y573500D01*
X456892Y573458D01*
X456517Y573292D01*
G01X464700Y554000D02*
X462600Y555800D01*
X464700Y558000D01*
G01X464800Y561600D02*
X445600D01*
Y550400D01*
X464800D01*
Y561600D01*
X464400D01*
G01X411900Y571000D02*
X411567Y571042D01*
X411275Y571208D01*
X411025Y571458D01*
X410858Y571750D01*
X410775Y572083D01*
Y572417D01*
X410858Y572750D01*
X411025Y573042D01*
X411275Y573292D01*
X411567Y573458D01*
X411900Y573500D01*
X412233Y573458D01*
X412525Y573292D01*
X412775Y573042D01*
X412942Y572750D01*
X413025Y572417D01*
Y572083D01*
X412942Y571750D01*
X412775Y571458D01*
X412525Y571208D01*
X412233Y571042D01*
X411900Y571000D01*
G01X412233Y571667D02*
X412733Y571000D01*
G01X414208Y572042D02*
X414500Y572333D01*
X414750Y572500D01*
X415083Y572583D01*
X415375Y572500D01*
X415583Y572333D01*
X415750Y572083D01*
X415792Y571792D01*
X415750Y571542D01*
X415583Y571292D01*
X415333Y571083D01*
X415042Y571000D01*
X414708Y571083D01*
X414417Y571333D01*
X414250Y571708D01*
X414208Y572125D01*
X414292Y572667D01*
X414417Y572958D01*
X414625Y573250D01*
X414917Y573458D01*
X415208Y573500D01*
X415500Y573417D01*
X415708Y573208D01*
G01X417308Y572042D02*
X417600Y572333D01*
X417850Y572500D01*
X418183Y572583D01*
X418475Y572500D01*
X418683Y572333D01*
X418850Y572083D01*
X418892Y571792D01*
X418850Y571542D01*
X418683Y571292D01*
X418433Y571083D01*
X418142Y571000D01*
X417808Y571083D01*
X417517Y571333D01*
X417350Y571708D01*
X417308Y572125D01*
X417392Y572667D01*
X417517Y572958D01*
X417725Y573250D01*
X418017Y573458D01*
X418308Y573500D01*
X418600Y573417D01*
X418808Y573208D01*
G01X420200Y568400D02*
X439400D01*
Y579600D01*
X420200D01*
Y568400D01*
X420600D01*
G01X440000Y504483D02*
X437500D01*
Y505317D01*
X437625Y505650D01*
X437792Y505900D01*
X438042Y506108D01*
X438333Y506275D01*
X438750Y506317D01*
X439167Y506275D01*
X439458Y506108D01*
X439708Y505900D01*
X439875Y505650D01*
X440000Y505317D01*
Y504483D01*
G01Y508500D02*
X437500D01*
X438000Y508000D01*
G01X440000D02*
Y509000D01*
G01X439625Y510683D02*
X439833Y510933D01*
X439958Y511225D01*
X440000Y511600D01*
X439917Y511975D01*
X439750Y512267D01*
X439458Y512475D01*
X439125Y512517D01*
X438792Y512433D01*
X438583Y512225D01*
X438417Y511933D01*
X438375Y511642D01*
X438417Y511350D01*
X438583Y510975D01*
X437500Y511100D01*
Y512225D01*
G01X442500Y530500D02*
Y514400D01*
G01X435500Y530500D02*
X442500D01*
G01X435500Y514400D02*
Y530500D01*
G01X442500Y514400D02*
X435500D01*
G01X446500Y530400D02*
X446458Y530067D01*
X446292Y529775D01*
X446042Y529525D01*
X445750Y529358D01*
X445417Y529275D01*
X445083D01*
X444750Y529358D01*
X444458Y529525D01*
X444208Y529775D01*
X444042Y530067D01*
X444000Y530400D01*
X444042Y530733D01*
X444208Y531025D01*
X444458Y531275D01*
X444750Y531442D01*
X445083Y531525D01*
X445417D01*
X445750Y531442D01*
X446042Y531275D01*
X446292Y531025D01*
X446458Y530733D01*
X446500Y530400D01*
G01X445833Y530733D02*
X446500Y531233D01*
G01X445458Y532708D02*
X445167Y533000D01*
X445000Y533250D01*
X444917Y533583D01*
X445000Y533875D01*
X445167Y534083D01*
X445417Y534250D01*
X445708Y534292D01*
X445958Y534250D01*
X446208Y534083D01*
X446417Y533833D01*
X446500Y533542D01*
X446417Y533208D01*
X446167Y532917D01*
X445792Y532750D01*
X445375Y532708D01*
X444833Y532792D01*
X444542Y532917D01*
X444250Y533125D01*
X444042Y533417D01*
X444000Y533708D01*
X444083Y534000D01*
X444292Y534208D01*
G01X446125Y535683D02*
X446333Y535933D01*
X446458Y536225D01*
X446500Y536600D01*
X446417Y536975D01*
X446250Y537267D01*
X445958Y537475D01*
X445625Y537517D01*
X445292Y537433D01*
X445083Y537225D01*
X444917Y536933D01*
X444875Y536642D01*
X444917Y536350D01*
X445083Y535975D01*
X444000Y536100D01*
Y537225D01*
G01X458700Y536200D02*
X447300D01*
G01X458700Y522800D02*
Y536200D01*
G01X447300Y522800D02*
X458700D01*
G01X447300Y536200D02*
Y522800D01*
G01X395267Y579953D02*
X395017Y580078D01*
X394725Y580161D01*
X394392D01*
X394017Y580036D01*
X393725Y579828D01*
X393517Y579578D01*
X393350Y579161D01*
X393308Y578786D01*
X393392Y578411D01*
X393517Y578161D01*
X393767Y577911D01*
X394058Y577744D01*
X394350Y577661D01*
X394642D01*
X394933Y577744D01*
X395183Y577869D01*
X395392Y578036D01*
G01X396658Y579744D02*
X396908Y579994D01*
X397200Y580119D01*
X397533Y580161D01*
X397950Y580078D01*
X398242Y579869D01*
X398325Y579619D01*
X398283Y579369D01*
X398117Y579161D01*
X397283Y578744D01*
X396908Y578453D01*
X396658Y578036D01*
X396575Y577661D01*
X398325D01*
G01X400550D02*
Y580161D01*
X400050Y579661D01*
G01Y577661D02*
X401050D01*
G01X403650D02*
X403942Y577703D01*
X404275Y577828D01*
X404483Y578036D01*
X404567Y578328D01*
X404483Y578619D01*
X404233Y578869D01*
X403858Y578994D01*
X403442D01*
X403192Y579078D01*
X402983Y579286D01*
X402900Y579578D01*
X403025Y579869D01*
X403317Y580078D01*
X403650Y580161D01*
X403983Y580078D01*
X404275Y579869D01*
X404400Y579578D01*
X404317Y579286D01*
X404108Y579078D01*
X403858Y578994D01*
X403442D01*
X403067Y578869D01*
X402817Y578619D01*
X402733Y578328D01*
X402817Y578036D01*
X403025Y577828D01*
X403358Y577703D01*
X403650Y577661D01*
G01X393517Y581661D02*
Y584161D01*
X394558D01*
X394892Y584036D01*
X395100Y583869D01*
X395183Y583536D01*
X395100Y583203D01*
X394850Y582994D01*
X394558Y582869D01*
X393517D01*
G01X394558D02*
X395183Y581661D01*
G01X396533Y582161D02*
X396783Y581869D01*
X397117Y581703D01*
X397492Y581661D01*
X397825Y581703D01*
X398158Y581911D01*
X398367Y582161D01*
X398408Y582411D01*
X398325Y582703D01*
X398033Y582911D01*
X397742Y582994D01*
X397367D01*
G01X397742D02*
X397992Y583119D01*
X398200Y583328D01*
X398283Y583578D01*
X398200Y583828D01*
X397992Y584036D01*
X397617Y584161D01*
X397242Y584119D01*
X396867Y583953D01*
G01X399842Y581953D02*
X400133Y581744D01*
X400467Y581661D01*
X400800Y581744D01*
X401092Y581994D01*
X401300Y582369D01*
X401383Y582744D01*
Y583203D01*
X401300Y583578D01*
X401092Y583911D01*
X400842Y584078D01*
X400550Y584161D01*
X400217Y584078D01*
X399967Y583911D01*
X399800Y583661D01*
X399717Y583328D01*
X399800Y583036D01*
X400008Y582744D01*
X400258Y582578D01*
X400550Y582536D01*
X400883Y582619D01*
X401133Y582828D01*
X401383Y583203D01*
G01X402858Y583744D02*
X403108Y583994D01*
X403400Y584119D01*
X403733Y584161D01*
X404150Y584078D01*
X404442Y583869D01*
X404525Y583619D01*
X404483Y583369D01*
X404317Y583161D01*
X403483Y582744D01*
X403108Y582453D01*
X402858Y582036D01*
X402775Y581661D01*
X404525D01*
G01X445167Y609292D02*
X444917Y609417D01*
X444625Y609500D01*
X444292D01*
X443917Y609375D01*
X443625Y609167D01*
X443417Y608917D01*
X443250Y608500D01*
X443208Y608125D01*
X443292Y607750D01*
X443417Y607500D01*
X443667Y607250D01*
X443958Y607083D01*
X444250Y607000D01*
X444542D01*
X444833Y607083D01*
X445083Y607208D01*
X445292Y607375D01*
G01X446558Y609083D02*
X446808Y609333D01*
X447100Y609458D01*
X447433Y609500D01*
X447850Y609417D01*
X448142Y609208D01*
X448225Y608958D01*
X448183Y608708D01*
X448017Y608500D01*
X447183Y608083D01*
X446808Y607792D01*
X446558Y607375D01*
X446475Y607000D01*
X448225D01*
G01X449658Y609083D02*
X449908Y609333D01*
X450200Y609458D01*
X450533Y609500D01*
X450950Y609417D01*
X451242Y609208D01*
X451325Y608958D01*
X451283Y608708D01*
X451117Y608500D01*
X450283Y608083D01*
X449908Y607792D01*
X449658Y607375D01*
X449575Y607000D01*
X451325D01*
G01X452633Y607375D02*
X452883Y607167D01*
X453175Y607042D01*
X453550Y607000D01*
X453925Y607083D01*
X454217Y607250D01*
X454425Y607542D01*
X454467Y607875D01*
X454383Y608208D01*
X454175Y608417D01*
X453883Y608583D01*
X453592Y608625D01*
X453300Y608583D01*
X452925Y608417D01*
X453050Y609500D01*
X454175D01*
G01X462208Y632767D02*
X462083Y632517D01*
X462000Y632225D01*
Y631892D01*
X462125Y631517D01*
X462333Y631225D01*
X462583Y631017D01*
X463000Y630850D01*
X463375Y630808D01*
X463750Y630892D01*
X464000Y631017D01*
X464250Y631267D01*
X464417Y631558D01*
X464500Y631850D01*
Y632142D01*
X464417Y632433D01*
X464292Y632683D01*
X464125Y632892D01*
G01X462417Y634158D02*
X462167Y634408D01*
X462042Y634700D01*
X462000Y635033D01*
X462083Y635450D01*
X462292Y635742D01*
X462542Y635825D01*
X462792Y635783D01*
X463000Y635617D01*
X463417Y634783D01*
X463708Y634408D01*
X464125Y634158D01*
X464500Y634075D01*
Y635825D01*
G01X464000Y637133D02*
X464292Y637383D01*
X464458Y637717D01*
X464500Y638092D01*
X464458Y638425D01*
X464250Y638758D01*
X464000Y638967D01*
X463750Y639008D01*
X463458Y638925D01*
X463250Y638633D01*
X463167Y638342D01*
Y637967D01*
G01Y638342D02*
X463042Y638592D01*
X462833Y638800D01*
X462583Y638883D01*
X462333Y638800D01*
X462125Y638592D01*
X462000Y638217D01*
X462042Y637842D01*
X462208Y637467D01*
G01X464500Y641150D02*
X462000D01*
X462500Y640650D01*
G01X464500D02*
Y641650D01*
G01X420300Y576000D02*
X422400Y574200D01*
X420300Y572000D01*
G01X445267Y604953D02*
X445017Y605078D01*
X444725Y605161D01*
X444392D01*
X444017Y605036D01*
X443725Y604828D01*
X443517Y604578D01*
X443350Y604161D01*
X443308Y603786D01*
X443392Y603411D01*
X443517Y603161D01*
X443767Y602911D01*
X444058Y602744D01*
X444350Y602661D01*
X444642D01*
X444933Y602744D01*
X445183Y602869D01*
X445392Y603036D01*
G01X446658Y604744D02*
X446908Y604994D01*
X447200Y605119D01*
X447533Y605161D01*
X447950Y605078D01*
X448242Y604869D01*
X448325Y604619D01*
X448283Y604369D01*
X448117Y604161D01*
X447283Y603744D01*
X446908Y603453D01*
X446658Y603036D01*
X446575Y602661D01*
X448325D01*
G01X449758Y604744D02*
X450008Y604994D01*
X450300Y605119D01*
X450633Y605161D01*
X451050Y605078D01*
X451342Y604869D01*
X451425Y604619D01*
X451383Y604369D01*
X451217Y604161D01*
X450383Y603744D01*
X450008Y603453D01*
X449758Y603036D01*
X449675Y602661D01*
X451425D01*
G01X452858Y603703D02*
X453150Y603994D01*
X453400Y604161D01*
X453733Y604244D01*
X454025Y604161D01*
X454233Y603994D01*
X454400Y603744D01*
X454442Y603453D01*
X454400Y603203D01*
X454233Y602953D01*
X453983Y602744D01*
X453692Y602661D01*
X453358Y602744D01*
X453067Y602994D01*
X452900Y603369D01*
X452858Y603786D01*
X452942Y604328D01*
X453067Y604619D01*
X453275Y604911D01*
X453567Y605119D01*
X453858Y605161D01*
X454150Y605078D01*
X454358Y604869D01*
G01X460300Y574500D02*
X454800D01*
G01X460300Y582500D02*
Y574500D01*
G01X454800Y582500D02*
X460300D01*
G01X442700D02*
X448200D01*
G01X442700Y574500D02*
Y582500D01*
G01X448200Y574500D02*
X442700D01*
G01X467000Y594017D02*
X464500D01*
Y595058D01*
X464625Y595392D01*
X464792Y595600D01*
X465125Y595683D01*
X465458Y595600D01*
X465667Y595350D01*
X465792Y595058D01*
Y594017D01*
G01Y595058D02*
X467000Y595683D01*
G01Y598450D02*
X464500D01*
X466292Y596908D01*
Y598992D01*
G01X467000Y601050D02*
X464500D01*
X465000Y600550D01*
G01X467000D02*
Y601550D01*
G01Y604650D02*
X464500D01*
X466292Y603108D01*
Y605192D01*
G01X462000Y592300D02*
X470000D01*
Y574700D01*
X462000D01*
Y592300D01*
G01X443517Y611000D02*
Y613500D01*
X444558D01*
X444892Y613375D01*
X445100Y613208D01*
X445183Y612875D01*
X445100Y612542D01*
X444850Y612333D01*
X444558Y612208D01*
X443517D01*
G01X444558D02*
X445183Y611000D01*
G01X447950D02*
Y613500D01*
X446408Y611708D01*
X448492D01*
G01X450550Y611000D02*
Y613500D01*
X450050Y613000D01*
G01Y611000D02*
X451050D01*
G01X452858Y612042D02*
X453150Y612333D01*
X453400Y612500D01*
X453733Y612583D01*
X454025Y612500D01*
X454233Y612333D01*
X454400Y612083D01*
X454442Y611792D01*
X454400Y611542D01*
X454233Y611292D01*
X453983Y611083D01*
X453692Y611000D01*
X453358Y611083D01*
X453067Y611333D01*
X452900Y611708D01*
X452858Y612125D01*
X452942Y612667D01*
X453067Y612958D01*
X453275Y613250D01*
X453567Y613458D01*
X453858Y613500D01*
X454150Y613417D01*
X454358Y613208D01*
G01X438200Y589000D02*
Y597000D01*
X455800D01*
Y589000D01*
X438200D01*
G01X426767Y600792D02*
X426517Y600917D01*
X426225Y601000D01*
X425892D01*
X425517Y600875D01*
X425225Y600667D01*
X425017Y600417D01*
X424850Y600000D01*
X424808Y599625D01*
X424892Y599250D01*
X425017Y599000D01*
X425267Y598750D01*
X425558Y598583D01*
X425850Y598500D01*
X426142D01*
X426433Y598583D01*
X426683Y598708D01*
X426892Y598875D01*
G01X428158Y600583D02*
X428408Y600833D01*
X428700Y600958D01*
X429033Y601000D01*
X429450Y600917D01*
X429742Y600708D01*
X429825Y600458D01*
X429783Y600208D01*
X429617Y600000D01*
X428783Y599583D01*
X428408Y599292D01*
X428158Y598875D01*
X428075Y598500D01*
X429825D01*
G01X431258Y600583D02*
X431508Y600833D01*
X431800Y600958D01*
X432133Y601000D01*
X432550Y600917D01*
X432842Y600708D01*
X432925Y600458D01*
X432883Y600208D01*
X432717Y600000D01*
X431883Y599583D01*
X431508Y599292D01*
X431258Y598875D01*
X431175Y598500D01*
X432925D01*
G01X434442Y598792D02*
X434733Y598583D01*
X435067Y598500D01*
X435400Y598583D01*
X435692Y598833D01*
X435900Y599208D01*
X435983Y599583D01*
Y600042D01*
X435900Y600417D01*
X435692Y600750D01*
X435442Y600917D01*
X435150Y601000D01*
X434817Y600917D01*
X434567Y600750D01*
X434400Y600500D01*
X434317Y600167D01*
X434400Y599875D01*
X434608Y599583D01*
X434858Y599417D01*
X435150Y599375D01*
X435483Y599458D01*
X435733Y599667D01*
X435983Y600042D01*
G01X460208Y619767D02*
X460083Y619517D01*
X460000Y619225D01*
Y618892D01*
X460125Y618517D01*
X460333Y618225D01*
X460583Y618017D01*
X461000Y617850D01*
X461375Y617808D01*
X461750Y617892D01*
X462000Y618017D01*
X462250Y618267D01*
X462417Y618558D01*
X462500Y618850D01*
Y619142D01*
X462417Y619433D01*
X462292Y619683D01*
X462125Y619892D01*
G01X460417Y621158D02*
X460167Y621408D01*
X460042Y621700D01*
X460000Y622033D01*
X460083Y622450D01*
X460292Y622742D01*
X460542Y622825D01*
X460792Y622783D01*
X461000Y622617D01*
X461417Y621783D01*
X461708Y621408D01*
X462125Y621158D01*
X462500Y621075D01*
Y622825D01*
G01X462000Y624133D02*
X462292Y624383D01*
X462458Y624717D01*
X462500Y625092D01*
X462458Y625425D01*
X462250Y625758D01*
X462000Y625967D01*
X461750Y626008D01*
X461458Y625925D01*
X461250Y625633D01*
X461167Y625342D01*
Y624967D01*
G01Y625342D02*
X461042Y625592D01*
X460833Y625800D01*
X460583Y625883D01*
X460333Y625800D01*
X460125Y625592D01*
X460000Y625217D01*
X460042Y624842D01*
X460208Y624467D01*
G01X460000Y628150D02*
X460083Y627817D01*
X460292Y627567D01*
X460542Y627400D01*
X460875Y627275D01*
X461250Y627233D01*
X461625Y627275D01*
X461958Y627400D01*
X462208Y627567D01*
X462417Y627817D01*
X462500Y628150D01*
X462417Y628483D01*
X462208Y628733D01*
X461958Y628900D01*
X461625Y629025D01*
X461250Y629067D01*
X460875Y629025D01*
X460542Y628900D01*
X460292Y628733D01*
X460083Y628483D01*
X460000Y628150D01*
G01X434616Y720454D02*
Y717954D01*
X436282D01*
G01X439382D02*
X437716D01*
Y720454D01*
X439382D01*
G01X438716Y719246D02*
X437716D01*
G01X440732Y717954D02*
Y720454D01*
X441566D01*
X441899Y720329D01*
X442149Y720162D01*
X442357Y719912D01*
X442524Y719621D01*
X442566Y719204D01*
X442524Y718787D01*
X442357Y718496D01*
X442149Y718246D01*
X441899Y718079D01*
X441566Y717954D01*
X440732D01*
G01X445249D02*
Y720454D01*
X443707Y718662D01*
X445791D01*
G01X438317Y704636D02*
Y715836D01*
X447117D01*
Y704636D01*
X438317D01*
G01X400517Y834500D02*
Y837000D01*
X401558D01*
X401892Y836875D01*
X402100Y836708D01*
X402183Y836375D01*
X402100Y836042D01*
X401850Y835833D01*
X401558Y835708D01*
X400517D01*
G01X401558D02*
X402183Y834500D01*
G01X404450D02*
Y837000D01*
X403950Y836500D01*
G01Y834500D02*
X404950D01*
G01X406842Y834792D02*
X407133Y834583D01*
X407467Y834500D01*
X407800Y834583D01*
X408092Y834833D01*
X408300Y835208D01*
X408383Y835583D01*
Y836042D01*
X408300Y836417D01*
X408092Y836750D01*
X407842Y836917D01*
X407550Y837000D01*
X407217Y836917D01*
X406967Y836750D01*
X406800Y836500D01*
X406717Y836167D01*
X406800Y835875D01*
X407008Y835583D01*
X407258Y835417D01*
X407550Y835375D01*
X407883Y835458D01*
X408133Y835667D01*
X408383Y836042D01*
G01X410567Y834500D02*
X410650Y835042D01*
X410775Y835500D01*
X410942Y835917D01*
X411150Y836375D01*
X411483Y837000D01*
X409817D01*
G01X420692Y833876D02*
Y837876D01*
X413292D01*
G01X435425Y853659D02*
Y857659D01*
X428025D01*
G01X445800Y852717D02*
X443300D01*
Y853758D01*
X443425Y854092D01*
X443592Y854300D01*
X443925Y854383D01*
X444258Y854300D01*
X444467Y854050D01*
X444592Y853758D01*
Y852717D01*
G01Y853758D02*
X445800Y854383D01*
G01X443717Y855858D02*
X443467Y856108D01*
X443342Y856400D01*
X443300Y856733D01*
X443383Y857150D01*
X443592Y857442D01*
X443842Y857525D01*
X444092Y857483D01*
X444300Y857317D01*
X444717Y856483D01*
X445008Y856108D01*
X445425Y855858D01*
X445800Y855775D01*
Y857525D01*
G01X445425Y858833D02*
X445633Y859083D01*
X445758Y859375D01*
X445800Y859750D01*
X445717Y860125D01*
X445550Y860417D01*
X445258Y860625D01*
X444925Y860667D01*
X444592Y860583D01*
X444383Y860375D01*
X444217Y860083D01*
X444175Y859792D01*
X444217Y859500D01*
X444383Y859125D01*
X443300Y859250D01*
Y860375D01*
G01X443717Y862058D02*
X443467Y862308D01*
X443342Y862600D01*
X443300Y862933D01*
X443383Y863350D01*
X443592Y863642D01*
X443842Y863725D01*
X444092Y863683D01*
X444300Y863517D01*
X444717Y862683D01*
X445008Y862308D01*
X445425Y862058D01*
X445800Y861975D01*
Y863725D01*
G01X441800Y852717D02*
X439300D01*
Y853758D01*
X439425Y854092D01*
X439592Y854300D01*
X439925Y854383D01*
X440258Y854300D01*
X440467Y854050D01*
X440592Y853758D01*
Y852717D01*
G01Y853758D02*
X441800Y854383D01*
G01X439717Y855858D02*
X439467Y856108D01*
X439342Y856400D01*
X439300Y856733D01*
X439383Y857150D01*
X439592Y857442D01*
X439842Y857525D01*
X440092Y857483D01*
X440300Y857317D01*
X440717Y856483D01*
X441008Y856108D01*
X441425Y855858D01*
X441800Y855775D01*
Y857525D01*
G01X441425Y858833D02*
X441633Y859083D01*
X441758Y859375D01*
X441800Y859750D01*
X441717Y860125D01*
X441550Y860417D01*
X441258Y860625D01*
X440925Y860667D01*
X440592Y860583D01*
X440383Y860375D01*
X440217Y860083D01*
X440175Y859792D01*
X440217Y859500D01*
X440383Y859125D01*
X439300Y859250D01*
Y860375D01*
G01X441300Y861933D02*
X441592Y862183D01*
X441758Y862517D01*
X441800Y862892D01*
X441758Y863225D01*
X441550Y863558D01*
X441300Y863767D01*
X441050Y863808D01*
X440758Y863725D01*
X440550Y863433D01*
X440467Y863142D01*
Y862767D01*
G01Y863142D02*
X440342Y863392D01*
X440133Y863600D01*
X439883Y863683D01*
X439633Y863600D01*
X439425Y863392D01*
X439300Y863017D01*
X439342Y862642D01*
X439508Y862267D01*
G01X427350Y834000D02*
X427017Y834042D01*
X426725Y834208D01*
X426475Y834458D01*
X426308Y834750D01*
X426225Y835083D01*
Y835417D01*
X426308Y835750D01*
X426475Y836042D01*
X426725Y836292D01*
X427017Y836458D01*
X427350Y836500D01*
X427683Y836458D01*
X427975Y836292D01*
X428225Y836042D01*
X428392Y835750D01*
X428475Y835417D01*
Y835083D01*
X428392Y834750D01*
X428225Y834458D01*
X427975Y834208D01*
X427683Y834042D01*
X427350Y834000D01*
G01X427683Y834667D02*
X428183Y834000D01*
G01X429658Y836083D02*
X429908Y836333D01*
X430200Y836458D01*
X430533Y836500D01*
X430950Y836417D01*
X431242Y836208D01*
X431325Y835958D01*
X431283Y835708D01*
X431117Y835500D01*
X430283Y835083D01*
X429908Y834792D01*
X429658Y834375D01*
X429575Y834000D01*
X431325D01*
G01X432758Y836083D02*
X433008Y836333D01*
X433300Y836458D01*
X433633Y836500D01*
X434050Y836417D01*
X434342Y836208D01*
X434425Y835958D01*
X434383Y835708D01*
X434217Y835500D01*
X433383Y835083D01*
X433008Y834792D01*
X432758Y834375D01*
X432675Y834000D01*
X434425D01*
G01X435858Y836083D02*
X436108Y836333D01*
X436400Y836458D01*
X436733Y836500D01*
X437150Y836417D01*
X437442Y836208D01*
X437525Y835958D01*
X437483Y835708D01*
X437317Y835500D01*
X436483Y835083D01*
X436108Y834792D01*
X435858Y834375D01*
X435775Y834000D01*
X437525D01*
G01X436100Y838300D02*
Y852300D01*
G01X423100Y838300D02*
X436100D01*
G01X423100Y852300D02*
Y838300D01*
G01X436100Y852300D02*
X423100D01*
G01X408050Y855800D02*
X407717Y855842D01*
X407425Y856008D01*
X407175Y856258D01*
X407008Y856550D01*
X406925Y856883D01*
Y857217D01*
X407008Y857550D01*
X407175Y857842D01*
X407425Y858092D01*
X407717Y858258D01*
X408050Y858300D01*
X408383Y858258D01*
X408675Y858092D01*
X408925Y857842D01*
X409092Y857550D01*
X409175Y857217D01*
Y856883D01*
X409092Y856550D01*
X408925Y856258D01*
X408675Y856008D01*
X408383Y855842D01*
X408050Y855800D01*
G01X408383Y856467D02*
X408883Y855800D01*
G01X410358Y857883D02*
X410608Y858133D01*
X410900Y858258D01*
X411233Y858300D01*
X411650Y858217D01*
X411942Y858008D01*
X412025Y857758D01*
X411983Y857508D01*
X411817Y857300D01*
X410983Y856883D01*
X410608Y856592D01*
X410358Y856175D01*
X410275Y855800D01*
X412025D01*
G01X414750D02*
Y858300D01*
X413208Y856508D01*
X415292D01*
G01X416558Y856842D02*
X416850Y857133D01*
X417100Y857300D01*
X417433Y857383D01*
X417725Y857300D01*
X417933Y857133D01*
X418100Y856883D01*
X418142Y856592D01*
X418100Y856342D01*
X417933Y856092D01*
X417683Y855883D01*
X417392Y855800D01*
X417058Y855883D01*
X416767Y856133D01*
X416600Y856508D01*
X416558Y856925D01*
X416642Y857467D01*
X416767Y857758D01*
X416975Y858050D01*
X417267Y858258D01*
X417558Y858300D01*
X417850Y858217D01*
X418058Y858008D01*
G01X407992Y839107D02*
X421992D01*
G01X407992Y852107D02*
Y839107D01*
G01X421992Y852107D02*
X407992D01*
G01X421992Y839107D02*
Y852107D01*
G01X466761Y1012831D02*
X471811D01*
Y1111531D01*
X496461D01*
Y927131D01*
X471811D01*
Y985831D01*
X466761D01*
Y1012831D01*
G01X421517Y858500D02*
Y861000D01*
X422558D01*
X422892Y860875D01*
X423100Y860708D01*
X423183Y860375D01*
X423100Y860042D01*
X422850Y859833D01*
X422558Y859708D01*
X421517D01*
G01X422558D02*
X423183Y858500D01*
G01X425450D02*
Y861000D01*
X424950Y860500D01*
G01Y858500D02*
X425950D01*
G01X427842Y858792D02*
X428133Y858583D01*
X428467Y858500D01*
X428800Y858583D01*
X429092Y858833D01*
X429300Y859208D01*
X429383Y859583D01*
Y860042D01*
X429300Y860417D01*
X429092Y860750D01*
X428842Y860917D01*
X428550Y861000D01*
X428217Y860917D01*
X427967Y860750D01*
X427800Y860500D01*
X427717Y860167D01*
X427800Y859875D01*
X428008Y859583D01*
X428258Y859417D01*
X428550Y859375D01*
X428883Y859458D01*
X429133Y859667D01*
X429383Y860042D01*
G01X432150Y858500D02*
Y861000D01*
X430608Y859208D01*
X432692D01*
G01X395317Y1032792D02*
X395067Y1032917D01*
X394775Y1033000D01*
X394442D01*
X394067Y1032875D01*
X393775Y1032667D01*
X393567Y1032417D01*
X393400Y1032000D01*
X393358Y1031625D01*
X393442Y1031250D01*
X393567Y1031000D01*
X393817Y1030750D01*
X394108Y1030583D01*
X394400Y1030500D01*
X394692D01*
X394983Y1030583D01*
X395233Y1030708D01*
X395442Y1030875D01*
G01X396708Y1031542D02*
X397000Y1031833D01*
X397250Y1032000D01*
X397583Y1032083D01*
X397875Y1032000D01*
X398083Y1031833D01*
X398250Y1031583D01*
X398292Y1031292D01*
X398250Y1031042D01*
X398083Y1030792D01*
X397833Y1030583D01*
X397542Y1030500D01*
X397208Y1030583D01*
X396917Y1030833D01*
X396750Y1031208D01*
X396708Y1031625D01*
X396792Y1032167D01*
X396917Y1032458D01*
X397125Y1032750D01*
X397417Y1032958D01*
X397708Y1033000D01*
X398000Y1032917D01*
X398208Y1032708D01*
G01X399683Y1031000D02*
X399933Y1030708D01*
X400267Y1030542D01*
X400642Y1030500D01*
X400975Y1030542D01*
X401308Y1030750D01*
X401517Y1031000D01*
X401558Y1031250D01*
X401475Y1031542D01*
X401183Y1031750D01*
X400892Y1031833D01*
X400517D01*
G01X400892D02*
X401142Y1031958D01*
X401350Y1032167D01*
X401433Y1032417D01*
X401350Y1032667D01*
X401142Y1032875D01*
X400767Y1033000D01*
X400392Y1032958D01*
X400017Y1032792D01*
G01X416317Y1007792D02*
X416067Y1007917D01*
X415775Y1008000D01*
X415442D01*
X415067Y1007875D01*
X414775Y1007667D01*
X414567Y1007417D01*
X414400Y1007000D01*
X414358Y1006625D01*
X414442Y1006250D01*
X414567Y1006000D01*
X414817Y1005750D01*
X415108Y1005583D01*
X415400Y1005500D01*
X415692D01*
X415983Y1005583D01*
X416233Y1005708D01*
X416442Y1005875D01*
G01X418417Y1005500D02*
X418500Y1006042D01*
X418625Y1006500D01*
X418792Y1006917D01*
X419000Y1007375D01*
X419333Y1008000D01*
X417667D01*
G01X421600Y1005500D02*
X421892Y1005542D01*
X422225Y1005667D01*
X422433Y1005875D01*
X422517Y1006167D01*
X422433Y1006458D01*
X422183Y1006708D01*
X421808Y1006833D01*
X421392D01*
X421142Y1006917D01*
X420933Y1007125D01*
X420850Y1007417D01*
X420975Y1007708D01*
X421267Y1007917D01*
X421600Y1008000D01*
X421933Y1007917D01*
X422225Y1007708D01*
X422350Y1007417D01*
X422267Y1007125D01*
X422058Y1006917D01*
X421808Y1006833D01*
X421392D01*
X421017Y1006708D01*
X420767Y1006458D01*
X420683Y1006167D01*
X420767Y1005875D01*
X420975Y1005667D01*
X421308Y1005542D01*
X421600Y1005500D01*
G01X425317Y998292D02*
X425067Y998417D01*
X424775Y998500D01*
X424442D01*
X424067Y998375D01*
X423775Y998167D01*
X423567Y997917D01*
X423400Y997500D01*
X423358Y997125D01*
X423442Y996750D01*
X423567Y996500D01*
X423817Y996250D01*
X424108Y996083D01*
X424400Y996000D01*
X424692D01*
X424983Y996083D01*
X425233Y996208D01*
X425442Y996375D01*
G01X427417Y996000D02*
X427500Y996542D01*
X427625Y997000D01*
X427792Y997417D01*
X428000Y997875D01*
X428333Y998500D01*
X426667D01*
G01X430517Y996000D02*
X430600Y996542D01*
X430725Y997000D01*
X430892Y997417D01*
X431100Y997875D01*
X431433Y998500D01*
X429767D01*
G01X393517Y1035161D02*
Y1037661D01*
X394558D01*
X394892Y1037536D01*
X395100Y1037369D01*
X395183Y1037036D01*
X395100Y1036703D01*
X394850Y1036494D01*
X394558Y1036369D01*
X393517D01*
G01X394558D02*
X395183Y1035161D01*
G01X397450D02*
Y1037661D01*
X396950Y1037161D01*
G01Y1035161D02*
X397950D01*
G01X399842Y1035453D02*
X400133Y1035244D01*
X400467Y1035161D01*
X400800Y1035244D01*
X401092Y1035494D01*
X401300Y1035869D01*
X401383Y1036244D01*
Y1036703D01*
X401300Y1037078D01*
X401092Y1037411D01*
X400842Y1037578D01*
X400550Y1037661D01*
X400217Y1037578D01*
X399967Y1037411D01*
X399800Y1037161D01*
X399717Y1036828D01*
X399800Y1036536D01*
X400008Y1036244D01*
X400258Y1036078D01*
X400550Y1036036D01*
X400883Y1036119D01*
X401133Y1036328D01*
X401383Y1036703D01*
G01X403650Y1035161D02*
Y1037661D01*
X403150Y1037161D01*
G01Y1035161D02*
X404150D01*
G01X422517Y964500D02*
Y967000D01*
X423558D01*
X423892Y966875D01*
X424100Y966708D01*
X424183Y966375D01*
X424100Y966042D01*
X423850Y965833D01*
X423558Y965708D01*
X422517D01*
G01X423558D02*
X424183Y964500D01*
G01X425658Y966583D02*
X425908Y966833D01*
X426200Y966958D01*
X426533Y967000D01*
X426950Y966917D01*
X427242Y966708D01*
X427325Y966458D01*
X427283Y966208D01*
X427117Y966000D01*
X426283Y965583D01*
X425908Y965292D01*
X425658Y964875D01*
X425575Y964500D01*
X427325D01*
G01X429550D02*
Y967000D01*
X429050Y966500D01*
G01Y964500D02*
X430050D01*
G01X431858Y965542D02*
X432150Y965833D01*
X432400Y966000D01*
X432733Y966083D01*
X433025Y966000D01*
X433233Y965833D01*
X433400Y965583D01*
X433442Y965292D01*
X433400Y965042D01*
X433233Y964792D01*
X432983Y964583D01*
X432692Y964500D01*
X432358Y964583D01*
X432067Y964833D01*
X431900Y965208D01*
X431858Y965625D01*
X431942Y966167D01*
X432067Y966458D01*
X432275Y966750D01*
X432567Y966958D01*
X432858Y967000D01*
X433150Y966917D01*
X433358Y966708D01*
G01X427300Y973000D02*
Y969000D01*
X434700D01*
G01X414517Y1001161D02*
Y1003661D01*
X415558D01*
X415892Y1003536D01*
X416100Y1003369D01*
X416183Y1003036D01*
X416100Y1002703D01*
X415850Y1002494D01*
X415558Y1002369D01*
X414517D01*
G01X415558D02*
X416183Y1001161D01*
G01X417658Y1003244D02*
X417908Y1003494D01*
X418200Y1003619D01*
X418533Y1003661D01*
X418950Y1003578D01*
X419242Y1003369D01*
X419325Y1003119D01*
X419283Y1002869D01*
X419117Y1002661D01*
X418283Y1002244D01*
X417908Y1001953D01*
X417658Y1001536D01*
X417575Y1001161D01*
X419325D01*
G01X421550D02*
Y1003661D01*
X421050Y1003161D01*
G01Y1001161D02*
X422050D01*
G01X424567D02*
X424650Y1001703D01*
X424775Y1002161D01*
X424942Y1002578D01*
X425150Y1003036D01*
X425483Y1003661D01*
X423817D01*
G01X434700Y1000000D02*
Y1004000D01*
X427300D01*
G01X424500Y974017D02*
X422000D01*
Y975058D01*
X422125Y975392D01*
X422292Y975600D01*
X422625Y975683D01*
X422958Y975600D01*
X423167Y975350D01*
X423292Y975058D01*
Y974017D01*
G01Y975058D02*
X424500Y975683D01*
G01X422417Y977158D02*
X422167Y977408D01*
X422042Y977700D01*
X422000Y978033D01*
X422083Y978450D01*
X422292Y978742D01*
X422542Y978825D01*
X422792Y978783D01*
X423000Y978617D01*
X423417Y977783D01*
X423708Y977408D01*
X424125Y977158D01*
X424500Y977075D01*
Y978825D01*
G01Y981050D02*
X422000D01*
X422500Y980550D01*
G01X424500D02*
Y981550D01*
G01Y984150D02*
X424458Y984442D01*
X424333Y984775D01*
X424125Y984983D01*
X423833Y985067D01*
X423542Y984983D01*
X423292Y984733D01*
X423167Y984358D01*
Y983942D01*
X423083Y983692D01*
X422875Y983483D01*
X422583Y983400D01*
X422292Y983525D01*
X422083Y983817D01*
X422000Y984150D01*
X422083Y984483D01*
X422292Y984775D01*
X422583Y984900D01*
X422875Y984817D01*
X423083Y984608D01*
X423167Y984358D01*
Y983942D01*
X423292Y983567D01*
X423542Y983317D01*
X423833Y983233D01*
X424125Y983317D01*
X424333Y983525D01*
X424458Y983858D01*
X424500Y984150D01*
G01X430500Y973300D02*
X434500D01*
Y980700D01*
G01X446000Y954517D02*
X443500D01*
Y955558D01*
X443625Y955892D01*
X443792Y956100D01*
X444125Y956183D01*
X444458Y956100D01*
X444667Y955850D01*
X444792Y955558D01*
Y954517D01*
G01Y955558D02*
X446000Y956183D01*
G01X443917Y957658D02*
X443667Y957908D01*
X443542Y958200D01*
X443500Y958533D01*
X443583Y958950D01*
X443792Y959242D01*
X444042Y959325D01*
X444292Y959283D01*
X444500Y959117D01*
X444917Y958283D01*
X445208Y957908D01*
X445625Y957658D01*
X446000Y957575D01*
Y959325D01*
G01Y961550D02*
X443500D01*
X444000Y961050D01*
G01X446000D02*
Y962050D01*
G01X445708Y963942D02*
X445917Y964233D01*
X446000Y964567D01*
X445917Y964900D01*
X445667Y965192D01*
X445292Y965400D01*
X444917Y965483D01*
X444458D01*
X444083Y965400D01*
X443750Y965192D01*
X443583Y964942D01*
X443500Y964650D01*
X443583Y964317D01*
X443750Y964067D01*
X444000Y963900D01*
X444333Y963817D01*
X444625Y963900D01*
X444917Y964108D01*
X445083Y964358D01*
X445125Y964650D01*
X445042Y964983D01*
X444833Y965233D01*
X444458Y965483D01*
G01X447000Y974700D02*
X443000D01*
Y967300D01*
G01X456517Y953500D02*
Y956000D01*
X457558D01*
X457892Y955875D01*
X458100Y955708D01*
X458183Y955375D01*
X458100Y955042D01*
X457850Y954833D01*
X457558Y954708D01*
X456517D01*
G01X457558D02*
X458183Y953500D01*
G01X459658Y955583D02*
X459908Y955833D01*
X460200Y955958D01*
X460533Y956000D01*
X460950Y955917D01*
X461242Y955708D01*
X461325Y955458D01*
X461283Y955208D01*
X461117Y955000D01*
X460283Y954583D01*
X459908Y954292D01*
X459658Y953875D01*
X459575Y953500D01*
X461325D01*
G01X463550D02*
Y956000D01*
X463050Y955500D01*
G01Y953500D02*
X464050D01*
G01X467150D02*
Y956000D01*
X465608Y954208D01*
X467692D01*
G01X464600Y967200D02*
Y971200D01*
X457200D01*
G01X456517Y957500D02*
Y960000D01*
X457558D01*
X457892Y959875D01*
X458100Y959708D01*
X458183Y959375D01*
X458100Y959042D01*
X457850Y958833D01*
X457558Y958708D01*
X456517D01*
G01X457558D02*
X458183Y957500D01*
G01X459658Y959583D02*
X459908Y959833D01*
X460200Y959958D01*
X460533Y960000D01*
X460950Y959917D01*
X461242Y959708D01*
X461325Y959458D01*
X461283Y959208D01*
X461117Y959000D01*
X460283Y958583D01*
X459908Y958292D01*
X459658Y957875D01*
X459575Y957500D01*
X461325D01*
G01X463550D02*
Y960000D01*
X463050Y959500D01*
G01Y957500D02*
X464050D01*
G01X465858Y959583D02*
X466108Y959833D01*
X466400Y959958D01*
X466733Y960000D01*
X467150Y959917D01*
X467442Y959708D01*
X467525Y959458D01*
X467483Y959208D01*
X467317Y959000D01*
X466483Y958583D01*
X466108Y958292D01*
X465858Y957875D01*
X465775Y957500D01*
X467525D01*
G01X466600Y976000D02*
Y980000D01*
X459200D01*
G01X456517Y961500D02*
Y964000D01*
X457558D01*
X457892Y963875D01*
X458100Y963708D01*
X458183Y963375D01*
X458100Y963042D01*
X457850Y962833D01*
X457558Y962708D01*
X456517D01*
G01X457558D02*
X458183Y961500D01*
G01X459658Y963583D02*
X459908Y963833D01*
X460200Y963958D01*
X460533Y964000D01*
X460950Y963917D01*
X461242Y963708D01*
X461325Y963458D01*
X461283Y963208D01*
X461117Y963000D01*
X460283Y962583D01*
X459908Y962292D01*
X459658Y961875D01*
X459575Y961500D01*
X461325D01*
G01X463550D02*
Y964000D01*
X463050Y963500D01*
G01Y961500D02*
X464050D01*
G01X465733Y961875D02*
X465983Y961667D01*
X466275Y961542D01*
X466650Y961500D01*
X467025Y961583D01*
X467317Y961750D01*
X467525Y962042D01*
X467567Y962375D01*
X467483Y962708D01*
X467275Y962917D01*
X466983Y963083D01*
X466692Y963125D01*
X466400Y963083D01*
X466025Y962917D01*
X466150Y964000D01*
X467275D01*
G01X459300Y984500D02*
Y980500D01*
X466700D01*
G01X423517Y991661D02*
Y994161D01*
X424558D01*
X424892Y994036D01*
X425100Y993869D01*
X425183Y993536D01*
X425100Y993203D01*
X424850Y992994D01*
X424558Y992869D01*
X423517D01*
G01X424558D02*
X425183Y991661D01*
G01X426658Y993744D02*
X426908Y993994D01*
X427200Y994119D01*
X427533Y994161D01*
X427950Y994078D01*
X428242Y993869D01*
X428325Y993619D01*
X428283Y993369D01*
X428117Y993161D01*
X427283Y992744D01*
X426908Y992453D01*
X426658Y992036D01*
X426575Y991661D01*
X428325D01*
G01X430550D02*
Y994161D01*
X430050Y993661D01*
G01Y991661D02*
X431050D01*
G01X433650D02*
Y994161D01*
X433150Y993661D01*
G01Y991661D02*
X434150D01*
G01X434800Y998500D02*
Y994500D01*
X442200D01*
G01X451900Y1024000D02*
X451567Y1024042D01*
X451275Y1024208D01*
X451025Y1024458D01*
X450858Y1024750D01*
X450775Y1025083D01*
Y1025417D01*
X450858Y1025750D01*
X451025Y1026042D01*
X451275Y1026292D01*
X451567Y1026458D01*
X451900Y1026500D01*
X452233Y1026458D01*
X452525Y1026292D01*
X452775Y1026042D01*
X452942Y1025750D01*
X453025Y1025417D01*
Y1025083D01*
X452942Y1024750D01*
X452775Y1024458D01*
X452525Y1024208D01*
X452233Y1024042D01*
X451900Y1024000D01*
G01X452233Y1024667D02*
X452733Y1024000D01*
G01X455000D02*
Y1026500D01*
X454500Y1026000D01*
G01Y1024000D02*
X455500D01*
G01X458100Y1026500D02*
X457767Y1026417D01*
X457517Y1026208D01*
X457350Y1025958D01*
X457225Y1025625D01*
X457183Y1025250D01*
X457225Y1024875D01*
X457350Y1024542D01*
X457517Y1024292D01*
X457767Y1024083D01*
X458100Y1024000D01*
X458433Y1024083D01*
X458683Y1024292D01*
X458850Y1024542D01*
X458975Y1024875D01*
X459017Y1025250D01*
X458975Y1025625D01*
X458850Y1025958D01*
X458683Y1026208D01*
X458433Y1026417D01*
X458100Y1026500D01*
G01X464700Y1007000D02*
X462600Y1008800D01*
X464700Y1011000D01*
G01X464800Y1014600D02*
X445600D01*
Y1003400D01*
X464800D01*
Y1014600D01*
X464400D01*
G01X411900Y1026500D02*
X411567Y1026542D01*
X411275Y1026708D01*
X411025Y1026958D01*
X410858Y1027250D01*
X410775Y1027583D01*
Y1027917D01*
X410858Y1028250D01*
X411025Y1028542D01*
X411275Y1028792D01*
X411567Y1028958D01*
X411900Y1029000D01*
X412233Y1028958D01*
X412525Y1028792D01*
X412775Y1028542D01*
X412942Y1028250D01*
X413025Y1027917D01*
Y1027583D01*
X412942Y1027250D01*
X412775Y1026958D01*
X412525Y1026708D01*
X412233Y1026542D01*
X411900Y1026500D01*
G01X412233Y1027167D02*
X412733Y1026500D01*
G01X415000D02*
Y1029000D01*
X414500Y1028500D01*
G01Y1026500D02*
X415500D01*
G01X417308Y1028583D02*
X417558Y1028833D01*
X417850Y1028958D01*
X418183Y1029000D01*
X418600Y1028917D01*
X418892Y1028708D01*
X418975Y1028458D01*
X418933Y1028208D01*
X418767Y1028000D01*
X417933Y1027583D01*
X417558Y1027292D01*
X417308Y1026875D01*
X417225Y1026500D01*
X418975D01*
G01X420300Y1029000D02*
X422400Y1027200D01*
X420300Y1025000D01*
G01X420200Y1021400D02*
X439400D01*
Y1032600D01*
X420200D01*
Y1021400D01*
X420600D01*
G01X460300Y1027500D02*
X454800D01*
G01X460300Y1035500D02*
Y1027500D01*
G01X454800Y1035500D02*
X460300D01*
G01X442700D02*
X448200D01*
G01X442700Y1027500D02*
Y1035500D01*
G01X448200Y1027500D02*
X442700D01*
G01X440000Y960033D02*
X437500D01*
Y960867D01*
X437625Y961200D01*
X437792Y961450D01*
X438042Y961658D01*
X438333Y961825D01*
X438750Y961867D01*
X439167Y961825D01*
X439458Y961658D01*
X439708Y961450D01*
X439875Y961200D01*
X440000Y960867D01*
Y960033D01*
G01X439500Y963133D02*
X439792Y963383D01*
X439958Y963717D01*
X440000Y964092D01*
X439958Y964425D01*
X439750Y964758D01*
X439500Y964967D01*
X439250Y965008D01*
X438958Y964925D01*
X438750Y964633D01*
X438667Y964342D01*
Y963967D01*
G01Y964342D02*
X438542Y964592D01*
X438333Y964800D01*
X438083Y964883D01*
X437833Y964800D01*
X437625Y964592D01*
X437500Y964217D01*
X437542Y963842D01*
X437708Y963467D01*
G01X442500Y983500D02*
Y967400D01*
G01X435500Y983500D02*
X442500D01*
G01X435500Y967400D02*
Y983500D01*
G01X442500Y967400D02*
X435500D01*
G01X446234Y981800D02*
X446192Y981467D01*
X446026Y981175D01*
X445776Y980925D01*
X445484Y980758D01*
X445151Y980675D01*
X444817D01*
X444484Y980758D01*
X444192Y980925D01*
X443942Y981175D01*
X443776Y981467D01*
X443734Y981800D01*
X443776Y982133D01*
X443942Y982425D01*
X444192Y982675D01*
X444484Y982842D01*
X444817Y982925D01*
X445151D01*
X445484Y982842D01*
X445776Y982675D01*
X446026Y982425D01*
X446192Y982133D01*
X446234Y981800D01*
G01X445567Y982133D02*
X446234Y982633D01*
G01Y984900D02*
X443734D01*
X444234Y984400D01*
G01X446234D02*
Y985400D01*
G01Y988000D02*
X443734D01*
X444234Y987500D01*
G01X446234D02*
Y988500D01*
G01X458700Y989200D02*
X447300D01*
G01X458700Y975800D02*
Y989200D01*
G01X447300Y975800D02*
X458700D01*
G01X447300Y989200D02*
Y975800D01*
G01X467000Y1046517D02*
X464500D01*
Y1047558D01*
X464625Y1047892D01*
X464792Y1048100D01*
X465125Y1048183D01*
X465458Y1048100D01*
X465667Y1047850D01*
X465792Y1047558D01*
Y1046517D01*
G01Y1047558D02*
X467000Y1048183D01*
G01X464917Y1049658D02*
X464667Y1049908D01*
X464542Y1050200D01*
X464500Y1050533D01*
X464583Y1050950D01*
X464792Y1051242D01*
X465042Y1051325D01*
X465292Y1051283D01*
X465500Y1051117D01*
X465917Y1050283D01*
X466208Y1049908D01*
X466625Y1049658D01*
X467000Y1049575D01*
Y1051325D01*
G01X464500Y1053550D02*
X464583Y1053217D01*
X464792Y1052967D01*
X465042Y1052800D01*
X465375Y1052675D01*
X465750Y1052633D01*
X466125Y1052675D01*
X466458Y1052800D01*
X466708Y1052967D01*
X466917Y1053217D01*
X467000Y1053550D01*
X466917Y1053883D01*
X466708Y1054133D01*
X466458Y1054300D01*
X466125Y1054425D01*
X465750Y1054467D01*
X465375Y1054425D01*
X465042Y1054300D01*
X464792Y1054133D01*
X464583Y1053883D01*
X464500Y1053550D01*
G01X465958Y1055858D02*
X465667Y1056150D01*
X465500Y1056400D01*
X465417Y1056733D01*
X465500Y1057025D01*
X465667Y1057233D01*
X465917Y1057400D01*
X466208Y1057442D01*
X466458Y1057400D01*
X466708Y1057233D01*
X466917Y1056983D01*
X467000Y1056692D01*
X466917Y1056358D01*
X466667Y1056067D01*
X466292Y1055900D01*
X465875Y1055858D01*
X465333Y1055942D01*
X465042Y1056067D01*
X464750Y1056275D01*
X464542Y1056567D01*
X464500Y1056858D01*
X464583Y1057150D01*
X464792Y1057358D01*
G01X462000Y1045300D02*
X470000D01*
Y1027700D01*
X462000D01*
Y1045300D01*
G01X438200Y1042000D02*
Y1050000D01*
X455800D01*
Y1042000D01*
X438200D01*
G01X471825Y1114500D02*
Y1117000D01*
G01X473575D02*
Y1114500D01*
G01Y1115750D02*
X471825D01*
G01X474883Y1114500D02*
Y1117000D01*
X475717D01*
X476050Y1116875D01*
X476300Y1116708D01*
X476508Y1116458D01*
X476675Y1116167D01*
X476717Y1115750D01*
X476675Y1115333D01*
X476508Y1115042D01*
X476300Y1114792D01*
X476050Y1114625D01*
X475717Y1114500D01*
X474883D01*
G01X477983D02*
Y1117000D01*
X478817D01*
X479150Y1116875D01*
X479400Y1116708D01*
X479608Y1116458D01*
X479775Y1116167D01*
X479817Y1115750D01*
X479775Y1115333D01*
X479608Y1115042D01*
X479400Y1114792D01*
X479150Y1114625D01*
X478817Y1114500D01*
X477983D01*
G01X481125Y1114833D02*
X481458Y1114625D01*
X481833Y1114500D01*
X482167D01*
X482500Y1114625D01*
X482750Y1114833D01*
X482875Y1115125D01*
X482792Y1115417D01*
X482583Y1115667D01*
X482208Y1115833D01*
X481708Y1115917D01*
X481417Y1116083D01*
X481292Y1116375D01*
X481375Y1116667D01*
X481583Y1116875D01*
X481875Y1117000D01*
X482167D01*
X482458Y1116917D01*
X482708Y1116708D01*
G01X484058Y1114500D02*
X485100Y1117000D01*
X486142Y1114500D01*
G01X485767Y1115375D02*
X484433D01*
G01X487325Y1114833D02*
X487658Y1114625D01*
X488033Y1114500D01*
X488367D01*
X488700Y1114625D01*
X488950Y1114833D01*
X489075Y1115125D01*
X488992Y1115417D01*
X488783Y1115667D01*
X488408Y1115833D01*
X487908Y1115917D01*
X487617Y1116083D01*
X487492Y1116375D01*
X487575Y1116667D01*
X487783Y1116875D01*
X488075Y1117000D01*
X488367D01*
X488658Y1116917D01*
X488908Y1116708D01*
G01X490383Y1115000D02*
X490633Y1114708D01*
X490967Y1114542D01*
X491342Y1114500D01*
X491675Y1114542D01*
X492008Y1114750D01*
X492217Y1115000D01*
X492258Y1115250D01*
X492175Y1115542D01*
X491883Y1115750D01*
X491592Y1115833D01*
X491217D01*
G01X491592D02*
X491842Y1115958D01*
X492050Y1116167D01*
X492133Y1116417D01*
X492050Y1116667D01*
X491842Y1116875D01*
X491467Y1117000D01*
X491092Y1116958D01*
X490717Y1116792D01*
G01X446217Y1058292D02*
X445967Y1058417D01*
X445675Y1058500D01*
X445342D01*
X444967Y1058375D01*
X444675Y1058167D01*
X444467Y1057917D01*
X444300Y1057500D01*
X444258Y1057125D01*
X444342Y1056750D01*
X444467Y1056500D01*
X444717Y1056250D01*
X445008Y1056083D01*
X445300Y1056000D01*
X445592D01*
X445883Y1056083D01*
X446133Y1056208D01*
X446342Y1056375D01*
G01X447608Y1057042D02*
X447900Y1057333D01*
X448150Y1057500D01*
X448483Y1057583D01*
X448775Y1057500D01*
X448983Y1057333D01*
X449150Y1057083D01*
X449192Y1056792D01*
X449150Y1056542D01*
X448983Y1056292D01*
X448733Y1056083D01*
X448442Y1056000D01*
X448108Y1056083D01*
X447817Y1056333D01*
X447650Y1056708D01*
X447608Y1057125D01*
X447692Y1057667D01*
X447817Y1057958D01*
X448025Y1058250D01*
X448317Y1058458D01*
X448608Y1058500D01*
X448900Y1058417D01*
X449108Y1058208D01*
G01X450792Y1056292D02*
X451083Y1056083D01*
X451417Y1056000D01*
X451750Y1056083D01*
X452042Y1056333D01*
X452250Y1056708D01*
X452333Y1057083D01*
Y1057542D01*
X452250Y1057917D01*
X452042Y1058250D01*
X451792Y1058417D01*
X451500Y1058500D01*
X451167Y1058417D01*
X450917Y1058250D01*
X450750Y1058000D01*
X450667Y1057667D01*
X450750Y1057375D01*
X450958Y1057083D01*
X451208Y1056917D01*
X451500Y1056875D01*
X451833Y1056958D01*
X452083Y1057167D01*
X452333Y1057542D01*
G01X461708Y1083317D02*
X461583Y1083067D01*
X461500Y1082775D01*
Y1082442D01*
X461625Y1082067D01*
X461833Y1081775D01*
X462083Y1081567D01*
X462500Y1081400D01*
X462875Y1081358D01*
X463250Y1081442D01*
X463500Y1081567D01*
X463750Y1081817D01*
X463917Y1082108D01*
X464000Y1082400D01*
Y1082692D01*
X463917Y1082983D01*
X463792Y1083233D01*
X463625Y1083442D01*
G01X464000Y1085417D02*
X463458Y1085500D01*
X463000Y1085625D01*
X462583Y1085792D01*
X462125Y1086000D01*
X461500Y1086333D01*
Y1084667D01*
G01X462958Y1087808D02*
X462667Y1088100D01*
X462500Y1088350D01*
X462417Y1088683D01*
X462500Y1088975D01*
X462667Y1089183D01*
X462917Y1089350D01*
X463208Y1089392D01*
X463458Y1089350D01*
X463708Y1089183D01*
X463917Y1088933D01*
X464000Y1088642D01*
X463917Y1088308D01*
X463667Y1088017D01*
X463292Y1087850D01*
X462875Y1087808D01*
X462333Y1087892D01*
X462042Y1088017D01*
X461750Y1088225D01*
X461542Y1088517D01*
X461500Y1088808D01*
X461583Y1089100D01*
X461792Y1089308D01*
G01X446317Y1053953D02*
X446067Y1054078D01*
X445775Y1054161D01*
X445442D01*
X445067Y1054036D01*
X444775Y1053828D01*
X444567Y1053578D01*
X444400Y1053161D01*
X444358Y1052786D01*
X444442Y1052411D01*
X444567Y1052161D01*
X444817Y1051911D01*
X445108Y1051744D01*
X445400Y1051661D01*
X445692D01*
X445983Y1051744D01*
X446233Y1051869D01*
X446442Y1052036D01*
G01X448417Y1051661D02*
X448500Y1052203D01*
X448625Y1052661D01*
X448792Y1053078D01*
X449000Y1053536D01*
X449333Y1054161D01*
X447667D01*
G01X451600D02*
X451267Y1054078D01*
X451017Y1053869D01*
X450850Y1053619D01*
X450725Y1053286D01*
X450683Y1052911D01*
X450725Y1052536D01*
X450850Y1052203D01*
X451017Y1051953D01*
X451267Y1051744D01*
X451600Y1051661D01*
X451933Y1051744D01*
X452183Y1051953D01*
X452350Y1052203D01*
X452475Y1052536D01*
X452517Y1052911D01*
X452475Y1053286D01*
X452350Y1053619D01*
X452183Y1053869D01*
X451933Y1054078D01*
X451600Y1054161D01*
G01X444517Y1060000D02*
Y1062500D01*
X445558D01*
X445892Y1062375D01*
X446100Y1062208D01*
X446183Y1061875D01*
X446100Y1061542D01*
X445850Y1061333D01*
X445558Y1061208D01*
X444517D01*
G01X445558D02*
X446183Y1060000D01*
G01X447658Y1062083D02*
X447908Y1062333D01*
X448200Y1062458D01*
X448533Y1062500D01*
X448950Y1062417D01*
X449242Y1062208D01*
X449325Y1061958D01*
X449283Y1061708D01*
X449117Y1061500D01*
X448283Y1061083D01*
X447908Y1060792D01*
X447658Y1060375D01*
X447575Y1060000D01*
X449325D01*
G01X451550Y1062500D02*
X451217Y1062417D01*
X450967Y1062208D01*
X450800Y1061958D01*
X450675Y1061625D01*
X450633Y1061250D01*
X450675Y1060875D01*
X450800Y1060542D01*
X450967Y1060292D01*
X451217Y1060083D01*
X451550Y1060000D01*
X451883Y1060083D01*
X452133Y1060292D01*
X452300Y1060542D01*
X452425Y1060875D01*
X452467Y1061250D01*
X452425Y1061625D01*
X452300Y1061958D01*
X452133Y1062208D01*
X451883Y1062417D01*
X451550Y1062500D01*
G01X454650Y1060000D02*
X454942Y1060042D01*
X455275Y1060167D01*
X455483Y1060375D01*
X455567Y1060667D01*
X455483Y1060958D01*
X455233Y1061208D01*
X454858Y1061333D01*
X454442D01*
X454192Y1061417D01*
X453983Y1061625D01*
X453900Y1061917D01*
X454025Y1062208D01*
X454317Y1062417D01*
X454650Y1062500D01*
X454983Y1062417D01*
X455275Y1062208D01*
X455400Y1061917D01*
X455317Y1061625D01*
X455108Y1061417D01*
X454858Y1061333D01*
X454442D01*
X454067Y1061208D01*
X453817Y1060958D01*
X453733Y1060667D01*
X453817Y1060375D01*
X454025Y1060167D01*
X454358Y1060042D01*
X454650Y1060000D01*
G01X428317Y1053292D02*
X428067Y1053417D01*
X427775Y1053500D01*
X427442D01*
X427067Y1053375D01*
X426775Y1053167D01*
X426567Y1052917D01*
X426400Y1052500D01*
X426358Y1052125D01*
X426442Y1051750D01*
X426567Y1051500D01*
X426817Y1051250D01*
X427108Y1051083D01*
X427400Y1051000D01*
X427692D01*
X427983Y1051083D01*
X428233Y1051208D01*
X428442Y1051375D01*
G01X430417Y1051000D02*
X430500Y1051542D01*
X430625Y1052000D01*
X430792Y1052417D01*
X431000Y1052875D01*
X431333Y1053500D01*
X429667D01*
G01X432683Y1051500D02*
X432933Y1051208D01*
X433267Y1051042D01*
X433642Y1051000D01*
X433975Y1051042D01*
X434308Y1051250D01*
X434517Y1051500D01*
X434558Y1051750D01*
X434475Y1052042D01*
X434183Y1052250D01*
X433892Y1052333D01*
X433517D01*
G01X433892D02*
X434142Y1052458D01*
X434350Y1052667D01*
X434433Y1052917D01*
X434350Y1053167D01*
X434142Y1053375D01*
X433767Y1053500D01*
X433392Y1053458D01*
X433017Y1053292D01*
G01X459708Y1072317D02*
X459583Y1072067D01*
X459500Y1071775D01*
Y1071442D01*
X459625Y1071067D01*
X459833Y1070775D01*
X460083Y1070567D01*
X460500Y1070400D01*
X460875Y1070358D01*
X461250Y1070442D01*
X461500Y1070567D01*
X461750Y1070817D01*
X461917Y1071108D01*
X462000Y1071400D01*
Y1071692D01*
X461917Y1071983D01*
X461792Y1072233D01*
X461625Y1072442D01*
G01X462000Y1074417D02*
X461458Y1074500D01*
X461000Y1074625D01*
X460583Y1074792D01*
X460125Y1075000D01*
X459500Y1075333D01*
Y1073667D01*
G01X462000Y1078100D02*
X459500D01*
X461292Y1076558D01*
Y1078642D01*
G01X391183Y1298333D02*
X391350Y1298458D01*
X391475Y1298667D01*
X391558Y1298958D01*
X391475Y1299208D01*
X391308Y1299375D01*
X391017Y1299500D01*
X389892D01*
Y1297000D01*
X391267D01*
X391558Y1297167D01*
X391725Y1297417D01*
X391808Y1297708D01*
X391725Y1298000D01*
X391475Y1298250D01*
X391183Y1298333D01*
X389892D01*
G01X393033Y1299500D02*
Y1297708D01*
X393200Y1297333D01*
X393533Y1297083D01*
X393950Y1297000D01*
X394367Y1297083D01*
X394700Y1297333D01*
X394867Y1297708D01*
Y1299500D01*
G01X396175Y1297333D02*
X396508Y1297125D01*
X396883Y1297000D01*
X397217D01*
X397550Y1297125D01*
X397800Y1297333D01*
X397925Y1297625D01*
X397842Y1297917D01*
X397633Y1298167D01*
X397258Y1298333D01*
X396758Y1298417D01*
X396467Y1298583D01*
X396342Y1298875D01*
X396425Y1299167D01*
X396633Y1299375D01*
X396925Y1299500D01*
X397217D01*
X397508Y1299417D01*
X397758Y1299208D01*
G01X400150Y1297000D02*
Y1299500D01*
X399650Y1299000D01*
G01Y1297000D02*
X400650D01*
G01X396267Y1403292D02*
X396017Y1403417D01*
X395725Y1403500D01*
X395392D01*
X395017Y1403375D01*
X394725Y1403167D01*
X394517Y1402917D01*
X394350Y1402500D01*
X394308Y1402125D01*
X394392Y1401750D01*
X394517Y1401500D01*
X394767Y1401250D01*
X395058Y1401083D01*
X395350Y1401000D01*
X395642D01*
X395933Y1401083D01*
X396183Y1401208D01*
X396392Y1401375D01*
G01X397533D02*
X397783Y1401167D01*
X398075Y1401042D01*
X398450Y1401000D01*
X398825Y1401083D01*
X399117Y1401250D01*
X399325Y1401542D01*
X399367Y1401875D01*
X399283Y1402208D01*
X399075Y1402417D01*
X398783Y1402583D01*
X398492Y1402625D01*
X398200Y1402583D01*
X397825Y1402417D01*
X397950Y1403500D01*
X399075D01*
G01X402050Y1401000D02*
Y1403500D01*
X400508Y1401708D01*
X402592D01*
G01X403942Y1401292D02*
X404233Y1401083D01*
X404567Y1401000D01*
X404900Y1401083D01*
X405192Y1401333D01*
X405400Y1401708D01*
X405483Y1402083D01*
Y1402542D01*
X405400Y1402917D01*
X405192Y1403250D01*
X404942Y1403417D01*
X404650Y1403500D01*
X404317Y1403417D01*
X404067Y1403250D01*
X403900Y1403000D01*
X403817Y1402667D01*
X403900Y1402375D01*
X404108Y1402083D01*
X404358Y1401917D01*
X404650Y1401875D01*
X404983Y1401958D01*
X405233Y1402167D01*
X405483Y1402542D01*
G01X482267Y1472792D02*
X482017Y1472917D01*
X481725Y1473000D01*
X481392D01*
X481017Y1472875D01*
X480725Y1472667D01*
X480517Y1472417D01*
X480350Y1472000D01*
X480308Y1471625D01*
X480392Y1471250D01*
X480517Y1471000D01*
X480767Y1470750D01*
X481058Y1470583D01*
X481350Y1470500D01*
X481642D01*
X481933Y1470583D01*
X482183Y1470708D01*
X482392Y1470875D01*
G01X483533D02*
X483783Y1470667D01*
X484075Y1470542D01*
X484450Y1470500D01*
X484825Y1470583D01*
X485117Y1470750D01*
X485325Y1471042D01*
X485367Y1471375D01*
X485283Y1471708D01*
X485075Y1471917D01*
X484783Y1472083D01*
X484492Y1472125D01*
X484200Y1472083D01*
X483825Y1471917D01*
X483950Y1473000D01*
X485075D01*
G01X486758Y1472583D02*
X487008Y1472833D01*
X487300Y1472958D01*
X487633Y1473000D01*
X488050Y1472917D01*
X488342Y1472708D01*
X488425Y1472458D01*
X488383Y1472208D01*
X488217Y1472000D01*
X487383Y1471583D01*
X487008Y1471292D01*
X486758Y1470875D01*
X486675Y1470500D01*
X488425D01*
G01X491150D02*
Y1473000D01*
X489608Y1471208D01*
X491692D01*
G01X480517Y1466500D02*
Y1469000D01*
X481558D01*
X481892Y1468875D01*
X482100Y1468708D01*
X482183Y1468375D01*
X482100Y1468042D01*
X481850Y1467833D01*
X481558Y1467708D01*
X480517D01*
G01X481558D02*
X482183Y1466500D01*
G01X483742Y1466792D02*
X484033Y1466583D01*
X484367Y1466500D01*
X484700Y1466583D01*
X484992Y1466833D01*
X485200Y1467208D01*
X485283Y1467583D01*
Y1468042D01*
X485200Y1468417D01*
X484992Y1468750D01*
X484742Y1468917D01*
X484450Y1469000D01*
X484117Y1468917D01*
X483867Y1468750D01*
X483700Y1468500D01*
X483617Y1468167D01*
X483700Y1467875D01*
X483908Y1467583D01*
X484158Y1467417D01*
X484450Y1467375D01*
X484783Y1467458D01*
X485033Y1467667D01*
X485283Y1468042D01*
G01X486633Y1467000D02*
X486883Y1466708D01*
X487217Y1466542D01*
X487592Y1466500D01*
X487925Y1466542D01*
X488258Y1466750D01*
X488467Y1467000D01*
X488508Y1467250D01*
X488425Y1467542D01*
X488133Y1467750D01*
X487842Y1467833D01*
X487467D01*
G01X487842D02*
X488092Y1467958D01*
X488300Y1468167D01*
X488383Y1468417D01*
X488300Y1468667D01*
X488092Y1468875D01*
X487717Y1469000D01*
X487342Y1468958D01*
X486967Y1468792D01*
G01X491150Y1466500D02*
Y1469000D01*
X489608Y1467208D01*
X491692D01*
G01X478500Y1462517D02*
X476000D01*
Y1463558D01*
X476125Y1463892D01*
X476292Y1464100D01*
X476625Y1464183D01*
X476958Y1464100D01*
X477167Y1463850D01*
X477292Y1463558D01*
Y1462517D01*
G01Y1463558D02*
X478500Y1464183D01*
G01X478208Y1465742D02*
X478417Y1466033D01*
X478500Y1466367D01*
X478417Y1466700D01*
X478167Y1466992D01*
X477792Y1467200D01*
X477417Y1467283D01*
X476958D01*
X476583Y1467200D01*
X476250Y1466992D01*
X476083Y1466742D01*
X476000Y1466450D01*
X476083Y1466117D01*
X476250Y1465867D01*
X476500Y1465700D01*
X476833Y1465617D01*
X477125Y1465700D01*
X477417Y1465908D01*
X477583Y1466158D01*
X477625Y1466450D01*
X477542Y1466783D01*
X477333Y1467033D01*
X476958Y1467283D01*
G01X478000Y1468633D02*
X478292Y1468883D01*
X478458Y1469217D01*
X478500Y1469592D01*
X478458Y1469925D01*
X478250Y1470258D01*
X478000Y1470467D01*
X477750Y1470508D01*
X477458Y1470425D01*
X477250Y1470133D01*
X477167Y1469842D01*
Y1469467D01*
G01Y1469842D02*
X477042Y1470092D01*
X476833Y1470300D01*
X476583Y1470383D01*
X476333Y1470300D01*
X476125Y1470092D01*
X476000Y1469717D01*
X476042Y1469342D01*
X476208Y1468967D01*
G01X478500Y1472567D02*
X477958Y1472650D01*
X477500Y1472775D01*
X477083Y1472942D01*
X476625Y1473150D01*
X476000Y1473483D01*
Y1471817D01*
G01X480517Y1462500D02*
Y1465000D01*
X481558D01*
X481892Y1464875D01*
X482100Y1464708D01*
X482183Y1464375D01*
X482100Y1464042D01*
X481850Y1463833D01*
X481558Y1463708D01*
X480517D01*
G01X481558D02*
X482183Y1462500D01*
G01X483742Y1462792D02*
X484033Y1462583D01*
X484367Y1462500D01*
X484700Y1462583D01*
X484992Y1462833D01*
X485200Y1463208D01*
X485283Y1463583D01*
Y1464042D01*
X485200Y1464417D01*
X484992Y1464750D01*
X484742Y1464917D01*
X484450Y1465000D01*
X484117Y1464917D01*
X483867Y1464750D01*
X483700Y1464500D01*
X483617Y1464167D01*
X483700Y1463875D01*
X483908Y1463583D01*
X484158Y1463417D01*
X484450Y1463375D01*
X484783Y1463458D01*
X485033Y1463667D01*
X485283Y1464042D01*
G01X486633Y1463000D02*
X486883Y1462708D01*
X487217Y1462542D01*
X487592Y1462500D01*
X487925Y1462542D01*
X488258Y1462750D01*
X488467Y1463000D01*
X488508Y1463250D01*
X488425Y1463542D01*
X488133Y1463750D01*
X487842Y1463833D01*
X487467D01*
G01X487842D02*
X488092Y1463958D01*
X488300Y1464167D01*
X488383Y1464417D01*
X488300Y1464667D01*
X488092Y1464875D01*
X487717Y1465000D01*
X487342Y1464958D01*
X486967Y1464792D01*
G01X489858Y1463542D02*
X490150Y1463833D01*
X490400Y1464000D01*
X490733Y1464083D01*
X491025Y1464000D01*
X491233Y1463833D01*
X491400Y1463583D01*
X491442Y1463292D01*
X491400Y1463042D01*
X491233Y1462792D01*
X490983Y1462583D01*
X490692Y1462500D01*
X490358Y1462583D01*
X490067Y1462833D01*
X489900Y1463208D01*
X489858Y1463625D01*
X489942Y1464167D01*
X490067Y1464458D01*
X490275Y1464750D01*
X490567Y1464958D01*
X490858Y1465000D01*
X491150Y1464917D01*
X491358Y1464708D01*
G01X400983Y1438500D02*
Y1441000D01*
X401817D01*
X402150Y1440875D01*
X402400Y1440708D01*
X402608Y1440458D01*
X402775Y1440167D01*
X402817Y1439750D01*
X402775Y1439333D01*
X402608Y1439042D01*
X402400Y1438792D01*
X402150Y1438625D01*
X401817Y1438500D01*
X400983D01*
G01X405500D02*
Y1441000D01*
X403958Y1439208D01*
X406042D01*
G01X407183Y1438875D02*
X407433Y1438667D01*
X407725Y1438542D01*
X408100Y1438500D01*
X408475Y1438583D01*
X408767Y1438750D01*
X408975Y1439042D01*
X409017Y1439375D01*
X408933Y1439708D01*
X408725Y1439917D01*
X408433Y1440083D01*
X408142Y1440125D01*
X407850Y1440083D01*
X407475Y1439917D01*
X407600Y1441000D01*
X408725D01*
G01X512267Y57792D02*
X512017Y57917D01*
X511725Y58000D01*
X511392D01*
X511017Y57875D01*
X510725Y57667D01*
X510517Y57417D01*
X510350Y57000D01*
X510308Y56625D01*
X510392Y56250D01*
X510517Y56000D01*
X510767Y55750D01*
X511058Y55583D01*
X511350Y55500D01*
X511642D01*
X511933Y55583D01*
X512183Y55708D01*
X512392Y55875D01*
G01X513533Y56000D02*
X513783Y55708D01*
X514117Y55542D01*
X514492Y55500D01*
X514825Y55542D01*
X515158Y55750D01*
X515367Y56000D01*
X515408Y56250D01*
X515325Y56542D01*
X515033Y56750D01*
X514742Y56833D01*
X514367D01*
G01X514742D02*
X514992Y56958D01*
X515200Y57167D01*
X515283Y57417D01*
X515200Y57667D01*
X514992Y57875D01*
X514617Y58000D01*
X514242Y57958D01*
X513867Y57792D01*
G01X517550Y55500D02*
X517842Y55542D01*
X518175Y55667D01*
X518383Y55875D01*
X518467Y56167D01*
X518383Y56458D01*
X518133Y56708D01*
X517758Y56833D01*
X517342D01*
X517092Y56917D01*
X516883Y57125D01*
X516800Y57417D01*
X516925Y57708D01*
X517217Y57917D01*
X517550Y58000D01*
X517883Y57917D01*
X518175Y57708D01*
X518300Y57417D01*
X518217Y57125D01*
X518008Y56917D01*
X517758Y56833D01*
X517342D01*
X516967Y56708D01*
X516717Y56458D01*
X516633Y56167D01*
X516717Y55875D01*
X516925Y55667D01*
X517258Y55542D01*
X517550Y55500D01*
G01X520650Y58000D02*
X520317Y57917D01*
X520067Y57708D01*
X519900Y57458D01*
X519775Y57125D01*
X519733Y56750D01*
X519775Y56375D01*
X519900Y56042D01*
X520067Y55792D01*
X520317Y55583D01*
X520650Y55500D01*
X520983Y55583D01*
X521233Y55792D01*
X521400Y56042D01*
X521525Y56375D01*
X521567Y56750D01*
X521525Y57125D01*
X521400Y57458D01*
X521233Y57708D01*
X520983Y57917D01*
X520650Y58000D01*
G01X512213Y61872D02*
X511963Y61997D01*
X511671Y62080D01*
X511338D01*
X510963Y61955D01*
X510671Y61747D01*
X510463Y61497D01*
X510296Y61080D01*
X510254Y60705D01*
X510338Y60330D01*
X510463Y60080D01*
X510713Y59830D01*
X511004Y59663D01*
X511296Y59580D01*
X511588D01*
X511879Y59663D01*
X512129Y59788D01*
X512338Y59955D01*
G01X513479Y60080D02*
X513729Y59788D01*
X514063Y59622D01*
X514438Y59580D01*
X514771Y59622D01*
X515104Y59830D01*
X515313Y60080D01*
X515354Y60330D01*
X515271Y60622D01*
X514979Y60830D01*
X514688Y60913D01*
X514313D01*
G01X514688D02*
X514938Y61038D01*
X515146Y61247D01*
X515229Y61497D01*
X515146Y61747D01*
X514938Y61955D01*
X514563Y62080D01*
X514188Y62038D01*
X513813Y61872D01*
G01X517413Y59580D02*
X517496Y60122D01*
X517621Y60580D01*
X517788Y60997D01*
X517996Y61455D01*
X518329Y62080D01*
X516663D01*
G01X519888Y59872D02*
X520179Y59663D01*
X520513Y59580D01*
X520846Y59663D01*
X521138Y59913D01*
X521346Y60288D01*
X521429Y60663D01*
Y61122D01*
X521346Y61497D01*
X521138Y61830D01*
X520888Y61997D01*
X520596Y62080D01*
X520263Y61997D01*
X520013Y61830D01*
X519846Y61580D01*
X519763Y61247D01*
X519846Y60955D01*
X520054Y60663D01*
X520304Y60497D01*
X520596Y60455D01*
X520929Y60538D01*
X521179Y60747D01*
X521429Y61122D01*
G01X548767Y89953D02*
X548517Y90078D01*
X548225Y90161D01*
X547892D01*
X547517Y90036D01*
X547225Y89828D01*
X547017Y89578D01*
X546850Y89161D01*
X546808Y88786D01*
X546892Y88411D01*
X547017Y88161D01*
X547267Y87911D01*
X547558Y87744D01*
X547850Y87661D01*
X548142D01*
X548433Y87744D01*
X548683Y87869D01*
X548892Y88036D01*
G01X551450Y87661D02*
Y90161D01*
X549908Y88369D01*
X551992D01*
G01X554050Y90161D02*
X553717Y90078D01*
X553467Y89869D01*
X553300Y89619D01*
X553175Y89286D01*
X553133Y88911D01*
X553175Y88536D01*
X553300Y88203D01*
X553467Y87953D01*
X553717Y87744D01*
X554050Y87661D01*
X554383Y87744D01*
X554633Y87953D01*
X554800Y88203D01*
X554925Y88536D01*
X554967Y88911D01*
X554925Y89286D01*
X554800Y89619D01*
X554633Y89869D01*
X554383Y90078D01*
X554050Y90161D01*
G01X556358Y89744D02*
X556608Y89994D01*
X556900Y90119D01*
X557233Y90161D01*
X557650Y90078D01*
X557942Y89869D01*
X558025Y89619D01*
X557983Y89369D01*
X557817Y89161D01*
X556983Y88744D01*
X556608Y88453D01*
X556358Y88036D01*
X556275Y87661D01*
X558025D01*
G01X547017Y83661D02*
Y86161D01*
X548058D01*
X548392Y86036D01*
X548600Y85869D01*
X548683Y85536D01*
X548600Y85203D01*
X548350Y84994D01*
X548058Y84869D01*
X547017D01*
G01X548058D02*
X548683Y83661D01*
G01X550867D02*
X550950Y84203D01*
X551075Y84661D01*
X551242Y85078D01*
X551450Y85536D01*
X551783Y86161D01*
X550117D01*
G01X553258Y85744D02*
X553508Y85994D01*
X553800Y86119D01*
X554133Y86161D01*
X554550Y86078D01*
X554842Y85869D01*
X554925Y85619D01*
X554883Y85369D01*
X554717Y85161D01*
X553883Y84744D01*
X553508Y84453D01*
X553258Y84036D01*
X553175Y83661D01*
X554925D01*
G01X557150D02*
Y86161D01*
X556650Y85661D01*
G01Y83661D02*
X557650D01*
G01X559300Y93000D02*
Y89000D01*
X566700D01*
G01X547017Y58500D02*
Y61000D01*
X548058D01*
X548392Y60875D01*
X548600Y60708D01*
X548683Y60375D01*
X548600Y60042D01*
X548350Y59833D01*
X548058Y59708D01*
X547017D01*
G01X548058D02*
X548683Y58500D01*
G01X550867D02*
X550950Y59042D01*
X551075Y59500D01*
X551242Y59917D01*
X551450Y60375D01*
X551783Y61000D01*
X550117D01*
G01X553258Y60583D02*
X553508Y60833D01*
X553800Y60958D01*
X554133Y61000D01*
X554550Y60917D01*
X554842Y60708D01*
X554925Y60458D01*
X554883Y60208D01*
X554717Y60000D01*
X553883Y59583D01*
X553508Y59292D01*
X553258Y58875D01*
X553175Y58500D01*
X554925D01*
G01X557150D02*
X557442Y58542D01*
X557775Y58667D01*
X557983Y58875D01*
X558067Y59167D01*
X557983Y59458D01*
X557733Y59708D01*
X557358Y59833D01*
X556942D01*
X556692Y59917D01*
X556483Y60125D01*
X556400Y60417D01*
X556525Y60708D01*
X556817Y60917D01*
X557150Y61000D01*
X557483Y60917D01*
X557775Y60708D01*
X557900Y60417D01*
X557817Y60125D01*
X557608Y59917D01*
X557358Y59833D01*
X556942D01*
X556567Y59708D01*
X556317Y59458D01*
X556233Y59167D01*
X556317Y58875D01*
X556525Y58667D01*
X556858Y58542D01*
X557150Y58500D01*
G01X551800Y67500D02*
Y63500D01*
X559200D01*
G01X539517Y92661D02*
Y95161D01*
X540558D01*
X540892Y95036D01*
X541100Y94869D01*
X541183Y94536D01*
X541100Y94203D01*
X540850Y93994D01*
X540558Y93869D01*
X539517D01*
G01X540558D02*
X541183Y92661D01*
G01X543367D02*
X543450Y93203D01*
X543575Y93661D01*
X543742Y94078D01*
X543950Y94536D01*
X544283Y95161D01*
X542617D01*
G01X545758Y94744D02*
X546008Y94994D01*
X546300Y95119D01*
X546633Y95161D01*
X547050Y95078D01*
X547342Y94869D01*
X547425Y94619D01*
X547383Y94369D01*
X547217Y94161D01*
X546383Y93744D01*
X546008Y93453D01*
X545758Y93036D01*
X545675Y92661D01*
X547425D01*
G01X548942Y92953D02*
X549233Y92744D01*
X549567Y92661D01*
X549900Y92744D01*
X550192Y92994D01*
X550400Y93369D01*
X550483Y93744D01*
Y94203D01*
X550400Y94578D01*
X550192Y94911D01*
X549942Y95078D01*
X549650Y95161D01*
X549317Y95078D01*
X549067Y94911D01*
X548900Y94661D01*
X548817Y94328D01*
X548900Y94036D01*
X549108Y93744D01*
X549358Y93578D01*
X549650Y93536D01*
X549983Y93619D01*
X550233Y93828D01*
X550483Y94203D01*
G01X553500Y69017D02*
X551000D01*
Y70058D01*
X551125Y70392D01*
X551292Y70600D01*
X551625Y70683D01*
X551958Y70600D01*
X552167Y70350D01*
X552292Y70058D01*
Y69017D01*
G01Y70058D02*
X553500Y70683D01*
G01Y72867D02*
X552958Y72950D01*
X552500Y73075D01*
X552083Y73242D01*
X551625Y73450D01*
X551000Y73783D01*
Y72117D01*
G01X553000Y75133D02*
X553292Y75383D01*
X553458Y75717D01*
X553500Y76092D01*
X553458Y76425D01*
X553250Y76758D01*
X553000Y76967D01*
X552750Y77008D01*
X552458Y76925D01*
X552250Y76633D01*
X552167Y76342D01*
Y75967D01*
G01Y76342D02*
X552042Y76592D01*
X551833Y76800D01*
X551583Y76883D01*
X551333Y76800D01*
X551125Y76592D01*
X551000Y76217D01*
X551042Y75842D01*
X551208Y75467D01*
G01X551000Y79150D02*
X551083Y78817D01*
X551292Y78567D01*
X551542Y78400D01*
X551875Y78275D01*
X552250Y78233D01*
X552625Y78275D01*
X552958Y78400D01*
X553208Y78567D01*
X553417Y78817D01*
X553500Y79150D01*
X553417Y79483D01*
X553208Y79733D01*
X552958Y79900D01*
X552625Y80025D01*
X552250Y80067D01*
X551875Y80025D01*
X551542Y79900D01*
X551292Y79733D01*
X551083Y79483D01*
X551000Y79150D01*
G01X555000Y67800D02*
X559000D01*
Y75200D01*
G01X570500Y50017D02*
X568000D01*
Y51058D01*
X568125Y51392D01*
X568292Y51600D01*
X568625Y51683D01*
X568958Y51600D01*
X569167Y51350D01*
X569292Y51058D01*
Y50017D01*
G01Y51058D02*
X570500Y51683D01*
G01Y53867D02*
X569958Y53950D01*
X569500Y54075D01*
X569083Y54242D01*
X568625Y54450D01*
X568000Y54783D01*
Y53117D01*
G01X570000Y56133D02*
X570292Y56383D01*
X570458Y56717D01*
X570500Y57092D01*
X570458Y57425D01*
X570250Y57758D01*
X570000Y57967D01*
X569750Y58008D01*
X569458Y57925D01*
X569250Y57633D01*
X569167Y57342D01*
Y56967D01*
G01Y57342D02*
X569042Y57592D01*
X568833Y57800D01*
X568583Y57883D01*
X568333Y57800D01*
X568125Y57592D01*
X568000Y57217D01*
X568042Y56842D01*
X568208Y56467D01*
G01X570500Y60150D02*
X568000D01*
X568500Y59650D01*
G01X570500D02*
Y60650D01*
G01X571500Y69200D02*
X567500D01*
Y61800D01*
G01X564500Y49983D02*
X562000D01*
Y50817D01*
X562125Y51150D01*
X562292Y51400D01*
X562542Y51608D01*
X562833Y51775D01*
X563250Y51817D01*
X563667Y51775D01*
X563958Y51608D01*
X564208Y51400D01*
X564375Y51150D01*
X564500Y50817D01*
Y49983D01*
G01X562417Y53208D02*
X562167Y53458D01*
X562042Y53750D01*
X562000Y54083D01*
X562083Y54500D01*
X562292Y54792D01*
X562542Y54875D01*
X562792Y54833D01*
X563000Y54667D01*
X563417Y53833D01*
X563708Y53458D01*
X564125Y53208D01*
X564500Y53125D01*
Y54875D01*
G01Y57100D02*
X564458Y57392D01*
X564333Y57725D01*
X564125Y57933D01*
X563833Y58017D01*
X563542Y57933D01*
X563292Y57683D01*
X563167Y57308D01*
Y56892D01*
X563083Y56642D01*
X562875Y56433D01*
X562583Y56350D01*
X562292Y56475D01*
X562083Y56767D01*
X562000Y57100D01*
X562083Y57433D01*
X562292Y57725D01*
X562583Y57850D01*
X562875Y57767D01*
X563083Y57558D01*
X563167Y57308D01*
Y56892D01*
X563292Y56517D01*
X563542Y56267D01*
X563833Y56183D01*
X564125Y56267D01*
X564333Y56475D01*
X564458Y56808D01*
X564500Y57100D01*
G01X567000Y78000D02*
Y61900D01*
G01X560000Y78000D02*
X567000D01*
G01X560000Y61900D02*
Y78000D01*
G01X567000Y61900D02*
X560000D01*
G01X570722Y75273D02*
X570680Y74940D01*
X570514Y74648D01*
X570264Y74398D01*
X569972Y74231D01*
X569639Y74148D01*
X569305D01*
X568972Y74231D01*
X568680Y74398D01*
X568430Y74648D01*
X568264Y74940D01*
X568222Y75273D01*
X568264Y75606D01*
X568430Y75898D01*
X568680Y76148D01*
X568972Y76315D01*
X569305Y76398D01*
X569639D01*
X569972Y76315D01*
X570264Y76148D01*
X570514Y75898D01*
X570680Y75606D01*
X570722Y75273D01*
G01X570055Y75606D02*
X570722Y76106D01*
G01Y78373D02*
X568222D01*
X568722Y77873D01*
G01X570722D02*
Y78873D01*
G01Y81973D02*
X568222D01*
X570014Y80431D01*
Y82515D01*
G01X570222Y83656D02*
X570514Y83906D01*
X570680Y84240D01*
X570722Y84615D01*
X570680Y84948D01*
X570472Y85281D01*
X570222Y85490D01*
X569972Y85531D01*
X569680Y85448D01*
X569472Y85156D01*
X569389Y84865D01*
Y84490D01*
G01Y84865D02*
X569264Y85115D01*
X569055Y85323D01*
X568805Y85406D01*
X568555Y85323D01*
X568347Y85115D01*
X568222Y84740D01*
X568264Y84365D01*
X568430Y83990D01*
G01X583200Y83700D02*
X571800D01*
G01Y70300D02*
X583200D01*
G01X571800Y83700D02*
Y70300D01*
G01X499435Y131767D02*
X499310Y131517D01*
X499227Y131225D01*
Y130892D01*
X499352Y130517D01*
X499560Y130225D01*
X499810Y130017D01*
X500227Y129850D01*
X500602Y129808D01*
X500977Y129892D01*
X501227Y130017D01*
X501477Y130267D01*
X501644Y130558D01*
X501727Y130850D01*
Y131142D01*
X501644Y131433D01*
X501519Y131683D01*
X501352Y131892D01*
G01X501227Y133033D02*
X501519Y133283D01*
X501685Y133617D01*
X501727Y133992D01*
X501685Y134325D01*
X501477Y134658D01*
X501227Y134867D01*
X500977Y134908D01*
X500685Y134825D01*
X500477Y134533D01*
X500394Y134242D01*
Y133867D01*
G01Y134242D02*
X500269Y134492D01*
X500060Y134700D01*
X499810Y134783D01*
X499560Y134700D01*
X499352Y134492D01*
X499227Y134117D01*
X499269Y133742D01*
X499435Y133367D01*
G01X501727Y137050D02*
X501685Y137342D01*
X501560Y137675D01*
X501352Y137883D01*
X501060Y137967D01*
X500769Y137883D01*
X500519Y137633D01*
X500394Y137258D01*
Y136842D01*
X500310Y136592D01*
X500102Y136383D01*
X499810Y136300D01*
X499519Y136425D01*
X499310Y136717D01*
X499227Y137050D01*
X499310Y137383D01*
X499519Y137675D01*
X499810Y137800D01*
X500102Y137717D01*
X500310Y137508D01*
X500394Y137258D01*
Y136842D01*
X500519Y136467D01*
X500769Y136217D01*
X501060Y136133D01*
X501352Y136217D01*
X501560Y136425D01*
X501685Y136758D01*
X501727Y137050D01*
G01Y140150D02*
X501685Y140442D01*
X501560Y140775D01*
X501352Y140983D01*
X501060Y141067D01*
X500769Y140983D01*
X500519Y140733D01*
X500394Y140358D01*
Y139942D01*
X500310Y139692D01*
X500102Y139483D01*
X499810Y139400D01*
X499519Y139525D01*
X499310Y139817D01*
X499227Y140150D01*
X499310Y140483D01*
X499519Y140775D01*
X499810Y140900D01*
X500102Y140817D01*
X500310Y140608D01*
X500394Y140358D01*
Y139942D01*
X500519Y139567D01*
X500769Y139317D01*
X501060Y139233D01*
X501352Y139317D01*
X501560Y139525D01*
X501685Y139858D01*
X501727Y140150D01*
G01X541267Y98953D02*
X541017Y99078D01*
X540725Y99161D01*
X540392D01*
X540017Y99036D01*
X539725Y98828D01*
X539517Y98578D01*
X539350Y98161D01*
X539308Y97786D01*
X539392Y97411D01*
X539517Y97161D01*
X539767Y96911D01*
X540058Y96744D01*
X540350Y96661D01*
X540642D01*
X540933Y96744D01*
X541183Y96869D01*
X541392Y97036D01*
G01X543950Y96661D02*
Y99161D01*
X542408Y97369D01*
X544492D01*
G01X546550Y99161D02*
X546217Y99078D01*
X545967Y98869D01*
X545800Y98619D01*
X545675Y98286D01*
X545633Y97911D01*
X545675Y97536D01*
X545800Y97203D01*
X545967Y96953D01*
X546217Y96744D01*
X546550Y96661D01*
X546883Y96744D01*
X547133Y96953D01*
X547300Y97203D01*
X547425Y97536D01*
X547467Y97911D01*
X547425Y98286D01*
X547300Y98619D01*
X547133Y98869D01*
X546883Y99078D01*
X546550Y99161D01*
G01X548733Y97161D02*
X548983Y96869D01*
X549317Y96703D01*
X549692Y96661D01*
X550025Y96703D01*
X550358Y96911D01*
X550567Y97161D01*
X550608Y97411D01*
X550525Y97703D01*
X550233Y97911D01*
X549942Y97994D01*
X549567D01*
G01X549942D02*
X550192Y98119D01*
X550400Y98328D01*
X550483Y98578D01*
X550400Y98828D01*
X550192Y99036D01*
X549817Y99161D01*
X549442Y99119D01*
X549067Y98953D01*
G01X505727Y130017D02*
X503227D01*
Y131058D01*
X503352Y131392D01*
X503519Y131600D01*
X503852Y131683D01*
X504185Y131600D01*
X504394Y131350D01*
X504519Y131058D01*
Y130017D01*
G01Y131058D02*
X505727Y131683D01*
G01X504685Y133158D02*
X504394Y133450D01*
X504227Y133700D01*
X504144Y134033D01*
X504227Y134325D01*
X504394Y134533D01*
X504644Y134700D01*
X504935Y134742D01*
X505185Y134700D01*
X505435Y134533D01*
X505644Y134283D01*
X505727Y133992D01*
X505644Y133658D01*
X505394Y133367D01*
X505019Y133200D01*
X504602Y133158D01*
X504060Y133242D01*
X503769Y133367D01*
X503477Y133575D01*
X503269Y133867D01*
X503227Y134158D01*
X503310Y134450D01*
X503519Y134658D01*
G01X505435Y136342D02*
X505644Y136633D01*
X505727Y136967D01*
X505644Y137300D01*
X505394Y137592D01*
X505019Y137800D01*
X504644Y137883D01*
X504185D01*
X503810Y137800D01*
X503477Y137592D01*
X503310Y137342D01*
X503227Y137050D01*
X503310Y136717D01*
X503477Y136467D01*
X503727Y136300D01*
X504060Y136217D01*
X504352Y136300D01*
X504644Y136508D01*
X504810Y136758D01*
X504852Y137050D01*
X504769Y137383D01*
X504560Y137633D01*
X504185Y137883D01*
G01X505727Y140150D02*
X503227D01*
X503727Y139650D01*
G01X505727D02*
Y140650D01*
G01X501900Y120800D02*
X505900D01*
Y128200D01*
G01X559200Y94500D02*
Y98500D01*
X551800D01*
G01X569327Y156292D02*
X569077Y156417D01*
X568785Y156500D01*
X568452D01*
X568077Y156375D01*
X567785Y156167D01*
X567577Y155917D01*
X567410Y155500D01*
X567368Y155125D01*
X567452Y154750D01*
X567577Y154500D01*
X567827Y154250D01*
X568118Y154083D01*
X568410Y154000D01*
X568702D01*
X568993Y154083D01*
X569243Y154208D01*
X569452Y154375D01*
G01X570593Y154500D02*
X570843Y154208D01*
X571177Y154042D01*
X571552Y154000D01*
X571885Y154042D01*
X572218Y154250D01*
X572427Y154500D01*
X572468Y154750D01*
X572385Y155042D01*
X572093Y155250D01*
X571802Y155333D01*
X571427D01*
G01X571802D02*
X572052Y155458D01*
X572260Y155667D01*
X572343Y155917D01*
X572260Y156167D01*
X572052Y156375D01*
X571677Y156500D01*
X571302Y156458D01*
X570927Y156292D01*
G01X573902Y154292D02*
X574193Y154083D01*
X574527Y154000D01*
X574860Y154083D01*
X575152Y154333D01*
X575360Y154708D01*
X575443Y155083D01*
Y155542D01*
X575360Y155917D01*
X575152Y156250D01*
X574902Y156417D01*
X574610Y156500D01*
X574277Y156417D01*
X574027Y156250D01*
X573860Y156000D01*
X573777Y155667D01*
X573860Y155375D01*
X574068Y155083D01*
X574318Y154917D01*
X574610Y154875D01*
X574943Y154958D01*
X575193Y155167D01*
X575443Y155542D01*
G01X578210Y154000D02*
Y156500D01*
X576668Y154708D01*
X578752D01*
G01X503300Y163000D02*
Y160500D01*
G01X502342Y163000D02*
X504258D01*
G01X505567Y160500D02*
Y163000D01*
X506567D01*
X506900Y162875D01*
X507150Y162583D01*
X507233Y162250D01*
X507150Y161917D01*
X506942Y161667D01*
X506567Y161542D01*
X505567D01*
G01X509500Y160500D02*
Y163000D01*
X509000Y162500D01*
G01Y160500D02*
X510000D01*
G01X511683Y160875D02*
X511933Y160667D01*
X512225Y160542D01*
X512600Y160500D01*
X512975Y160583D01*
X513267Y160750D01*
X513475Y161042D01*
X513517Y161375D01*
X513433Y161708D01*
X513225Y161917D01*
X512933Y162083D01*
X512642Y162125D01*
X512350Y162083D01*
X511975Y161917D01*
X512100Y163000D01*
X513225D01*
G01X514908Y161542D02*
X515200Y161833D01*
X515450Y162000D01*
X515783Y162083D01*
X516075Y162000D01*
X516283Y161833D01*
X516450Y161583D01*
X516492Y161292D01*
X516450Y161042D01*
X516283Y160792D01*
X516033Y160583D01*
X515742Y160500D01*
X515408Y160583D01*
X515117Y160833D01*
X514950Y161208D01*
X514908Y161625D01*
X514992Y162167D01*
X515117Y162458D01*
X515325Y162750D01*
X515617Y162958D01*
X515908Y163000D01*
X516200Y162917D01*
X516408Y162708D01*
G01X574350Y118500D02*
X574017Y118542D01*
X573725Y118708D01*
X573475Y118958D01*
X573308Y119250D01*
X573225Y119583D01*
Y119917D01*
X573308Y120250D01*
X573475Y120542D01*
X573725Y120792D01*
X574017Y120958D01*
X574350Y121000D01*
X574683Y120958D01*
X574975Y120792D01*
X575225Y120542D01*
X575392Y120250D01*
X575475Y119917D01*
Y119583D01*
X575392Y119250D01*
X575225Y118958D01*
X574975Y118708D01*
X574683Y118542D01*
X574350Y118500D01*
G01X574683Y119167D02*
X575183Y118500D01*
G01X577450D02*
Y121000D01*
X576950Y120500D01*
G01Y118500D02*
X577950D01*
G01X581050D02*
Y121000D01*
X579508Y119208D01*
X581592D01*
G01X582858Y120583D02*
X583108Y120833D01*
X583400Y120958D01*
X583733Y121000D01*
X584150Y120917D01*
X584442Y120708D01*
X584525Y120458D01*
X584483Y120208D01*
X584317Y120000D01*
X583483Y119583D01*
X583108Y119292D01*
X582858Y118875D01*
X582775Y118500D01*
X584525D01*
G01X589300Y109100D02*
X570100D01*
Y97900D01*
X589300D01*
Y109100D01*
X588900D01*
G01X543500Y120350D02*
X543458Y120017D01*
X543292Y119725D01*
X543042Y119475D01*
X542750Y119308D01*
X542417Y119225D01*
X542083D01*
X541750Y119308D01*
X541458Y119475D01*
X541208Y119725D01*
X541042Y120017D01*
X541000Y120350D01*
X541042Y120683D01*
X541208Y120975D01*
X541458Y121225D01*
X541750Y121392D01*
X542083Y121475D01*
X542417D01*
X542750Y121392D01*
X543042Y121225D01*
X543292Y120975D01*
X543458Y120683D01*
X543500Y120350D01*
G01X542833Y120683D02*
X543500Y121183D01*
G01Y123450D02*
X541000D01*
X541500Y122950D01*
G01X543500D02*
Y123950D01*
G01Y127050D02*
X541000D01*
X542792Y125508D01*
Y127592D01*
G01X543500Y130150D02*
X541000D01*
X542792Y128608D01*
Y130692D01*
G01X544800Y123500D02*
X546900Y121700D01*
X544800Y119500D01*
G01X544700Y115900D02*
X563900D01*
Y127100D01*
X544700D01*
Y115900D01*
X545100D01*
G01X515000Y135517D02*
X512500D01*
Y136558D01*
X512625Y136892D01*
X512792Y137100D01*
X513125Y137183D01*
X513458Y137100D01*
X513667Y136850D01*
X513792Y136558D01*
Y135517D01*
G01Y136558D02*
X515000Y137183D01*
G01X513958Y138658D02*
X513667Y138950D01*
X513500Y139200D01*
X513417Y139533D01*
X513500Y139825D01*
X513667Y140033D01*
X513917Y140200D01*
X514208Y140242D01*
X514458Y140200D01*
X514708Y140033D01*
X514917Y139783D01*
X515000Y139492D01*
X514917Y139158D01*
X514667Y138867D01*
X514292Y138700D01*
X513875Y138658D01*
X513333Y138742D01*
X513042Y138867D01*
X512750Y139075D01*
X512542Y139367D01*
X512500Y139658D01*
X512583Y139950D01*
X512792Y140158D01*
G01X514708Y141842D02*
X514917Y142133D01*
X515000Y142467D01*
X514917Y142800D01*
X514667Y143092D01*
X514292Y143300D01*
X513917Y143383D01*
X513458D01*
X513083Y143300D01*
X512750Y143092D01*
X512583Y142842D01*
X512500Y142550D01*
X512583Y142217D01*
X512750Y141967D01*
X513000Y141800D01*
X513333Y141717D01*
X513625Y141800D01*
X513917Y142008D01*
X514083Y142258D01*
X514125Y142550D01*
X514042Y142883D01*
X513833Y143133D01*
X513458Y143383D01*
G01X514625Y144733D02*
X514833Y144983D01*
X514958Y145275D01*
X515000Y145650D01*
X514917Y146025D01*
X514750Y146317D01*
X514458Y146525D01*
X514125Y146567D01*
X513792Y146483D01*
X513583Y146275D01*
X513417Y145983D01*
X513375Y145692D01*
X513417Y145400D01*
X513583Y145025D01*
X512500Y145150D01*
Y146275D01*
G01X569267Y152292D02*
X569017Y152417D01*
X568725Y152500D01*
X568392D01*
X568017Y152375D01*
X567725Y152167D01*
X567517Y151917D01*
X567350Y151500D01*
X567308Y151125D01*
X567392Y150750D01*
X567517Y150500D01*
X567767Y150250D01*
X568058Y150083D01*
X568350Y150000D01*
X568642D01*
X568933Y150083D01*
X569183Y150208D01*
X569392Y150375D01*
G01X570533Y150500D02*
X570783Y150208D01*
X571117Y150042D01*
X571492Y150000D01*
X571825Y150042D01*
X572158Y150250D01*
X572367Y150500D01*
X572408Y150750D01*
X572325Y151042D01*
X572033Y151250D01*
X571742Y151333D01*
X571367D01*
G01X571742D02*
X571992Y151458D01*
X572200Y151667D01*
X572283Y151917D01*
X572200Y152167D01*
X571992Y152375D01*
X571617Y152500D01*
X571242Y152458D01*
X570867Y152292D01*
G01X573842Y150292D02*
X574133Y150083D01*
X574467Y150000D01*
X574800Y150083D01*
X575092Y150333D01*
X575300Y150708D01*
X575383Y151083D01*
Y151542D01*
X575300Y151917D01*
X575092Y152250D01*
X574842Y152417D01*
X574550Y152500D01*
X574217Y152417D01*
X573967Y152250D01*
X573800Y152000D01*
X573717Y151667D01*
X573800Y151375D01*
X574008Y151083D01*
X574258Y150917D01*
X574550Y150875D01*
X574883Y150958D01*
X575133Y151167D01*
X575383Y151542D01*
G01X576733Y150375D02*
X576983Y150167D01*
X577275Y150042D01*
X577650Y150000D01*
X578025Y150083D01*
X578317Y150250D01*
X578525Y150542D01*
X578567Y150875D01*
X578483Y151208D01*
X578275Y151417D01*
X577983Y151583D01*
X577692Y151625D01*
X577400Y151583D01*
X577025Y151417D01*
X577150Y152500D01*
X578275D01*
G01X567200Y130000D02*
X572700D01*
G01X567200Y122000D02*
Y130000D01*
G01X572700Y122000D02*
X567200D01*
G01X567517Y158000D02*
Y160500D01*
X568558D01*
X568892Y160375D01*
X569100Y160208D01*
X569183Y159875D01*
X569100Y159542D01*
X568850Y159333D01*
X568558Y159208D01*
X567517D01*
G01X568558D02*
X569183Y158000D01*
G01X571367D02*
X571450Y158542D01*
X571575Y159000D01*
X571742Y159417D01*
X571950Y159875D01*
X572283Y160500D01*
X570617D01*
G01X574550Y158000D02*
Y160500D01*
X574050Y160000D01*
G01Y158000D02*
X575050D01*
G01X576733Y158375D02*
X576983Y158167D01*
X577275Y158042D01*
X577650Y158000D01*
X578025Y158083D01*
X578317Y158250D01*
X578525Y158542D01*
X578567Y158875D01*
X578483Y159208D01*
X578275Y159417D01*
X577983Y159583D01*
X577692Y159625D01*
X577400Y159583D01*
X577025Y159417D01*
X577150Y160500D01*
X578275D01*
G01X562700Y136500D02*
Y144500D01*
X580300D01*
Y136500D01*
X562700D01*
G01X551767Y147792D02*
X551517Y147917D01*
X551225Y148000D01*
X550892D01*
X550517Y147875D01*
X550225Y147667D01*
X550017Y147417D01*
X549850Y147000D01*
X549808Y146625D01*
X549892Y146250D01*
X550017Y146000D01*
X550267Y145750D01*
X550558Y145583D01*
X550850Y145500D01*
X551142D01*
X551433Y145583D01*
X551683Y145708D01*
X551892Y145875D01*
G01X553033Y146000D02*
X553283Y145708D01*
X553617Y145542D01*
X553992Y145500D01*
X554325Y145542D01*
X554658Y145750D01*
X554867Y146000D01*
X554908Y146250D01*
X554825Y146542D01*
X554533Y146750D01*
X554242Y146833D01*
X553867D01*
G01X554242D02*
X554492Y146958D01*
X554700Y147167D01*
X554783Y147417D01*
X554700Y147667D01*
X554492Y147875D01*
X554117Y148000D01*
X553742Y147958D01*
X553367Y147792D01*
G01X556342Y145792D02*
X556633Y145583D01*
X556967Y145500D01*
X557300Y145583D01*
X557592Y145833D01*
X557800Y146208D01*
X557883Y146583D01*
Y147042D01*
X557800Y147417D01*
X557592Y147750D01*
X557342Y147917D01*
X557050Y148000D01*
X556717Y147917D01*
X556467Y147750D01*
X556300Y147500D01*
X556217Y147167D01*
X556300Y146875D01*
X556508Y146583D01*
X556758Y146417D01*
X557050Y146375D01*
X557383Y146458D01*
X557633Y146667D01*
X557883Y147042D01*
G01X560150Y145500D02*
X560442Y145542D01*
X560775Y145667D01*
X560983Y145875D01*
X561067Y146167D01*
X560983Y146458D01*
X560733Y146708D01*
X560358Y146833D01*
X559942D01*
X559692Y146917D01*
X559483Y147125D01*
X559400Y147417D01*
X559525Y147708D01*
X559817Y147917D01*
X560150Y148000D01*
X560483Y147917D01*
X560775Y147708D01*
X560900Y147417D01*
X560817Y147125D01*
X560608Y146917D01*
X560358Y146833D01*
X559942D01*
X559567Y146708D01*
X559317Y146458D01*
X559233Y146167D01*
X559317Y145875D01*
X559525Y145667D01*
X559858Y145542D01*
X560150Y145500D01*
G01X576267Y173292D02*
X576017Y173417D01*
X575725Y173500D01*
X575392D01*
X575017Y173375D01*
X574725Y173167D01*
X574517Y172917D01*
X574350Y172500D01*
X574308Y172125D01*
X574392Y171750D01*
X574517Y171500D01*
X574767Y171250D01*
X575058Y171083D01*
X575350Y171000D01*
X575642D01*
X575933Y171083D01*
X576183Y171208D01*
X576392Y171375D01*
G01X577533Y171500D02*
X577783Y171208D01*
X578117Y171042D01*
X578492Y171000D01*
X578825Y171042D01*
X579158Y171250D01*
X579367Y171500D01*
X579408Y171750D01*
X579325Y172042D01*
X579033Y172250D01*
X578742Y172333D01*
X578367D01*
G01X578742D02*
X578992Y172458D01*
X579200Y172667D01*
X579283Y172917D01*
X579200Y173167D01*
X578992Y173375D01*
X578617Y173500D01*
X578242Y173458D01*
X577867Y173292D01*
G01X580842Y171292D02*
X581133Y171083D01*
X581467Y171000D01*
X581800Y171083D01*
X582092Y171333D01*
X582300Y171708D01*
X582383Y172083D01*
Y172542D01*
X582300Y172917D01*
X582092Y173250D01*
X581842Y173417D01*
X581550Y173500D01*
X581217Y173417D01*
X580967Y173250D01*
X580800Y173000D01*
X580717Y172667D01*
X580800Y172375D01*
X581008Y172083D01*
X581258Y171917D01*
X581550Y171875D01*
X581883Y171958D01*
X582133Y172167D01*
X582383Y172542D01*
G01X583942Y171292D02*
X584233Y171083D01*
X584567Y171000D01*
X584900Y171083D01*
X585192Y171333D01*
X585400Y171708D01*
X585483Y172083D01*
Y172542D01*
X585400Y172917D01*
X585192Y173250D01*
X584942Y173417D01*
X584650Y173500D01*
X584317Y173417D01*
X584067Y173250D01*
X583900Y173000D01*
X583817Y172667D01*
X583900Y172375D01*
X584108Y172083D01*
X584358Y171917D01*
X584650Y171875D01*
X584983Y171958D01*
X585233Y172167D01*
X585483Y172542D01*
G01X559467Y269000D02*
Y266500D01*
X561133D01*
G01X564233D02*
X562567D01*
Y269000D01*
X564233D01*
G01X563567Y267792D02*
X562567D01*
G01X565583Y266500D02*
Y269000D01*
X566417D01*
X566750Y268875D01*
X567000Y268708D01*
X567208Y268458D01*
X567375Y268167D01*
X567417Y267750D01*
X567375Y267333D01*
X567208Y267042D01*
X567000Y266792D01*
X566750Y266625D01*
X566417Y266500D01*
X565583D01*
G01X569600D02*
Y269000D01*
X569100Y268500D01*
G01Y266500D02*
X570100D01*
G01X572617D02*
X572700Y267042D01*
X572825Y267500D01*
X572992Y267917D01*
X573200Y268375D01*
X573533Y269000D01*
X571867D01*
G01X562529Y251880D02*
Y263080D01*
X571329D01*
Y251880D01*
X562529D01*
G01X525517Y382500D02*
Y385000D01*
X526558D01*
X526892Y384875D01*
X527100Y384708D01*
X527183Y384375D01*
X527100Y384042D01*
X526850Y383833D01*
X526558Y383708D01*
X525517D01*
G01X526558D02*
X527183Y382500D01*
G01X528533Y383000D02*
X528783Y382708D01*
X529117Y382542D01*
X529492Y382500D01*
X529825Y382542D01*
X530158Y382750D01*
X530367Y383000D01*
X530408Y383250D01*
X530325Y383542D01*
X530033Y383750D01*
X529742Y383833D01*
X529367D01*
G01X529742D02*
X529992Y383958D01*
X530200Y384167D01*
X530283Y384417D01*
X530200Y384667D01*
X529992Y384875D01*
X529617Y385000D01*
X529242Y384958D01*
X528867Y384792D01*
G01X531842Y382792D02*
X532133Y382583D01*
X532467Y382500D01*
X532800Y382583D01*
X533092Y382833D01*
X533300Y383208D01*
X533383Y383583D01*
Y384042D01*
X533300Y384417D01*
X533092Y384750D01*
X532842Y384917D01*
X532550Y385000D01*
X532217Y384917D01*
X531967Y384750D01*
X531800Y384500D01*
X531717Y384167D01*
X531800Y383875D01*
X532008Y383583D01*
X532258Y383417D01*
X532550Y383375D01*
X532883Y383458D01*
X533133Y383667D01*
X533383Y384042D01*
G01X536150Y382500D02*
Y385000D01*
X534608Y383208D01*
X536692D01*
G01X545192Y381482D02*
Y385482D01*
X537792D01*
G01X548517Y406500D02*
Y409000D01*
X549558D01*
X549892Y408875D01*
X550100Y408708D01*
X550183Y408375D01*
X550100Y408042D01*
X549850Y407833D01*
X549558Y407708D01*
X548517D01*
G01X549558D02*
X550183Y406500D01*
G01X551533Y407000D02*
X551783Y406708D01*
X552117Y406542D01*
X552492Y406500D01*
X552825Y406542D01*
X553158Y406750D01*
X553367Y407000D01*
X553408Y407250D01*
X553325Y407542D01*
X553033Y407750D01*
X552742Y407833D01*
X552367D01*
G01X552742D02*
X552992Y407958D01*
X553200Y408167D01*
X553283Y408417D01*
X553200Y408667D01*
X552992Y408875D01*
X552617Y409000D01*
X552242Y408958D01*
X551867Y408792D01*
G01X555550Y406500D02*
X555842Y406542D01*
X556175Y406667D01*
X556383Y406875D01*
X556467Y407167D01*
X556383Y407458D01*
X556133Y407708D01*
X555758Y407833D01*
X555342D01*
X555092Y407917D01*
X554883Y408125D01*
X554800Y408417D01*
X554925Y408708D01*
X555217Y408917D01*
X555550Y409000D01*
X555883Y408917D01*
X556175Y408708D01*
X556300Y408417D01*
X556217Y408125D01*
X556008Y407917D01*
X555758Y407833D01*
X555342D01*
X554967Y407708D01*
X554717Y407458D01*
X554633Y407167D01*
X554717Y406875D01*
X554925Y406667D01*
X555258Y406542D01*
X555550Y406500D01*
G01X557942Y406792D02*
X558233Y406583D01*
X558567Y406500D01*
X558900Y406583D01*
X559192Y406833D01*
X559400Y407208D01*
X559483Y407583D01*
Y408042D01*
X559400Y408417D01*
X559192Y408750D01*
X558942Y408917D01*
X558650Y409000D01*
X558317Y408917D01*
X558067Y408750D01*
X557900Y408500D01*
X557817Y408167D01*
X557900Y407875D01*
X558108Y407583D01*
X558358Y407417D01*
X558650Y407375D01*
X558983Y407458D01*
X559233Y407667D01*
X559483Y408042D01*
G01X559925Y401259D02*
Y405259D01*
X552525D01*
G01X565900Y399817D02*
X563400D01*
Y400858D01*
X563525Y401192D01*
X563692Y401400D01*
X564025Y401483D01*
X564358Y401400D01*
X564567Y401150D01*
X564692Y400858D01*
Y399817D01*
G01Y400858D02*
X565900Y401483D01*
G01Y404250D02*
X563400D01*
X565192Y402708D01*
Y404792D01*
G01X565900Y406850D02*
X563400D01*
X563900Y406350D01*
G01X565900D02*
Y407350D01*
G01Y409950D02*
X563400D01*
X563900Y409450D01*
G01X565900D02*
Y410450D01*
G01X569900Y399817D02*
X567400D01*
Y400858D01*
X567525Y401192D01*
X567692Y401400D01*
X568025Y401483D01*
X568358Y401400D01*
X568567Y401150D01*
X568692Y400858D01*
Y399817D01*
G01Y400858D02*
X569900Y401483D01*
G01Y404250D02*
X567400D01*
X569192Y402708D01*
Y404792D01*
G01X567817Y406058D02*
X567567Y406308D01*
X567442Y406600D01*
X567400Y406933D01*
X567483Y407350D01*
X567692Y407642D01*
X567942Y407725D01*
X568192Y407683D01*
X568400Y407517D01*
X568817Y406683D01*
X569108Y406308D01*
X569525Y406058D01*
X569900Y405975D01*
Y407725D01*
G01Y409950D02*
X567400D01*
X567900Y409450D01*
G01X569900D02*
Y410450D01*
G01X549350Y381500D02*
X549017Y381542D01*
X548725Y381708D01*
X548475Y381958D01*
X548308Y382250D01*
X548225Y382583D01*
Y382917D01*
X548308Y383250D01*
X548475Y383542D01*
X548725Y383792D01*
X549017Y383958D01*
X549350Y384000D01*
X549683Y383958D01*
X549975Y383792D01*
X550225Y383542D01*
X550392Y383250D01*
X550475Y382917D01*
Y382583D01*
X550392Y382250D01*
X550225Y381958D01*
X549975Y381708D01*
X549683Y381542D01*
X549350Y381500D01*
G01X549683Y382167D02*
X550183Y381500D01*
G01X551658Y383583D02*
X551908Y383833D01*
X552200Y383958D01*
X552533Y384000D01*
X552950Y383917D01*
X553242Y383708D01*
X553325Y383458D01*
X553283Y383208D01*
X553117Y383000D01*
X552283Y382583D01*
X551908Y382292D01*
X551658Y381875D01*
X551575Y381500D01*
X553325D01*
G01X554633Y382000D02*
X554883Y381708D01*
X555217Y381542D01*
X555592Y381500D01*
X555925Y381542D01*
X556258Y381750D01*
X556467Y382000D01*
X556508Y382250D01*
X556425Y382542D01*
X556133Y382750D01*
X555842Y382833D01*
X555467D01*
G01X555842D02*
X556092Y382958D01*
X556300Y383167D01*
X556383Y383417D01*
X556300Y383667D01*
X556092Y383875D01*
X555717Y384000D01*
X555342Y383958D01*
X554967Y383792D01*
G01X557733Y381875D02*
X557983Y381667D01*
X558275Y381542D01*
X558650Y381500D01*
X559025Y381583D01*
X559317Y381750D01*
X559525Y382042D01*
X559567Y382375D01*
X559483Y382708D01*
X559275Y382917D01*
X558983Y383083D01*
X558692Y383125D01*
X558400Y383083D01*
X558025Y382917D01*
X558150Y384000D01*
X559275D01*
G01X560600Y385800D02*
Y399800D01*
G01X547600Y385800D02*
X560600D01*
G01X547600Y399800D02*
Y385800D01*
G01X560600Y399800D02*
X547600D01*
G01X530350Y401500D02*
X530017Y401542D01*
X529725Y401708D01*
X529475Y401958D01*
X529308Y402250D01*
X529225Y402583D01*
Y402917D01*
X529308Y403250D01*
X529475Y403542D01*
X529725Y403792D01*
X530017Y403958D01*
X530350Y404000D01*
X530683Y403958D01*
X530975Y403792D01*
X531225Y403542D01*
X531392Y403250D01*
X531475Y402917D01*
Y402583D01*
X531392Y402250D01*
X531225Y401958D01*
X530975Y401708D01*
X530683Y401542D01*
X530350Y401500D01*
G01X530683Y402167D02*
X531183Y401500D01*
G01X532658Y403583D02*
X532908Y403833D01*
X533200Y403958D01*
X533533Y404000D01*
X533950Y403917D01*
X534242Y403708D01*
X534325Y403458D01*
X534283Y403208D01*
X534117Y403000D01*
X533283Y402583D01*
X532908Y402292D01*
X532658Y401875D01*
X532575Y401500D01*
X534325D01*
G01X535758Y402542D02*
X536050Y402833D01*
X536300Y403000D01*
X536633Y403083D01*
X536925Y403000D01*
X537133Y402833D01*
X537300Y402583D01*
X537342Y402292D01*
X537300Y402042D01*
X537133Y401792D01*
X536883Y401583D01*
X536592Y401500D01*
X536258Y401583D01*
X535967Y401833D01*
X535800Y402208D01*
X535758Y402625D01*
X535842Y403167D01*
X535967Y403458D01*
X536175Y403750D01*
X536467Y403958D01*
X536758Y404000D01*
X537050Y403917D01*
X537258Y403708D01*
G01X538733Y401875D02*
X538983Y401667D01*
X539275Y401542D01*
X539650Y401500D01*
X540025Y401583D01*
X540317Y401750D01*
X540525Y402042D01*
X540567Y402375D01*
X540483Y402708D01*
X540275Y402917D01*
X539983Y403083D01*
X539692Y403125D01*
X539400Y403083D01*
X539025Y402917D01*
X539150Y404000D01*
X540275D01*
G01X532492Y386707D02*
X546492D01*
G01X532492Y399707D02*
Y386707D01*
G01X546492Y399707D02*
X532492D01*
G01X546492Y386707D02*
Y399707D01*
G01X511713Y509928D02*
X511463Y510053D01*
X511171Y510136D01*
X510838D01*
X510463Y510011D01*
X510171Y509803D01*
X509963Y509553D01*
X509796Y509136D01*
X509754Y508761D01*
X509838Y508386D01*
X509963Y508136D01*
X510213Y507886D01*
X510504Y507719D01*
X510796Y507636D01*
X511088D01*
X511379Y507719D01*
X511629Y507844D01*
X511838Y508011D01*
G01X513104Y509719D02*
X513354Y509969D01*
X513646Y510094D01*
X513979Y510136D01*
X514396Y510053D01*
X514688Y509844D01*
X514771Y509594D01*
X514729Y509344D01*
X514563Y509136D01*
X513729Y508719D01*
X513354Y508428D01*
X513104Y508011D01*
X513021Y507636D01*
X514771D01*
G01X516204Y509719D02*
X516454Y509969D01*
X516746Y510094D01*
X517079Y510136D01*
X517496Y510053D01*
X517788Y509844D01*
X517871Y509594D01*
X517829Y509344D01*
X517663Y509136D01*
X516829Y508719D01*
X516454Y508428D01*
X516204Y508011D01*
X516121Y507636D01*
X517871D01*
G01X520596D02*
Y510136D01*
X519054Y508344D01*
X521138D01*
G01X511767Y514292D02*
X511517Y514417D01*
X511225Y514500D01*
X510892D01*
X510517Y514375D01*
X510225Y514167D01*
X510017Y513917D01*
X509850Y513500D01*
X509808Y513125D01*
X509892Y512750D01*
X510017Y512500D01*
X510267Y512250D01*
X510558Y512083D01*
X510850Y512000D01*
X511142D01*
X511433Y512083D01*
X511683Y512208D01*
X511892Y512375D01*
G01X513158Y514083D02*
X513408Y514333D01*
X513700Y514458D01*
X514033Y514500D01*
X514450Y514417D01*
X514742Y514208D01*
X514825Y513958D01*
X514783Y513708D01*
X514617Y513500D01*
X513783Y513083D01*
X513408Y512792D01*
X513158Y512375D01*
X513075Y512000D01*
X514825D01*
G01X516258Y514083D02*
X516508Y514333D01*
X516800Y514458D01*
X517133Y514500D01*
X517550Y514417D01*
X517842Y514208D01*
X517925Y513958D01*
X517883Y513708D01*
X517717Y513500D01*
X516883Y513083D01*
X516508Y512792D01*
X516258Y512375D01*
X516175Y512000D01*
X517925D01*
G01X519233Y512500D02*
X519483Y512208D01*
X519817Y512042D01*
X520192Y512000D01*
X520525Y512042D01*
X520858Y512250D01*
X521067Y512500D01*
X521108Y512750D01*
X521025Y513042D01*
X520733Y513250D01*
X520442Y513333D01*
X520067D01*
G01X520442D02*
X520692Y513458D01*
X520900Y513667D01*
X520983Y513917D01*
X520900Y514167D01*
X520692Y514375D01*
X520317Y514500D01*
X519942Y514458D01*
X519567Y514292D01*
G01X547767Y544453D02*
X547517Y544578D01*
X547225Y544661D01*
X546892D01*
X546517Y544536D01*
X546225Y544328D01*
X546017Y544078D01*
X545850Y543661D01*
X545808Y543286D01*
X545892Y542911D01*
X546017Y542661D01*
X546267Y542411D01*
X546558Y542244D01*
X546850Y542161D01*
X547142D01*
X547433Y542244D01*
X547683Y542369D01*
X547892Y542536D01*
G01X549158Y544244D02*
X549408Y544494D01*
X549700Y544619D01*
X550033Y544661D01*
X550450Y544578D01*
X550742Y544369D01*
X550825Y544119D01*
X550783Y543869D01*
X550617Y543661D01*
X549783Y543244D01*
X549408Y542953D01*
X549158Y542536D01*
X549075Y542161D01*
X550825D01*
G01X553550D02*
Y544661D01*
X552008Y542869D01*
X554092D01*
G01X555358Y543203D02*
X555650Y543494D01*
X555900Y543661D01*
X556233Y543744D01*
X556525Y543661D01*
X556733Y543494D01*
X556900Y543244D01*
X556942Y542953D01*
X556900Y542703D01*
X556733Y542453D01*
X556483Y542244D01*
X556192Y542161D01*
X555858Y542244D01*
X555567Y542494D01*
X555400Y542869D01*
X555358Y543286D01*
X555442Y543828D01*
X555567Y544119D01*
X555775Y544411D01*
X556067Y544619D01*
X556358Y544661D01*
X556650Y544578D01*
X556858Y544369D01*
G01X540267Y553953D02*
X540017Y554078D01*
X539725Y554161D01*
X539392D01*
X539017Y554036D01*
X538725Y553828D01*
X538517Y553578D01*
X538350Y553161D01*
X538308Y552786D01*
X538392Y552411D01*
X538517Y552161D01*
X538767Y551911D01*
X539058Y551744D01*
X539350Y551661D01*
X539642D01*
X539933Y551744D01*
X540183Y551869D01*
X540392Y552036D01*
G01X541658Y553744D02*
X541908Y553994D01*
X542200Y554119D01*
X542533Y554161D01*
X542950Y554078D01*
X543242Y553869D01*
X543325Y553619D01*
X543283Y553369D01*
X543117Y553161D01*
X542283Y552744D01*
X541908Y552453D01*
X541658Y552036D01*
X541575Y551661D01*
X543325D01*
G01X546050D02*
Y554161D01*
X544508Y552369D01*
X546592D01*
G01X548567Y551661D02*
X548650Y552203D01*
X548775Y552661D01*
X548942Y553078D01*
X549150Y553536D01*
X549483Y554161D01*
X547817D01*
G01X546017Y538161D02*
Y540661D01*
X547058D01*
X547392Y540536D01*
X547600Y540369D01*
X547683Y540036D01*
X547600Y539703D01*
X547350Y539494D01*
X547058Y539369D01*
X546017D01*
G01X547058D02*
X547683Y538161D01*
G01X550450D02*
Y540661D01*
X548908Y538869D01*
X550992D01*
G01X553550Y538161D02*
Y540661D01*
X552008Y538869D01*
X554092D01*
G01X555233Y538536D02*
X555483Y538328D01*
X555775Y538203D01*
X556150Y538161D01*
X556525Y538244D01*
X556817Y538411D01*
X557025Y538703D01*
X557067Y539036D01*
X556983Y539369D01*
X556775Y539578D01*
X556483Y539744D01*
X556192Y539786D01*
X555900Y539744D01*
X555525Y539578D01*
X555650Y540661D01*
X556775D01*
G01X559300Y545500D02*
Y541500D01*
X566700D01*
G01X547017Y511500D02*
Y514000D01*
X548058D01*
X548392Y513875D01*
X548600Y513708D01*
X548683Y513375D01*
X548600Y513042D01*
X548350Y512833D01*
X548058Y512708D01*
X547017D01*
G01X548058D02*
X548683Y511500D01*
G01X551450D02*
Y514000D01*
X549908Y512208D01*
X551992D01*
G01X553133Y511875D02*
X553383Y511667D01*
X553675Y511542D01*
X554050Y511500D01*
X554425Y511583D01*
X554717Y511750D01*
X554925Y512042D01*
X554967Y512375D01*
X554883Y512708D01*
X554675Y512917D01*
X554383Y513083D01*
X554092Y513125D01*
X553800Y513083D01*
X553425Y512917D01*
X553550Y514000D01*
X554675D01*
G01X556358Y513583D02*
X556608Y513833D01*
X556900Y513958D01*
X557233Y514000D01*
X557650Y513917D01*
X557942Y513708D01*
X558025Y513458D01*
X557983Y513208D01*
X557817Y513000D01*
X556983Y512583D01*
X556608Y512292D01*
X556358Y511875D01*
X556275Y511500D01*
X558025D01*
G01X551800Y520000D02*
Y516000D01*
X559200D01*
G01X538517Y547661D02*
Y550161D01*
X539558D01*
X539892Y550036D01*
X540100Y549869D01*
X540183Y549536D01*
X540100Y549203D01*
X539850Y548994D01*
X539558Y548869D01*
X538517D01*
G01X539558D02*
X540183Y547661D01*
G01X542950D02*
Y550161D01*
X541408Y548369D01*
X543492D01*
G01X544633Y548036D02*
X544883Y547828D01*
X545175Y547703D01*
X545550Y547661D01*
X545925Y547744D01*
X546217Y547911D01*
X546425Y548203D01*
X546467Y548536D01*
X546383Y548869D01*
X546175Y549078D01*
X545883Y549244D01*
X545592Y549286D01*
X545300Y549244D01*
X544925Y549078D01*
X545050Y550161D01*
X546175D01*
G01X547733Y548161D02*
X547983Y547869D01*
X548317Y547703D01*
X548692Y547661D01*
X549025Y547703D01*
X549358Y547911D01*
X549567Y548161D01*
X549608Y548411D01*
X549525Y548703D01*
X549233Y548911D01*
X548942Y548994D01*
X548567D01*
G01X548942D02*
X549192Y549119D01*
X549400Y549328D01*
X549483Y549578D01*
X549400Y549828D01*
X549192Y550036D01*
X548817Y550161D01*
X548442Y550119D01*
X548067Y549953D01*
G01X559200Y547000D02*
Y551000D01*
X551800D01*
G01X553000Y521517D02*
X550500D01*
Y522558D01*
X550625Y522892D01*
X550792Y523100D01*
X551125Y523183D01*
X551458Y523100D01*
X551667Y522850D01*
X551792Y522558D01*
Y521517D01*
G01Y522558D02*
X553000Y523183D01*
G01Y525950D02*
X550500D01*
X552292Y524408D01*
Y526492D01*
G01X552625Y527633D02*
X552833Y527883D01*
X552958Y528175D01*
X553000Y528550D01*
X552917Y528925D01*
X552750Y529217D01*
X552458Y529425D01*
X552125Y529467D01*
X551792Y529383D01*
X551583Y529175D01*
X551417Y528883D01*
X551375Y528592D01*
X551417Y528300D01*
X551583Y527925D01*
X550500Y528050D01*
Y529175D01*
G01X553000Y532150D02*
X550500D01*
X552292Y530608D01*
Y532692D01*
G01X555000Y520300D02*
X559000D01*
Y527700D01*
G01X570500Y502517D02*
X568000D01*
Y503558D01*
X568125Y503892D01*
X568292Y504100D01*
X568625Y504183D01*
X568958Y504100D01*
X569167Y503850D01*
X569292Y503558D01*
Y502517D01*
G01Y503558D02*
X570500Y504183D01*
G01Y506950D02*
X568000D01*
X569792Y505408D01*
Y507492D01*
G01X570125Y508633D02*
X570333Y508883D01*
X570458Y509175D01*
X570500Y509550D01*
X570417Y509925D01*
X570250Y510217D01*
X569958Y510425D01*
X569625Y510467D01*
X569292Y510383D01*
X569083Y510175D01*
X568917Y509883D01*
X568875Y509592D01*
X568917Y509300D01*
X569083Y508925D01*
X568000Y509050D01*
Y510175D01*
G01X570125Y511733D02*
X570333Y511983D01*
X570458Y512275D01*
X570500Y512650D01*
X570417Y513025D01*
X570250Y513317D01*
X569958Y513525D01*
X569625Y513567D01*
X569292Y513483D01*
X569083Y513275D01*
X568917Y512983D01*
X568875Y512692D01*
X568917Y512400D01*
X569083Y512025D01*
X568000Y512150D01*
Y513275D01*
G01X571500Y521700D02*
X567500D01*
Y514300D01*
G01X575900Y571000D02*
X575567Y571042D01*
X575275Y571208D01*
X575025Y571458D01*
X574858Y571750D01*
X574775Y572083D01*
Y572417D01*
X574858Y572750D01*
X575025Y573042D01*
X575275Y573292D01*
X575567Y573458D01*
X575900Y573500D01*
X576233Y573458D01*
X576525Y573292D01*
X576775Y573042D01*
X576942Y572750D01*
X577025Y572417D01*
Y572083D01*
X576942Y571750D01*
X576775Y571458D01*
X576525Y571208D01*
X576233Y571042D01*
X575900Y571000D01*
G01X576233Y571667D02*
X576733Y571000D01*
G01X578917D02*
X579000Y571542D01*
X579125Y572000D01*
X579292Y572417D01*
X579500Y572875D01*
X579833Y573500D01*
X578167D01*
G01X582100D02*
X581767Y573417D01*
X581517Y573208D01*
X581350Y572958D01*
X581225Y572625D01*
X581183Y572250D01*
X581225Y571875D01*
X581350Y571542D01*
X581517Y571292D01*
X581767Y571083D01*
X582100Y571000D01*
X582433Y571083D01*
X582683Y571292D01*
X582850Y571542D01*
X582975Y571875D01*
X583017Y572250D01*
X582975Y572625D01*
X582850Y572958D01*
X582683Y573208D01*
X582433Y573417D01*
X582100Y573500D01*
G01X589300Y561600D02*
X570100D01*
Y550400D01*
X589300D01*
Y561600D01*
X588900D01*
G01X544700Y568400D02*
X563900D01*
Y579600D01*
X544700D01*
Y568400D01*
X545100D01*
G01X564500Y504983D02*
X562000D01*
Y505817D01*
X562125Y506150D01*
X562292Y506400D01*
X562542Y506608D01*
X562833Y506775D01*
X563250Y506817D01*
X563667Y506775D01*
X563958Y506608D01*
X564208Y506400D01*
X564375Y506150D01*
X564500Y505817D01*
Y504983D01*
G01Y509000D02*
X562000D01*
X562500Y508500D01*
G01X564500D02*
Y509500D01*
G01X563458Y511308D02*
X563167Y511600D01*
X563000Y511850D01*
X562917Y512183D01*
X563000Y512475D01*
X563167Y512683D01*
X563417Y512850D01*
X563708Y512892D01*
X563958Y512850D01*
X564208Y512683D01*
X564417Y512433D01*
X564500Y512142D01*
X564417Y511808D01*
X564167Y511517D01*
X563792Y511350D01*
X563375Y511308D01*
X562833Y511392D01*
X562542Y511517D01*
X562250Y511725D01*
X562042Y512017D01*
X562000Y512308D01*
X562083Y512600D01*
X562292Y512808D01*
G01X567000Y530500D02*
Y514400D01*
G01X560000Y530500D02*
X567000D01*
G01X560000Y514400D02*
Y530500D01*
G01X567000Y514400D02*
X560000D01*
G01X571000Y529400D02*
X570958Y529067D01*
X570792Y528775D01*
X570542Y528525D01*
X570250Y528358D01*
X569917Y528275D01*
X569583D01*
X569250Y528358D01*
X568958Y528525D01*
X568708Y528775D01*
X568542Y529067D01*
X568500Y529400D01*
X568542Y529733D01*
X568708Y530025D01*
X568958Y530275D01*
X569250Y530442D01*
X569583Y530525D01*
X569917D01*
X570250Y530442D01*
X570542Y530275D01*
X570792Y530025D01*
X570958Y529733D01*
X571000Y529400D01*
G01X570333Y529733D02*
X571000Y530233D01*
G01Y532417D02*
X570458Y532500D01*
X570000Y532625D01*
X569583Y532792D01*
X569125Y533000D01*
X568500Y533333D01*
Y531667D01*
G01X571000Y535600D02*
X568500D01*
X569000Y535100D01*
G01X571000D02*
Y536100D01*
G01X583200Y536200D02*
X571800D01*
G01Y522800D02*
X583200D01*
G01X571800Y536200D02*
Y522800D01*
G01X503730Y623929D02*
X501230D01*
G01Y625679D02*
X503730D01*
G01X502480D02*
Y623929D01*
G01X503730Y626987D02*
X501230D01*
Y627821D01*
X501355Y628154D01*
X501522Y628404D01*
X501772Y628612D01*
X502063Y628779D01*
X502480Y628821D01*
X502897Y628779D01*
X503188Y628612D01*
X503438Y628404D01*
X503605Y628154D01*
X503730Y627821D01*
Y626987D01*
G01Y630087D02*
X501230D01*
Y630921D01*
X501355Y631254D01*
X501522Y631504D01*
X501772Y631712D01*
X502063Y631879D01*
X502480Y631921D01*
X502897Y631879D01*
X503188Y631712D01*
X503438Y631504D01*
X503605Y631254D01*
X503730Y630921D01*
Y630087D01*
G01X503397Y633229D02*
X503605Y633562D01*
X503730Y633937D01*
Y634271D01*
X503605Y634604D01*
X503397Y634854D01*
X503105Y634979D01*
X502813Y634896D01*
X502563Y634687D01*
X502397Y634312D01*
X502313Y633812D01*
X502147Y633521D01*
X501855Y633396D01*
X501563Y633479D01*
X501355Y633687D01*
X501230Y633979D01*
Y634271D01*
X501313Y634562D01*
X501522Y634812D01*
G01X503730Y636162D02*
X501230Y637204D01*
X503730Y638246D01*
G01X502855Y637871D02*
Y636537D01*
G01X503397Y639429D02*
X503605Y639762D01*
X503730Y640137D01*
Y640471D01*
X503605Y640804D01*
X503397Y641054D01*
X503105Y641179D01*
X502813Y641096D01*
X502563Y640887D01*
X502397Y640512D01*
X502313Y640012D01*
X502147Y639721D01*
X501855Y639596D01*
X501563Y639679D01*
X501355Y639887D01*
X501230Y640179D01*
Y640471D01*
X501313Y640762D01*
X501522Y641012D01*
G01X503730Y643404D02*
X501230D01*
X501730Y642904D01*
G01X503730D02*
Y643904D01*
G01X503355Y645587D02*
X503563Y645837D01*
X503688Y646129D01*
X503730Y646504D01*
X503647Y646879D01*
X503480Y647171D01*
X503188Y647379D01*
X502855Y647421D01*
X502522Y647337D01*
X502313Y647129D01*
X502147Y646837D01*
X502105Y646546D01*
X502147Y646254D01*
X502313Y645879D01*
X501230Y646004D01*
Y647129D01*
G01X518767Y576453D02*
X518517Y576578D01*
X518225Y576661D01*
X517892D01*
X517517Y576536D01*
X517225Y576328D01*
X517017Y576078D01*
X516850Y575661D01*
X516808Y575286D01*
X516892Y574911D01*
X517017Y574661D01*
X517267Y574411D01*
X517558Y574244D01*
X517850Y574161D01*
X518142D01*
X518433Y574244D01*
X518683Y574369D01*
X518892Y574536D01*
G01X520158Y576244D02*
X520408Y576494D01*
X520700Y576619D01*
X521033Y576661D01*
X521450Y576578D01*
X521742Y576369D01*
X521825Y576119D01*
X521783Y575869D01*
X521617Y575661D01*
X520783Y575244D01*
X520408Y574953D01*
X520158Y574536D01*
X520075Y574161D01*
X521825D01*
G01X523133Y574661D02*
X523383Y574369D01*
X523717Y574203D01*
X524092Y574161D01*
X524425Y574203D01*
X524758Y574411D01*
X524967Y574661D01*
X525008Y574911D01*
X524925Y575203D01*
X524633Y575411D01*
X524342Y575494D01*
X523967D01*
G01X524342D02*
X524592Y575619D01*
X524800Y575828D01*
X524883Y576078D01*
X524800Y576328D01*
X524592Y576536D01*
X524217Y576661D01*
X523842Y576619D01*
X523467Y576453D01*
G01X526358Y576244D02*
X526608Y576494D01*
X526900Y576619D01*
X527233Y576661D01*
X527650Y576578D01*
X527942Y576369D01*
X528025Y576119D01*
X527983Y575869D01*
X527817Y575661D01*
X526983Y575244D01*
X526608Y574953D01*
X526358Y574536D01*
X526275Y574161D01*
X528025D01*
G01X517017Y578161D02*
Y580661D01*
X518058D01*
X518392Y580536D01*
X518600Y580369D01*
X518683Y580036D01*
X518600Y579703D01*
X518350Y579494D01*
X518058Y579369D01*
X517017D01*
G01X518058D02*
X518683Y578161D01*
G01X521450D02*
Y580661D01*
X519908Y578869D01*
X521992D01*
G01X524050Y578161D02*
Y580661D01*
X523550Y580161D01*
G01Y578161D02*
X524550D01*
G01X526233Y578536D02*
X526483Y578328D01*
X526775Y578203D01*
X527150Y578161D01*
X527525Y578244D01*
X527817Y578411D01*
X528025Y578703D01*
X528067Y579036D01*
X527983Y579369D01*
X527775Y579578D01*
X527483Y579744D01*
X527192Y579786D01*
X526900Y579744D01*
X526525Y579578D01*
X526650Y580661D01*
X527775D01*
G01X515200Y581000D02*
Y585000D01*
X507800D01*
G01X570267Y608792D02*
X570017Y608917D01*
X569725Y609000D01*
X569392D01*
X569017Y608875D01*
X568725Y608667D01*
X568517Y608417D01*
X568350Y608000D01*
X568308Y607625D01*
X568392Y607250D01*
X568517Y607000D01*
X568767Y606750D01*
X569058Y606583D01*
X569350Y606500D01*
X569642D01*
X569933Y606583D01*
X570183Y606708D01*
X570392Y606875D01*
G01X571658Y608583D02*
X571908Y608833D01*
X572200Y608958D01*
X572533Y609000D01*
X572950Y608917D01*
X573242Y608708D01*
X573325Y608458D01*
X573283Y608208D01*
X573117Y608000D01*
X572283Y607583D01*
X571908Y607292D01*
X571658Y606875D01*
X571575Y606500D01*
X573325D01*
G01X574633Y607000D02*
X574883Y606708D01*
X575217Y606542D01*
X575592Y606500D01*
X575925Y606542D01*
X576258Y606750D01*
X576467Y607000D01*
X576508Y607250D01*
X576425Y607542D01*
X576133Y607750D01*
X575842Y607833D01*
X575467D01*
G01X575842D02*
X576092Y607958D01*
X576300Y608167D01*
X576383Y608417D01*
X576300Y608667D01*
X576092Y608875D01*
X575717Y609000D01*
X575342Y608958D01*
X574967Y608792D01*
G01X578650Y606500D02*
X578942Y606542D01*
X579275Y606667D01*
X579483Y606875D01*
X579567Y607167D01*
X579483Y607458D01*
X579233Y607708D01*
X578858Y607833D01*
X578442D01*
X578192Y607917D01*
X577983Y608125D01*
X577900Y608417D01*
X578025Y608708D01*
X578317Y608917D01*
X578650Y609000D01*
X578983Y608917D01*
X579275Y608708D01*
X579400Y608417D01*
X579317Y608125D01*
X579108Y607917D01*
X578858Y607833D01*
X578442D01*
X578067Y607708D01*
X577817Y607458D01*
X577733Y607167D01*
X577817Y606875D01*
X578025Y606667D01*
X578358Y606542D01*
X578650Y606500D01*
G01X505850Y616000D02*
Y613500D01*
G01X504892Y616000D02*
X506808D01*
G01X508117Y613500D02*
Y616000D01*
X509117D01*
X509450Y615875D01*
X509700Y615583D01*
X509783Y615250D01*
X509700Y614917D01*
X509492Y614667D01*
X509117Y614542D01*
X508117D01*
G01X511342Y613792D02*
X511633Y613583D01*
X511967Y613500D01*
X512300Y613583D01*
X512592Y613833D01*
X512800Y614208D01*
X512883Y614583D01*
Y615042D01*
X512800Y615417D01*
X512592Y615750D01*
X512342Y615917D01*
X512050Y616000D01*
X511717Y615917D01*
X511467Y615750D01*
X511300Y615500D01*
X511217Y615167D01*
X511300Y614875D01*
X511508Y614583D01*
X511758Y614417D01*
X512050Y614375D01*
X512383Y614458D01*
X512633Y614667D01*
X512883Y615042D01*
G01X514358Y614542D02*
X514650Y614833D01*
X514900Y615000D01*
X515233Y615083D01*
X515525Y615000D01*
X515733Y614833D01*
X515900Y614583D01*
X515942Y614292D01*
X515900Y614042D01*
X515733Y613792D01*
X515483Y613583D01*
X515192Y613500D01*
X514858Y613583D01*
X514567Y613833D01*
X514400Y614208D01*
X514358Y614625D01*
X514442Y615167D01*
X514567Y615458D01*
X514775Y615750D01*
X515067Y615958D01*
X515358Y616000D01*
X515650Y615917D01*
X515858Y615708D01*
G01X536400Y572500D02*
X536067Y572542D01*
X535775Y572708D01*
X535525Y572958D01*
X535358Y573250D01*
X535275Y573583D01*
Y573917D01*
X535358Y574250D01*
X535525Y574542D01*
X535775Y574792D01*
X536067Y574958D01*
X536400Y575000D01*
X536733Y574958D01*
X537025Y574792D01*
X537275Y574542D01*
X537442Y574250D01*
X537525Y573917D01*
Y573583D01*
X537442Y573250D01*
X537275Y572958D01*
X537025Y572708D01*
X536733Y572542D01*
X536400Y572500D01*
G01X536733Y573167D02*
X537233Y572500D01*
G01X539417D02*
X539500Y573042D01*
X539625Y573500D01*
X539792Y573917D01*
X540000Y574375D01*
X540333Y575000D01*
X538667D01*
G01X541808Y574583D02*
X542058Y574833D01*
X542350Y574958D01*
X542683Y575000D01*
X543100Y574917D01*
X543392Y574708D01*
X543475Y574458D01*
X543433Y574208D01*
X543267Y574000D01*
X542433Y573583D01*
X542058Y573292D01*
X541808Y572875D01*
X541725Y572500D01*
X543475D01*
G01X544800Y576000D02*
X546900Y574200D01*
X544800Y572000D01*
G01X507517Y598500D02*
Y601000D01*
X508558D01*
X508892Y600875D01*
X509100Y600708D01*
X509183Y600375D01*
X509100Y600042D01*
X508850Y599833D01*
X508558Y599708D01*
X507517D01*
G01X508558D02*
X509183Y598500D01*
G01X511950D02*
Y601000D01*
X510408Y599208D01*
X512492D01*
G01X514550Y598500D02*
Y601000D01*
X514050Y600500D01*
G01Y598500D02*
X515050D01*
G01X516942Y598792D02*
X517233Y598583D01*
X517567Y598500D01*
X517900Y598583D01*
X518192Y598833D01*
X518400Y599208D01*
X518483Y599583D01*
Y600042D01*
X518400Y600417D01*
X518192Y600750D01*
X517942Y600917D01*
X517650Y601000D01*
X517317Y600917D01*
X517067Y600750D01*
X516900Y600500D01*
X516817Y600167D01*
X516900Y599875D01*
X517108Y599583D01*
X517358Y599417D01*
X517650Y599375D01*
X517983Y599458D01*
X518233Y599667D01*
X518483Y600042D01*
G01X570267Y604453D02*
X570017Y604578D01*
X569725Y604661D01*
X569392D01*
X569017Y604536D01*
X568725Y604328D01*
X568517Y604078D01*
X568350Y603661D01*
X568308Y603286D01*
X568392Y602911D01*
X568517Y602661D01*
X568767Y602411D01*
X569058Y602244D01*
X569350Y602161D01*
X569642D01*
X569933Y602244D01*
X570183Y602369D01*
X570392Y602536D01*
G01X571658Y604244D02*
X571908Y604494D01*
X572200Y604619D01*
X572533Y604661D01*
X572950Y604578D01*
X573242Y604369D01*
X573325Y604119D01*
X573283Y603869D01*
X573117Y603661D01*
X572283Y603244D01*
X571908Y602953D01*
X571658Y602536D01*
X571575Y602161D01*
X573325D01*
G01X574633Y602661D02*
X574883Y602369D01*
X575217Y602203D01*
X575592Y602161D01*
X575925Y602203D01*
X576258Y602411D01*
X576467Y602661D01*
X576508Y602911D01*
X576425Y603203D01*
X576133Y603411D01*
X575842Y603494D01*
X575467D01*
G01X575842D02*
X576092Y603619D01*
X576300Y603828D01*
X576383Y604078D01*
X576300Y604328D01*
X576092Y604536D01*
X575717Y604661D01*
X575342Y604619D01*
X574967Y604453D01*
G01X577942Y602453D02*
X578233Y602244D01*
X578567Y602161D01*
X578900Y602244D01*
X579192Y602494D01*
X579400Y602869D01*
X579483Y603244D01*
Y603703D01*
X579400Y604078D01*
X579192Y604411D01*
X578942Y604578D01*
X578650Y604661D01*
X578317Y604578D01*
X578067Y604411D01*
X577900Y604161D01*
X577817Y603828D01*
X577900Y603536D01*
X578108Y603244D01*
X578358Y603078D01*
X578650Y603036D01*
X578983Y603119D01*
X579233Y603328D01*
X579483Y603703D01*
G01X567200Y582500D02*
X572700D01*
G01X567200Y574500D02*
Y582500D01*
G01X572700Y574500D02*
X567200D01*
G01X568517Y610500D02*
Y613000D01*
X569558D01*
X569892Y612875D01*
X570100Y612708D01*
X570183Y612375D01*
X570100Y612042D01*
X569850Y611833D01*
X569558Y611708D01*
X568517D01*
G01X569558D02*
X570183Y610500D01*
G01X572950D02*
Y613000D01*
X571408Y611208D01*
X573492D01*
G01X574633Y611000D02*
X574883Y610708D01*
X575217Y610542D01*
X575592Y610500D01*
X575925Y610542D01*
X576258Y610750D01*
X576467Y611000D01*
X576508Y611250D01*
X576425Y611542D01*
X576133Y611750D01*
X575842Y611833D01*
X575467D01*
G01X575842D02*
X576092Y611958D01*
X576300Y612167D01*
X576383Y612417D01*
X576300Y612667D01*
X576092Y612875D01*
X575717Y613000D01*
X575342Y612958D01*
X574967Y612792D01*
G01X577942Y610792D02*
X578233Y610583D01*
X578567Y610500D01*
X578900Y610583D01*
X579192Y610833D01*
X579400Y611208D01*
X579483Y611583D01*
Y612042D01*
X579400Y612417D01*
X579192Y612750D01*
X578942Y612917D01*
X578650Y613000D01*
X578317Y612917D01*
X578067Y612750D01*
X577900Y612500D01*
X577817Y612167D01*
X577900Y611875D01*
X578108Y611583D01*
X578358Y611417D01*
X578650Y611375D01*
X578983Y611458D01*
X579233Y611667D01*
X579483Y612042D01*
G01X562700Y589000D02*
Y597000D01*
X580300D01*
Y589000D01*
X562700D01*
G01X553767Y602292D02*
X553517Y602417D01*
X553225Y602500D01*
X552892D01*
X552517Y602375D01*
X552225Y602167D01*
X552017Y601917D01*
X551850Y601500D01*
X551808Y601125D01*
X551892Y600750D01*
X552017Y600500D01*
X552267Y600250D01*
X552558Y600083D01*
X552850Y600000D01*
X553142D01*
X553433Y600083D01*
X553683Y600208D01*
X553892Y600375D01*
G01X555158Y602083D02*
X555408Y602333D01*
X555700Y602458D01*
X556033Y602500D01*
X556450Y602417D01*
X556742Y602208D01*
X556825Y601958D01*
X556783Y601708D01*
X556617Y601500D01*
X555783Y601083D01*
X555408Y600792D01*
X555158Y600375D01*
X555075Y600000D01*
X556825D01*
G01X559550D02*
Y602500D01*
X558008Y600708D01*
X560092D01*
G01X562150Y600000D02*
Y602500D01*
X561650Y602000D01*
G01Y600000D02*
X562650D01*
G01X561017Y721500D02*
Y719000D01*
X562683D01*
G01X565783D02*
X564117D01*
Y721500D01*
X565783D01*
G01X565117Y720292D02*
X564117D01*
G01X567133Y719000D02*
Y721500D01*
X567967D01*
X568300Y721375D01*
X568550Y721208D01*
X568758Y720958D01*
X568925Y720667D01*
X568967Y720250D01*
X568925Y719833D01*
X568758Y719542D01*
X568550Y719292D01*
X568300Y719125D01*
X567967Y719000D01*
X567133D01*
G01X570233Y719375D02*
X570483Y719167D01*
X570775Y719042D01*
X571150Y719000D01*
X571525Y719083D01*
X571817Y719250D01*
X572025Y719542D01*
X572067Y719875D01*
X571983Y720208D01*
X571775Y720417D01*
X571483Y720583D01*
X571192Y720625D01*
X570900Y720583D01*
X570525Y720417D01*
X570650Y721500D01*
X571775D01*
G01X562529Y704636D02*
Y715836D01*
X571329D01*
Y704636D01*
X562529D01*
G01X564923Y835023D02*
Y837523D01*
X565964D01*
X566298Y837398D01*
X566506Y837231D01*
X566589Y836898D01*
X566506Y836565D01*
X566256Y836356D01*
X565964Y836231D01*
X564923D01*
G01X565964D02*
X566589Y835023D01*
G01X568064Y837106D02*
X568314Y837356D01*
X568606Y837481D01*
X568939Y837523D01*
X569356Y837440D01*
X569648Y837231D01*
X569731Y836981D01*
X569689Y836731D01*
X569523Y836523D01*
X568689Y836106D01*
X568314Y835815D01*
X568064Y835398D01*
X567981Y835023D01*
X569731D01*
G01X571956D02*
Y837523D01*
X571456Y837023D01*
G01Y835023D02*
X572456D01*
G01X574139Y835523D02*
X574389Y835231D01*
X574723Y835065D01*
X575098Y835023D01*
X575431Y835065D01*
X575764Y835273D01*
X575973Y835523D01*
X576014Y835773D01*
X575931Y836065D01*
X575639Y836273D01*
X575348Y836356D01*
X574973D01*
G01X575348D02*
X575598Y836481D01*
X575806Y836690D01*
X575889Y836940D01*
X575806Y837190D01*
X575598Y837398D01*
X575223Y837523D01*
X574848Y837481D01*
X574473Y837315D01*
G01X566000Y852217D02*
X563500D01*
Y853258D01*
X563625Y853592D01*
X563792Y853800D01*
X564125Y853883D01*
X564458Y853800D01*
X564667Y853550D01*
X564792Y853258D01*
Y852217D01*
G01Y853258D02*
X566000Y853883D01*
G01X563917Y855358D02*
X563667Y855608D01*
X563542Y855900D01*
X563500Y856233D01*
X563583Y856650D01*
X563792Y856942D01*
X564042Y857025D01*
X564292Y856983D01*
X564500Y856817D01*
X564917Y855983D01*
X565208Y855608D01*
X565625Y855358D01*
X566000Y855275D01*
Y857025D01*
G01X564958Y858458D02*
X564667Y858750D01*
X564500Y859000D01*
X564417Y859333D01*
X564500Y859625D01*
X564667Y859833D01*
X564917Y860000D01*
X565208Y860042D01*
X565458Y860000D01*
X565708Y859833D01*
X565917Y859583D01*
X566000Y859292D01*
X565917Y858958D01*
X565667Y858667D01*
X565292Y858500D01*
X564875Y858458D01*
X564333Y858542D01*
X564042Y858667D01*
X563750Y858875D01*
X563542Y859167D01*
X563500Y859458D01*
X563583Y859750D01*
X563792Y859958D01*
G01X566000Y862350D02*
X565958Y862642D01*
X565833Y862975D01*
X565625Y863183D01*
X565333Y863267D01*
X565042Y863183D01*
X564792Y862933D01*
X564667Y862558D01*
Y862142D01*
X564583Y861892D01*
X564375Y861683D01*
X564083Y861600D01*
X563792Y861725D01*
X563583Y862017D01*
X563500Y862350D01*
X563583Y862683D01*
X563792Y862975D01*
X564083Y863100D01*
X564375Y863017D01*
X564583Y862808D01*
X564667Y862558D01*
Y862142D01*
X564792Y861767D01*
X565042Y861517D01*
X565333Y861433D01*
X565625Y861517D01*
X565833Y861725D01*
X565958Y862058D01*
X566000Y862350D01*
G01X570000Y852217D02*
X567500D01*
Y853258D01*
X567625Y853592D01*
X567792Y853800D01*
X568125Y853883D01*
X568458Y853800D01*
X568667Y853550D01*
X568792Y853258D01*
Y852217D01*
G01Y853258D02*
X570000Y853883D01*
G01X567917Y855358D02*
X567667Y855608D01*
X567542Y855900D01*
X567500Y856233D01*
X567583Y856650D01*
X567792Y856942D01*
X568042Y857025D01*
X568292Y856983D01*
X568500Y856817D01*
X568917Y855983D01*
X569208Y855608D01*
X569625Y855358D01*
X570000Y855275D01*
Y857025D01*
G01X568958Y858458D02*
X568667Y858750D01*
X568500Y859000D01*
X568417Y859333D01*
X568500Y859625D01*
X568667Y859833D01*
X568917Y860000D01*
X569208Y860042D01*
X569458Y860000D01*
X569708Y859833D01*
X569917Y859583D01*
X570000Y859292D01*
X569917Y858958D01*
X569667Y858667D01*
X569292Y858500D01*
X568875Y858458D01*
X568333Y858542D01*
X568042Y858667D01*
X567750Y858875D01*
X567542Y859167D01*
X567500Y859458D01*
X567583Y859750D01*
X567792Y859958D01*
G01X569708Y861642D02*
X569917Y861933D01*
X570000Y862267D01*
X569917Y862600D01*
X569667Y862892D01*
X569292Y863100D01*
X568917Y863183D01*
X568458D01*
X568083Y863100D01*
X567750Y862892D01*
X567583Y862642D01*
X567500Y862350D01*
X567583Y862017D01*
X567750Y861767D01*
X568000Y861600D01*
X568333Y861517D01*
X568625Y861600D01*
X568917Y861808D01*
X569083Y862058D01*
X569125Y862350D01*
X569042Y862683D01*
X568833Y862933D01*
X568458Y863183D01*
G01X572256Y855923D02*
X571923Y855965D01*
X571631Y856131D01*
X571381Y856381D01*
X571214Y856673D01*
X571131Y857006D01*
Y857340D01*
X571214Y857673D01*
X571381Y857965D01*
X571631Y858215D01*
X571923Y858381D01*
X572256Y858423D01*
X572589Y858381D01*
X572881Y858215D01*
X573131Y857965D01*
X573298Y857673D01*
X573381Y857340D01*
Y857006D01*
X573298Y856673D01*
X573131Y856381D01*
X572881Y856131D01*
X572589Y855965D01*
X572256Y855923D01*
G01X572589Y856590D02*
X573089Y855923D01*
G01X574564Y858006D02*
X574814Y858256D01*
X575106Y858381D01*
X575439Y858423D01*
X575856Y858340D01*
X576148Y858131D01*
X576231Y857881D01*
X576189Y857631D01*
X576023Y857423D01*
X575189Y857006D01*
X574814Y856715D01*
X574564Y856298D01*
X574481Y855923D01*
X576231D01*
G01X578956D02*
Y858423D01*
X577414Y856631D01*
X579498D01*
G01X581473Y855923D02*
X581556Y856465D01*
X581681Y856923D01*
X581848Y857340D01*
X582056Y857798D01*
X582389Y858423D01*
X580723D01*
G01X571898Y839630D02*
X585898D01*
G01X571898Y852630D02*
Y839630D01*
G01X585898Y852630D02*
X571898D01*
G01X511763Y963184D02*
X511513Y963309D01*
X511221Y963392D01*
X510888D01*
X510513Y963267D01*
X510221Y963059D01*
X510013Y962809D01*
X509846Y962392D01*
X509804Y962017D01*
X509888Y961642D01*
X510013Y961392D01*
X510263Y961142D01*
X510554Y960975D01*
X510846Y960892D01*
X511138D01*
X511429Y960975D01*
X511679Y961100D01*
X511888Y961267D01*
G01X513154Y961934D02*
X513446Y962225D01*
X513696Y962392D01*
X514029Y962475D01*
X514321Y962392D01*
X514529Y962225D01*
X514696Y961975D01*
X514738Y961684D01*
X514696Y961434D01*
X514529Y961184D01*
X514279Y960975D01*
X513988Y960892D01*
X513654Y960975D01*
X513363Y961225D01*
X513196Y961600D01*
X513154Y962017D01*
X513238Y962559D01*
X513363Y962850D01*
X513571Y963142D01*
X513863Y963350D01*
X514154Y963392D01*
X514446Y963309D01*
X514654Y963100D01*
G01X517046Y960892D02*
X517338Y960934D01*
X517671Y961059D01*
X517879Y961267D01*
X517963Y961559D01*
X517879Y961850D01*
X517629Y962100D01*
X517254Y962225D01*
X516838D01*
X516588Y962309D01*
X516379Y962517D01*
X516296Y962809D01*
X516421Y963100D01*
X516713Y963309D01*
X517046Y963392D01*
X517379Y963309D01*
X517671Y963100D01*
X517796Y962809D01*
X517713Y962517D01*
X517504Y962309D01*
X517254Y962225D01*
X516838D01*
X516463Y962100D01*
X516213Y961850D01*
X516129Y961559D01*
X516213Y961267D01*
X516421Y961059D01*
X516754Y960934D01*
X517046Y960892D01*
G01X511817Y967292D02*
X511567Y967417D01*
X511275Y967500D01*
X510942D01*
X510567Y967375D01*
X510275Y967167D01*
X510067Y966917D01*
X509900Y966500D01*
X509858Y966125D01*
X509942Y965750D01*
X510067Y965500D01*
X510317Y965250D01*
X510608Y965083D01*
X510900Y965000D01*
X511192D01*
X511483Y965083D01*
X511733Y965208D01*
X511942Y965375D01*
G01X513208Y966042D02*
X513500Y966333D01*
X513750Y966500D01*
X514083Y966583D01*
X514375Y966500D01*
X514583Y966333D01*
X514750Y966083D01*
X514792Y965792D01*
X514750Y965542D01*
X514583Y965292D01*
X514333Y965083D01*
X514042Y965000D01*
X513708Y965083D01*
X513417Y965333D01*
X513250Y965708D01*
X513208Y966125D01*
X513292Y966667D01*
X513417Y966958D01*
X513625Y967250D01*
X513917Y967458D01*
X514208Y967500D01*
X514500Y967417D01*
X514708Y967208D01*
G01X517017Y965000D02*
X517100Y965542D01*
X517225Y966000D01*
X517392Y966417D01*
X517600Y966875D01*
X517933Y967500D01*
X516267D01*
G01X518817Y1032792D02*
X518567Y1032917D01*
X518275Y1033000D01*
X517942D01*
X517567Y1032875D01*
X517275Y1032667D01*
X517067Y1032417D01*
X516900Y1032000D01*
X516858Y1031625D01*
X516942Y1031250D01*
X517067Y1031000D01*
X517317Y1030750D01*
X517608Y1030583D01*
X517900Y1030500D01*
X518192D01*
X518483Y1030583D01*
X518733Y1030708D01*
X518942Y1030875D01*
G01X520917Y1030500D02*
X521000Y1031042D01*
X521125Y1031500D01*
X521292Y1031917D01*
X521500Y1032375D01*
X521833Y1033000D01*
X520167D01*
G01X523183Y1030875D02*
X523433Y1030667D01*
X523725Y1030542D01*
X524100Y1030500D01*
X524475Y1030583D01*
X524767Y1030750D01*
X524975Y1031042D01*
X525017Y1031375D01*
X524933Y1031708D01*
X524725Y1031917D01*
X524433Y1032083D01*
X524142Y1032125D01*
X523850Y1032083D01*
X523475Y1031917D01*
X523600Y1033000D01*
X524725D01*
G01X540817Y1007292D02*
X540567Y1007417D01*
X540275Y1007500D01*
X539942D01*
X539567Y1007375D01*
X539275Y1007167D01*
X539067Y1006917D01*
X538900Y1006500D01*
X538858Y1006125D01*
X538942Y1005750D01*
X539067Y1005500D01*
X539317Y1005250D01*
X539608Y1005083D01*
X539900Y1005000D01*
X540192D01*
X540483Y1005083D01*
X540733Y1005208D01*
X540942Y1005375D01*
G01X542292Y1005292D02*
X542583Y1005083D01*
X542917Y1005000D01*
X543250Y1005083D01*
X543542Y1005333D01*
X543750Y1005708D01*
X543833Y1006083D01*
Y1006542D01*
X543750Y1006917D01*
X543542Y1007250D01*
X543292Y1007417D01*
X543000Y1007500D01*
X542667Y1007417D01*
X542417Y1007250D01*
X542250Y1007000D01*
X542167Y1006667D01*
X542250Y1006375D01*
X542458Y1006083D01*
X542708Y1005917D01*
X543000Y1005875D01*
X543333Y1005958D01*
X543583Y1006167D01*
X543833Y1006542D01*
G01X546100Y1005000D02*
Y1007500D01*
X545600Y1007000D01*
G01Y1005000D02*
X546600D01*
G01X548817Y998292D02*
X548567Y998417D01*
X548275Y998500D01*
X547942D01*
X547567Y998375D01*
X547275Y998167D01*
X547067Y997917D01*
X546900Y997500D01*
X546858Y997125D01*
X546942Y996750D01*
X547067Y996500D01*
X547317Y996250D01*
X547608Y996083D01*
X547900Y996000D01*
X548192D01*
X548483Y996083D01*
X548733Y996208D01*
X548942Y996375D01*
G01X550292Y996292D02*
X550583Y996083D01*
X550917Y996000D01*
X551250Y996083D01*
X551542Y996333D01*
X551750Y996708D01*
X551833Y997083D01*
Y997542D01*
X551750Y997917D01*
X551542Y998250D01*
X551292Y998417D01*
X551000Y998500D01*
X550667Y998417D01*
X550417Y998250D01*
X550250Y998000D01*
X550167Y997667D01*
X550250Y997375D01*
X550458Y997083D01*
X550708Y996917D01*
X551000Y996875D01*
X551333Y996958D01*
X551583Y997167D01*
X551833Y997542D01*
G01X554100Y998500D02*
X553767Y998417D01*
X553517Y998208D01*
X553350Y997958D01*
X553225Y997625D01*
X553183Y997250D01*
X553225Y996875D01*
X553350Y996542D01*
X553517Y996292D01*
X553767Y996083D01*
X554100Y996000D01*
X554433Y996083D01*
X554683Y996292D01*
X554850Y996542D01*
X554975Y996875D01*
X555017Y997250D01*
X554975Y997625D01*
X554850Y997958D01*
X554683Y998208D01*
X554433Y998417D01*
X554100Y998500D01*
G01X517017Y1034500D02*
Y1037000D01*
X518058D01*
X518392Y1036875D01*
X518600Y1036708D01*
X518683Y1036375D01*
X518600Y1036042D01*
X518350Y1035833D01*
X518058Y1035708D01*
X517017D01*
G01X518058D02*
X518683Y1034500D01*
G01X520158Y1036583D02*
X520408Y1036833D01*
X520700Y1036958D01*
X521033Y1037000D01*
X521450Y1036917D01*
X521742Y1036708D01*
X521825Y1036458D01*
X521783Y1036208D01*
X521617Y1036000D01*
X520783Y1035583D01*
X520408Y1035292D01*
X520158Y1034875D01*
X520075Y1034500D01*
X521825D01*
G01X524050Y1037000D02*
X523717Y1036917D01*
X523467Y1036708D01*
X523300Y1036458D01*
X523175Y1036125D01*
X523133Y1035750D01*
X523175Y1035375D01*
X523300Y1035042D01*
X523467Y1034792D01*
X523717Y1034583D01*
X524050Y1034500D01*
X524383Y1034583D01*
X524633Y1034792D01*
X524800Y1035042D01*
X524925Y1035375D01*
X524967Y1035750D01*
X524925Y1036125D01*
X524800Y1036458D01*
X524633Y1036708D01*
X524383Y1036917D01*
X524050Y1037000D01*
G01X527067Y1034500D02*
X527150Y1035042D01*
X527275Y1035500D01*
X527442Y1035917D01*
X527650Y1036375D01*
X527983Y1037000D01*
X526317D01*
G01X515200Y1034000D02*
Y1038000D01*
X507800D01*
G01X548517Y962000D02*
Y964500D01*
X549558D01*
X549892Y964375D01*
X550100Y964208D01*
X550183Y963875D01*
X550100Y963542D01*
X549850Y963333D01*
X549558Y963208D01*
X548517D01*
G01X549558D02*
X550183Y962000D01*
G01X551658Y964083D02*
X551908Y964333D01*
X552200Y964458D01*
X552533Y964500D01*
X552950Y964417D01*
X553242Y964208D01*
X553325Y963958D01*
X553283Y963708D01*
X553117Y963500D01*
X552283Y963083D01*
X551908Y962792D01*
X551658Y962375D01*
X551575Y962000D01*
X553325D01*
G01X554633Y962500D02*
X554883Y962208D01*
X555217Y962042D01*
X555592Y962000D01*
X555925Y962042D01*
X556258Y962250D01*
X556467Y962500D01*
X556508Y962750D01*
X556425Y963042D01*
X556133Y963250D01*
X555842Y963333D01*
X555467D01*
G01X555842D02*
X556092Y963458D01*
X556300Y963667D01*
X556383Y963917D01*
X556300Y964167D01*
X556092Y964375D01*
X555717Y964500D01*
X555342Y964458D01*
X554967Y964292D01*
G01X557858Y964083D02*
X558108Y964333D01*
X558400Y964458D01*
X558733Y964500D01*
X559150Y964417D01*
X559442Y964208D01*
X559525Y963958D01*
X559483Y963708D01*
X559317Y963500D01*
X558483Y963083D01*
X558108Y962792D01*
X557858Y962375D01*
X557775Y962000D01*
X559525D01*
G01X551800Y973000D02*
Y969000D01*
X559200D01*
G01X539017Y1000661D02*
Y1003161D01*
X540058D01*
X540392Y1003036D01*
X540600Y1002869D01*
X540683Y1002536D01*
X540600Y1002203D01*
X540350Y1001994D01*
X540058Y1001869D01*
X539017D01*
G01X540058D02*
X540683Y1000661D01*
G01X542158Y1002744D02*
X542408Y1002994D01*
X542700Y1003119D01*
X543033Y1003161D01*
X543450Y1003078D01*
X543742Y1002869D01*
X543825Y1002619D01*
X543783Y1002369D01*
X543617Y1002161D01*
X542783Y1001744D01*
X542408Y1001453D01*
X542158Y1001036D01*
X542075Y1000661D01*
X543825D01*
G01X545133Y1001161D02*
X545383Y1000869D01*
X545717Y1000703D01*
X546092Y1000661D01*
X546425Y1000703D01*
X546758Y1000911D01*
X546967Y1001161D01*
X547008Y1001411D01*
X546925Y1001703D01*
X546633Y1001911D01*
X546342Y1001994D01*
X545967D01*
G01X546342D02*
X546592Y1002119D01*
X546800Y1002328D01*
X546883Y1002578D01*
X546800Y1002828D01*
X546592Y1003036D01*
X546217Y1003161D01*
X545842Y1003119D01*
X545467Y1002953D01*
G01X548233Y1001161D02*
X548483Y1000869D01*
X548817Y1000703D01*
X549192Y1000661D01*
X549525Y1000703D01*
X549858Y1000911D01*
X550067Y1001161D01*
X550108Y1001411D01*
X550025Y1001703D01*
X549733Y1001911D01*
X549442Y1001994D01*
X549067D01*
G01X549442D02*
X549692Y1002119D01*
X549900Y1002328D01*
X549983Y1002578D01*
X549900Y1002828D01*
X549692Y1003036D01*
X549317Y1003161D01*
X548942Y1003119D01*
X548567Y1002953D01*
G01X559200Y1000000D02*
Y1004000D01*
X551800D01*
G01X549000Y974517D02*
X546500D01*
Y975558D01*
X546625Y975892D01*
X546792Y976100D01*
X547125Y976183D01*
X547458Y976100D01*
X547667Y975850D01*
X547792Y975558D01*
Y974517D01*
G01Y975558D02*
X549000Y976183D01*
G01X546917Y977658D02*
X546667Y977908D01*
X546542Y978200D01*
X546500Y978533D01*
X546583Y978950D01*
X546792Y979242D01*
X547042Y979325D01*
X547292Y979283D01*
X547500Y979117D01*
X547917Y978283D01*
X548208Y977908D01*
X548625Y977658D01*
X549000Y977575D01*
Y979325D01*
G01X548500Y980633D02*
X548792Y980883D01*
X548958Y981217D01*
X549000Y981592D01*
X548958Y981925D01*
X548750Y982258D01*
X548500Y982467D01*
X548250Y982508D01*
X547958Y982425D01*
X547750Y982133D01*
X547667Y981842D01*
Y981467D01*
G01Y981842D02*
X547542Y982092D01*
X547333Y982300D01*
X547083Y982383D01*
X546833Y982300D01*
X546625Y982092D01*
X546500Y981717D01*
X546542Y981342D01*
X546708Y980967D01*
G01X549000Y985150D02*
X546500D01*
X548292Y983608D01*
Y985692D01*
G01X555000Y973300D02*
X559000D01*
Y980700D01*
G01X571000Y954017D02*
X568500D01*
Y955058D01*
X568625Y955392D01*
X568792Y955600D01*
X569125Y955683D01*
X569458Y955600D01*
X569667Y955350D01*
X569792Y955058D01*
Y954017D01*
G01Y955058D02*
X571000Y955683D01*
G01X568917Y957158D02*
X568667Y957408D01*
X568542Y957700D01*
X568500Y958033D01*
X568583Y958450D01*
X568792Y958742D01*
X569042Y958825D01*
X569292Y958783D01*
X569500Y958617D01*
X569917Y957783D01*
X570208Y957408D01*
X570625Y957158D01*
X571000Y957075D01*
Y958825D01*
G01X570500Y960133D02*
X570792Y960383D01*
X570958Y960717D01*
X571000Y961092D01*
X570958Y961425D01*
X570750Y961758D01*
X570500Y961967D01*
X570250Y962008D01*
X569958Y961925D01*
X569750Y961633D01*
X569667Y961342D01*
Y960967D01*
G01Y961342D02*
X569542Y961592D01*
X569333Y961800D01*
X569083Y961883D01*
X568833Y961800D01*
X568625Y961592D01*
X568500Y961217D01*
X568542Y960842D01*
X568708Y960467D01*
G01X570625Y963233D02*
X570833Y963483D01*
X570958Y963775D01*
X571000Y964150D01*
X570917Y964525D01*
X570750Y964817D01*
X570458Y965025D01*
X570125Y965067D01*
X569792Y964983D01*
X569583Y964775D01*
X569417Y964483D01*
X569375Y964192D01*
X569417Y963900D01*
X569583Y963525D01*
X568500Y963650D01*
Y964775D01*
G01X571500Y974700D02*
X567500D01*
Y967300D01*
G01X547017Y992161D02*
Y994661D01*
X548058D01*
X548392Y994536D01*
X548600Y994369D01*
X548683Y994036D01*
X548600Y993703D01*
X548350Y993494D01*
X548058Y993369D01*
X547017D01*
G01X548058D02*
X548683Y992161D01*
G01X550158Y994244D02*
X550408Y994494D01*
X550700Y994619D01*
X551033Y994661D01*
X551450Y994578D01*
X551742Y994369D01*
X551825Y994119D01*
X551783Y993869D01*
X551617Y993661D01*
X550783Y993244D01*
X550408Y992953D01*
X550158Y992536D01*
X550075Y992161D01*
X551825D01*
G01X553258Y994244D02*
X553508Y994494D01*
X553800Y994619D01*
X554133Y994661D01*
X554550Y994578D01*
X554842Y994369D01*
X554925Y994119D01*
X554883Y993869D01*
X554717Y993661D01*
X553883Y993244D01*
X553508Y992953D01*
X553258Y992536D01*
X553175Y992161D01*
X554925D01*
G01X557067D02*
X557150Y992703D01*
X557275Y993161D01*
X557442Y993578D01*
X557650Y994036D01*
X557983Y994661D01*
X556317D01*
G01X559300Y998500D02*
Y994500D01*
X566700D01*
G01X576400Y1024000D02*
X576067Y1024042D01*
X575775Y1024208D01*
X575525Y1024458D01*
X575358Y1024750D01*
X575275Y1025083D01*
Y1025417D01*
X575358Y1025750D01*
X575525Y1026042D01*
X575775Y1026292D01*
X576067Y1026458D01*
X576400Y1026500D01*
X576733Y1026458D01*
X577025Y1026292D01*
X577275Y1026042D01*
X577442Y1025750D01*
X577525Y1025417D01*
Y1025083D01*
X577442Y1024750D01*
X577275Y1024458D01*
X577025Y1024208D01*
X576733Y1024042D01*
X576400Y1024000D01*
G01X576733Y1024667D02*
X577233Y1024000D01*
G01X579500D02*
Y1026500D01*
X579000Y1026000D01*
G01Y1024000D02*
X580000D01*
G01X583100D02*
Y1026500D01*
X581558Y1024708D01*
X583642D01*
G01X589300Y1014600D02*
X570100D01*
Y1003400D01*
X589300D01*
Y1014600D01*
X588900D01*
G01X535900Y1025000D02*
X535567Y1025042D01*
X535275Y1025208D01*
X535025Y1025458D01*
X534858Y1025750D01*
X534775Y1026083D01*
Y1026417D01*
X534858Y1026750D01*
X535025Y1027042D01*
X535275Y1027292D01*
X535567Y1027458D01*
X535900Y1027500D01*
X536233Y1027458D01*
X536525Y1027292D01*
X536775Y1027042D01*
X536942Y1026750D01*
X537025Y1026417D01*
Y1026083D01*
X536942Y1025750D01*
X536775Y1025458D01*
X536525Y1025208D01*
X536233Y1025042D01*
X535900Y1025000D01*
G01X536233Y1025667D02*
X536733Y1025000D01*
G01X539000D02*
Y1027500D01*
X538500Y1027000D01*
G01Y1025000D02*
X539500D01*
G01X541308Y1026042D02*
X541600Y1026333D01*
X541850Y1026500D01*
X542183Y1026583D01*
X542475Y1026500D01*
X542683Y1026333D01*
X542850Y1026083D01*
X542892Y1025792D01*
X542850Y1025542D01*
X542683Y1025292D01*
X542433Y1025083D01*
X542142Y1025000D01*
X541808Y1025083D01*
X541517Y1025333D01*
X541350Y1025708D01*
X541308Y1026125D01*
X541392Y1026667D01*
X541517Y1026958D01*
X541725Y1027250D01*
X542017Y1027458D01*
X542308Y1027500D01*
X542600Y1027417D01*
X542808Y1027208D01*
G01X544800Y1029000D02*
X546900Y1027200D01*
X544800Y1025000D01*
G01X544700Y1021400D02*
X563900D01*
Y1032600D01*
X544700D01*
Y1021400D01*
X545100D01*
G01X567200Y1035500D02*
X572700D01*
G01X567200Y1027500D02*
Y1035500D01*
G01X572700Y1027500D02*
X567200D01*
G01X565000Y959533D02*
X562500D01*
Y960367D01*
X562625Y960700D01*
X562792Y960950D01*
X563042Y961158D01*
X563333Y961325D01*
X563750Y961367D01*
X564167Y961325D01*
X564458Y961158D01*
X564708Y960950D01*
X564875Y960700D01*
X565000Y960367D01*
Y959533D01*
G01Y964050D02*
X562500D01*
X564292Y962508D01*
Y964592D01*
G01X567000Y983500D02*
Y967400D01*
G01X560000Y983500D02*
X567000D01*
G01X560000Y967400D02*
Y983500D01*
G01X567000Y967400D02*
X560000D01*
G01X571000Y982400D02*
X570958Y982067D01*
X570792Y981775D01*
X570542Y981525D01*
X570250Y981358D01*
X569917Y981275D01*
X569583D01*
X569250Y981358D01*
X568958Y981525D01*
X568708Y981775D01*
X568542Y982067D01*
X568500Y982400D01*
X568542Y982733D01*
X568708Y983025D01*
X568958Y983275D01*
X569250Y983442D01*
X569583Y983525D01*
X569917D01*
X570250Y983442D01*
X570542Y983275D01*
X570792Y983025D01*
X570958Y982733D01*
X571000Y982400D01*
G01X570333Y982733D02*
X571000Y983233D01*
G01Y985500D02*
X568500D01*
X569000Y985000D01*
G01X571000D02*
Y986000D01*
G01X570625Y987683D02*
X570833Y987933D01*
X570958Y988225D01*
X571000Y988600D01*
X570917Y988975D01*
X570750Y989267D01*
X570458Y989475D01*
X570125Y989517D01*
X569792Y989433D01*
X569583Y989225D01*
X569417Y988933D01*
X569375Y988642D01*
X569417Y988350D01*
X569583Y987975D01*
X568500Y988100D01*
Y989225D01*
G01X583200Y989200D02*
X571800D01*
G01Y975800D02*
X583200D01*
G01X571800Y989200D02*
Y975800D01*
G01X562700Y1042000D02*
Y1050000D01*
X580300D01*
Y1042000D01*
X562700D01*
G01X571317Y1058792D02*
X571067Y1058917D01*
X570775Y1059000D01*
X570442D01*
X570067Y1058875D01*
X569775Y1058667D01*
X569567Y1058417D01*
X569400Y1058000D01*
X569358Y1057625D01*
X569442Y1057250D01*
X569567Y1057000D01*
X569817Y1056750D01*
X570108Y1056583D01*
X570400Y1056500D01*
X570692D01*
X570983Y1056583D01*
X571233Y1056708D01*
X571442Y1056875D01*
G01X573500Y1056500D02*
X573792Y1056542D01*
X574125Y1056667D01*
X574333Y1056875D01*
X574417Y1057167D01*
X574333Y1057458D01*
X574083Y1057708D01*
X573708Y1057833D01*
X573292D01*
X573042Y1057917D01*
X572833Y1058125D01*
X572750Y1058417D01*
X572875Y1058708D01*
X573167Y1058917D01*
X573500Y1059000D01*
X573833Y1058917D01*
X574125Y1058708D01*
X574250Y1058417D01*
X574167Y1058125D01*
X573958Y1057917D01*
X573708Y1057833D01*
X573292D01*
X572917Y1057708D01*
X572667Y1057458D01*
X572583Y1057167D01*
X572667Y1056875D01*
X572875Y1056667D01*
X573208Y1056542D01*
X573500Y1056500D01*
G01X575808Y1058583D02*
X576058Y1058833D01*
X576350Y1058958D01*
X576683Y1059000D01*
X577100Y1058917D01*
X577392Y1058708D01*
X577475Y1058458D01*
X577433Y1058208D01*
X577267Y1058000D01*
X576433Y1057583D01*
X576058Y1057292D01*
X575808Y1056875D01*
X575725Y1056500D01*
X577475D01*
G01X505850Y1069000D02*
Y1066500D01*
G01X504892Y1069000D02*
X506808D01*
G01X508117Y1066500D02*
Y1069000D01*
X509117D01*
X509450Y1068875D01*
X509700Y1068583D01*
X509783Y1068250D01*
X509700Y1067917D01*
X509492Y1067667D01*
X509117Y1067542D01*
X508117D01*
G01X511133Y1067000D02*
X511383Y1066708D01*
X511717Y1066542D01*
X512092Y1066500D01*
X512425Y1066542D01*
X512758Y1066750D01*
X512967Y1067000D01*
X513008Y1067250D01*
X512925Y1067542D01*
X512633Y1067750D01*
X512342Y1067833D01*
X511967D01*
G01X512342D02*
X512592Y1067958D01*
X512800Y1068167D01*
X512883Y1068417D01*
X512800Y1068667D01*
X512592Y1068875D01*
X512217Y1069000D01*
X511842Y1068958D01*
X511467Y1068792D01*
G01X514358Y1067542D02*
X514650Y1067833D01*
X514900Y1068000D01*
X515233Y1068083D01*
X515525Y1068000D01*
X515733Y1067833D01*
X515900Y1067583D01*
X515942Y1067292D01*
X515900Y1067042D01*
X515733Y1066792D01*
X515483Y1066583D01*
X515192Y1066500D01*
X514858Y1066583D01*
X514567Y1066833D01*
X514400Y1067208D01*
X514358Y1067625D01*
X514442Y1068167D01*
X514567Y1068458D01*
X514775Y1068750D01*
X515067Y1068958D01*
X515358Y1069000D01*
X515650Y1068917D01*
X515858Y1068708D01*
G01X507517Y1052000D02*
Y1054500D01*
X508558D01*
X508892Y1054375D01*
X509100Y1054208D01*
X509183Y1053875D01*
X509100Y1053542D01*
X508850Y1053333D01*
X508558Y1053208D01*
X507517D01*
G01X508558D02*
X509183Y1052000D01*
G01X510658Y1054083D02*
X510908Y1054333D01*
X511200Y1054458D01*
X511533Y1054500D01*
X511950Y1054417D01*
X512242Y1054208D01*
X512325Y1053958D01*
X512283Y1053708D01*
X512117Y1053500D01*
X511283Y1053083D01*
X510908Y1052792D01*
X510658Y1052375D01*
X510575Y1052000D01*
X512325D01*
G01X514550Y1054500D02*
X514217Y1054417D01*
X513967Y1054208D01*
X513800Y1053958D01*
X513675Y1053625D01*
X513633Y1053250D01*
X513675Y1052875D01*
X513800Y1052542D01*
X513967Y1052292D01*
X514217Y1052083D01*
X514550Y1052000D01*
X514883Y1052083D01*
X515133Y1052292D01*
X515300Y1052542D01*
X515425Y1052875D01*
X515467Y1053250D01*
X515425Y1053625D01*
X515300Y1053958D01*
X515133Y1054208D01*
X514883Y1054417D01*
X514550Y1054500D01*
G01X516942Y1052292D02*
X517233Y1052083D01*
X517567Y1052000D01*
X517900Y1052083D01*
X518192Y1052333D01*
X518400Y1052708D01*
X518483Y1053083D01*
Y1053542D01*
X518400Y1053917D01*
X518192Y1054250D01*
X517942Y1054417D01*
X517650Y1054500D01*
X517317Y1054417D01*
X517067Y1054250D01*
X516900Y1054000D01*
X516817Y1053667D01*
X516900Y1053375D01*
X517108Y1053083D01*
X517358Y1052917D01*
X517650Y1052875D01*
X517983Y1052958D01*
X518233Y1053167D01*
X518483Y1053542D01*
G01X571317Y1054453D02*
X571067Y1054578D01*
X570775Y1054661D01*
X570442D01*
X570067Y1054536D01*
X569775Y1054328D01*
X569567Y1054078D01*
X569400Y1053661D01*
X569358Y1053286D01*
X569442Y1052911D01*
X569567Y1052661D01*
X569817Y1052411D01*
X570108Y1052244D01*
X570400Y1052161D01*
X570692D01*
X570983Y1052244D01*
X571233Y1052369D01*
X571442Y1052536D01*
G01X573500Y1052161D02*
X573792Y1052203D01*
X574125Y1052328D01*
X574333Y1052536D01*
X574417Y1052828D01*
X574333Y1053119D01*
X574083Y1053369D01*
X573708Y1053494D01*
X573292D01*
X573042Y1053578D01*
X572833Y1053786D01*
X572750Y1054078D01*
X572875Y1054369D01*
X573167Y1054578D01*
X573500Y1054661D01*
X573833Y1054578D01*
X574125Y1054369D01*
X574250Y1054078D01*
X574167Y1053786D01*
X573958Y1053578D01*
X573708Y1053494D01*
X573292D01*
X572917Y1053369D01*
X572667Y1053119D01*
X572583Y1052828D01*
X572667Y1052536D01*
X572875Y1052328D01*
X573208Y1052203D01*
X573500Y1052161D01*
G01X575683Y1052661D02*
X575933Y1052369D01*
X576267Y1052203D01*
X576642Y1052161D01*
X576975Y1052203D01*
X577308Y1052411D01*
X577517Y1052661D01*
X577558Y1052911D01*
X577475Y1053203D01*
X577183Y1053411D01*
X576892Y1053494D01*
X576517D01*
G01X576892D02*
X577142Y1053619D01*
X577350Y1053828D01*
X577433Y1054078D01*
X577350Y1054328D01*
X577142Y1054536D01*
X576767Y1054661D01*
X576392Y1054619D01*
X576017Y1054453D01*
G01X569517Y1061000D02*
Y1063500D01*
X570558D01*
X570892Y1063375D01*
X571100Y1063208D01*
X571183Y1062875D01*
X571100Y1062542D01*
X570850Y1062333D01*
X570558Y1062208D01*
X569517D01*
G01X570558D02*
X571183Y1061000D01*
G01X572658Y1063083D02*
X572908Y1063333D01*
X573200Y1063458D01*
X573533Y1063500D01*
X573950Y1063417D01*
X574242Y1063208D01*
X574325Y1062958D01*
X574283Y1062708D01*
X574117Y1062500D01*
X573283Y1062083D01*
X572908Y1061792D01*
X572658Y1061375D01*
X572575Y1061000D01*
X574325D01*
G01X575758Y1063083D02*
X576008Y1063333D01*
X576300Y1063458D01*
X576633Y1063500D01*
X577050Y1063417D01*
X577342Y1063208D01*
X577425Y1062958D01*
X577383Y1062708D01*
X577217Y1062500D01*
X576383Y1062083D01*
X576008Y1061792D01*
X575758Y1061375D01*
X575675Y1061000D01*
X577425D01*
G01X580150D02*
Y1063500D01*
X578608Y1061708D01*
X580692D01*
G01X553317Y1053292D02*
X553067Y1053417D01*
X552775Y1053500D01*
X552442D01*
X552067Y1053375D01*
X551775Y1053167D01*
X551567Y1052917D01*
X551400Y1052500D01*
X551358Y1052125D01*
X551442Y1051750D01*
X551567Y1051500D01*
X551817Y1051250D01*
X552108Y1051083D01*
X552400Y1051000D01*
X552692D01*
X552983Y1051083D01*
X553233Y1051208D01*
X553442Y1051375D01*
G01X555500Y1051000D02*
X555792Y1051042D01*
X556125Y1051167D01*
X556333Y1051375D01*
X556417Y1051667D01*
X556333Y1051958D01*
X556083Y1052208D01*
X555708Y1052333D01*
X555292D01*
X555042Y1052417D01*
X554833Y1052625D01*
X554750Y1052917D01*
X554875Y1053208D01*
X555167Y1053417D01*
X555500Y1053500D01*
X555833Y1053417D01*
X556125Y1053208D01*
X556250Y1052917D01*
X556167Y1052625D01*
X555958Y1052417D01*
X555708Y1052333D01*
X555292D01*
X554917Y1052208D01*
X554667Y1051958D01*
X554583Y1051667D01*
X554667Y1051375D01*
X554875Y1051167D01*
X555208Y1051042D01*
X555500Y1051000D01*
G01X557808Y1052042D02*
X558100Y1052333D01*
X558350Y1052500D01*
X558683Y1052583D01*
X558975Y1052500D01*
X559183Y1052333D01*
X559350Y1052083D01*
X559392Y1051792D01*
X559350Y1051542D01*
X559183Y1051292D01*
X558933Y1051083D01*
X558642Y1051000D01*
X558308Y1051083D01*
X558017Y1051333D01*
X557850Y1051708D01*
X557808Y1052125D01*
X557892Y1052667D01*
X558017Y1052958D01*
X558225Y1053250D01*
X558517Y1053458D01*
X558808Y1053500D01*
X559100Y1053417D01*
X559308Y1053208D01*
G01X526417Y1407837D02*
X526292Y1407587D01*
X526209Y1407295D01*
Y1406962D01*
X526334Y1406587D01*
X526542Y1406295D01*
X526792Y1406087D01*
X527209Y1405920D01*
X527584Y1405878D01*
X527959Y1405962D01*
X528209Y1406087D01*
X528459Y1406337D01*
X528626Y1406628D01*
X528709Y1406920D01*
Y1407212D01*
X528626Y1407503D01*
X528501Y1407753D01*
X528334Y1407962D01*
G01Y1409103D02*
X528542Y1409353D01*
X528667Y1409645D01*
X528709Y1410020D01*
X528626Y1410395D01*
X528459Y1410687D01*
X528167Y1410895D01*
X527834Y1410937D01*
X527501Y1410853D01*
X527292Y1410645D01*
X527126Y1410353D01*
X527084Y1410062D01*
X527126Y1409770D01*
X527292Y1409395D01*
X526209Y1409520D01*
Y1410645D01*
G01X526626Y1412328D02*
X526376Y1412578D01*
X526251Y1412870D01*
X526209Y1413203D01*
X526292Y1413620D01*
X526501Y1413912D01*
X526751Y1413995D01*
X527001Y1413953D01*
X527209Y1413787D01*
X527626Y1412953D01*
X527917Y1412578D01*
X528334Y1412328D01*
X528709Y1412245D01*
Y1413995D01*
G01X527667Y1415428D02*
X527376Y1415720D01*
X527209Y1415970D01*
X527126Y1416303D01*
X527209Y1416595D01*
X527376Y1416803D01*
X527626Y1416970D01*
X527917Y1417012D01*
X528167Y1416970D01*
X528417Y1416803D01*
X528626Y1416553D01*
X528709Y1416262D01*
X528626Y1415928D01*
X528376Y1415637D01*
X528001Y1415470D01*
X527584Y1415428D01*
X527042Y1415512D01*
X526751Y1415637D01*
X526459Y1415845D01*
X526251Y1416137D01*
X526209Y1416428D01*
X526292Y1416720D01*
X526501Y1416928D01*
G01X530417Y1407837D02*
X530292Y1407587D01*
X530209Y1407295D01*
Y1406962D01*
X530334Y1406587D01*
X530542Y1406295D01*
X530792Y1406087D01*
X531209Y1405920D01*
X531584Y1405878D01*
X531959Y1405962D01*
X532209Y1406087D01*
X532459Y1406337D01*
X532626Y1406628D01*
X532709Y1406920D01*
Y1407212D01*
X532626Y1407503D01*
X532501Y1407753D01*
X532334Y1407962D01*
G01Y1409103D02*
X532542Y1409353D01*
X532667Y1409645D01*
X532709Y1410020D01*
X532626Y1410395D01*
X532459Y1410687D01*
X532167Y1410895D01*
X531834Y1410937D01*
X531501Y1410853D01*
X531292Y1410645D01*
X531126Y1410353D01*
X531084Y1410062D01*
X531126Y1409770D01*
X531292Y1409395D01*
X530209Y1409520D01*
Y1410645D01*
G01X530626Y1412328D02*
X530376Y1412578D01*
X530251Y1412870D01*
X530209Y1413203D01*
X530292Y1413620D01*
X530501Y1413912D01*
X530751Y1413995D01*
X531001Y1413953D01*
X531209Y1413787D01*
X531626Y1412953D01*
X531917Y1412578D01*
X532334Y1412328D01*
X532709Y1412245D01*
Y1413995D01*
G01Y1416137D02*
X532167Y1416220D01*
X531709Y1416345D01*
X531292Y1416512D01*
X530834Y1416720D01*
X530209Y1417053D01*
Y1415387D01*
G01X498528Y1423244D02*
X498486Y1422911D01*
X498320Y1422619D01*
X498070Y1422369D01*
X497778Y1422202D01*
X497445Y1422119D01*
X497111D01*
X496778Y1422202D01*
X496486Y1422369D01*
X496236Y1422619D01*
X496070Y1422911D01*
X496028Y1423244D01*
X496070Y1423577D01*
X496236Y1423869D01*
X496486Y1424119D01*
X496778Y1424286D01*
X497111Y1424369D01*
X497445D01*
X497778Y1424286D01*
X498070Y1424119D01*
X498320Y1423869D01*
X498486Y1423577D01*
X498528Y1423244D01*
G01X497861Y1423577D02*
X498528Y1424077D01*
G01Y1426344D02*
X496028D01*
X496528Y1425844D01*
G01X498528D02*
Y1426844D01*
G01X496445Y1428652D02*
X496195Y1428902D01*
X496070Y1429194D01*
X496028Y1429527D01*
X496111Y1429944D01*
X496320Y1430236D01*
X496570Y1430319D01*
X496820Y1430277D01*
X497028Y1430111D01*
X497445Y1429277D01*
X497736Y1428902D01*
X498153Y1428652D01*
X498528Y1428569D01*
Y1430319D01*
G01Y1432544D02*
X498486Y1432836D01*
X498361Y1433169D01*
X498153Y1433377D01*
X497861Y1433461D01*
X497570Y1433377D01*
X497320Y1433127D01*
X497195Y1432752D01*
Y1432336D01*
X497111Y1432086D01*
X496903Y1431877D01*
X496611Y1431794D01*
X496320Y1431919D01*
X496111Y1432211D01*
X496028Y1432544D01*
X496111Y1432877D01*
X496320Y1433169D01*
X496611Y1433294D01*
X496903Y1433211D01*
X497111Y1433002D01*
X497195Y1432752D01*
Y1432336D01*
X497320Y1431961D01*
X497570Y1431711D01*
X497861Y1431627D01*
X498153Y1431711D01*
X498361Y1431919D01*
X498486Y1432252D01*
X498528Y1432544D01*
G01X521235Y1426131D02*
X519135Y1427931D01*
X521235Y1430131D01*
G01X521335Y1433731D02*
X502135D01*
Y1422531D01*
X521335D01*
Y1433731D01*
X520935D01*
G01X534417Y1407337D02*
X534292Y1407087D01*
X534209Y1406795D01*
Y1406462D01*
X534334Y1406087D01*
X534542Y1405795D01*
X534792Y1405587D01*
X535209Y1405420D01*
X535584Y1405378D01*
X535959Y1405462D01*
X536209Y1405587D01*
X536459Y1405837D01*
X536626Y1406128D01*
X536709Y1406420D01*
Y1406712D01*
X536626Y1407003D01*
X536501Y1407253D01*
X536334Y1407462D01*
G01Y1408603D02*
X536542Y1408853D01*
X536667Y1409145D01*
X536709Y1409520D01*
X536626Y1409895D01*
X536459Y1410187D01*
X536167Y1410395D01*
X535834Y1410437D01*
X535501Y1410353D01*
X535292Y1410145D01*
X535126Y1409853D01*
X535084Y1409562D01*
X535126Y1409270D01*
X535292Y1408895D01*
X534209Y1409020D01*
Y1410145D01*
G01X534626Y1411828D02*
X534376Y1412078D01*
X534251Y1412370D01*
X534209Y1412703D01*
X534292Y1413120D01*
X534501Y1413412D01*
X534751Y1413495D01*
X535001Y1413453D01*
X535209Y1413287D01*
X535626Y1412453D01*
X535917Y1412078D01*
X536334Y1411828D01*
X536709Y1411745D01*
Y1413495D01*
G01X536334Y1414803D02*
X536542Y1415053D01*
X536667Y1415345D01*
X536709Y1415720D01*
X536626Y1416095D01*
X536459Y1416387D01*
X536167Y1416595D01*
X535834Y1416637D01*
X535501Y1416553D01*
X535292Y1416345D01*
X535126Y1416053D01*
X535084Y1415762D01*
X535126Y1415470D01*
X535292Y1415095D01*
X534209Y1415220D01*
Y1416345D01*
G01X531034Y1425329D02*
Y1419129D01*
X543434D01*
Y1425329D01*
G01X523526Y1500858D02*
X521026D01*
Y1502442D01*
G01X522234Y1501858D02*
Y1500858D01*
G01X523526Y1503708D02*
X521026Y1504750D01*
X523526Y1505792D01*
G01X522651Y1505417D02*
Y1504083D01*
G01X523526Y1506892D02*
X521026D01*
X523526Y1508808D01*
X521026D01*
G01X521443Y1510158D02*
X521193Y1510408D01*
X521068Y1510700D01*
X521026Y1511033D01*
X521109Y1511450D01*
X521318Y1511742D01*
X521568Y1511825D01*
X521818Y1511783D01*
X522026Y1511617D01*
X522443Y1510783D01*
X522734Y1510408D01*
X523151Y1510158D01*
X523526Y1510075D01*
Y1511825D01*
G01X636402Y1527769D02*
Y1470269D01*
X620202D01*
Y1439269D01*
X542002D01*
Y1470269D01*
X525802D01*
Y1527769D01*
X636402D01*
G01X510367Y1484853D02*
X510117Y1484978D01*
X509825Y1485061D01*
X509492D01*
X509117Y1484936D01*
X508825Y1484728D01*
X508617Y1484478D01*
X508450Y1484061D01*
X508408Y1483686D01*
X508492Y1483311D01*
X508617Y1483061D01*
X508867Y1482811D01*
X509158Y1482644D01*
X509450Y1482561D01*
X509742D01*
X510033Y1482644D01*
X510283Y1482769D01*
X510492Y1482936D01*
G01X511633D02*
X511883Y1482728D01*
X512175Y1482603D01*
X512550Y1482561D01*
X512925Y1482644D01*
X513217Y1482811D01*
X513425Y1483103D01*
X513467Y1483436D01*
X513383Y1483769D01*
X513175Y1483978D01*
X512883Y1484144D01*
X512592Y1484186D01*
X512300Y1484144D01*
X511925Y1483978D01*
X512050Y1485061D01*
X513175D01*
G01X514858Y1484644D02*
X515108Y1484894D01*
X515400Y1485019D01*
X515733Y1485061D01*
X516150Y1484978D01*
X516442Y1484769D01*
X516525Y1484519D01*
X516483Y1484269D01*
X516317Y1484061D01*
X515483Y1483644D01*
X515108Y1483353D01*
X514858Y1482936D01*
X514775Y1482561D01*
X516525D01*
G01X518750D02*
X519042Y1482603D01*
X519375Y1482728D01*
X519583Y1482936D01*
X519667Y1483228D01*
X519583Y1483519D01*
X519333Y1483769D01*
X518958Y1483894D01*
X518542D01*
X518292Y1483978D01*
X518083Y1484186D01*
X518000Y1484478D01*
X518125Y1484769D01*
X518417Y1484978D01*
X518750Y1485061D01*
X519083Y1484978D01*
X519375Y1484769D01*
X519500Y1484478D01*
X519417Y1484186D01*
X519208Y1483978D01*
X518958Y1483894D01*
X518542D01*
X518167Y1483769D01*
X517917Y1483519D01*
X517833Y1483228D01*
X517917Y1482936D01*
X518125Y1482728D01*
X518458Y1482603D01*
X518750Y1482561D01*
G01X505300Y1472500D02*
Y1468500D01*
X512700D01*
G01X502000Y1470700D02*
X498000D01*
Y1463300D01*
G01X508617Y1486561D02*
Y1489061D01*
X509658D01*
X509992Y1488936D01*
X510200Y1488769D01*
X510283Y1488436D01*
X510200Y1488103D01*
X509950Y1487894D01*
X509658Y1487769D01*
X508617D01*
G01X509658D02*
X510283Y1486561D01*
G01X511842Y1486853D02*
X512133Y1486644D01*
X512467Y1486561D01*
X512800Y1486644D01*
X513092Y1486894D01*
X513300Y1487269D01*
X513383Y1487644D01*
Y1488103D01*
X513300Y1488478D01*
X513092Y1488811D01*
X512842Y1488978D01*
X512550Y1489061D01*
X512217Y1488978D01*
X511967Y1488811D01*
X511800Y1488561D01*
X511717Y1488228D01*
X511800Y1487936D01*
X512008Y1487644D01*
X512258Y1487478D01*
X512550Y1487436D01*
X512883Y1487519D01*
X513133Y1487728D01*
X513383Y1488103D01*
G01X514733Y1487061D02*
X514983Y1486769D01*
X515317Y1486603D01*
X515692Y1486561D01*
X516025Y1486603D01*
X516358Y1486811D01*
X516567Y1487061D01*
X516608Y1487311D01*
X516525Y1487603D01*
X516233Y1487811D01*
X515942Y1487894D01*
X515567D01*
G01X515942D02*
X516192Y1488019D01*
X516400Y1488228D01*
X516483Y1488478D01*
X516400Y1488728D01*
X516192Y1488936D01*
X515817Y1489061D01*
X515442Y1489019D01*
X515067Y1488853D01*
G01X518750Y1486561D02*
X519042Y1486603D01*
X519375Y1486728D01*
X519583Y1486936D01*
X519667Y1487228D01*
X519583Y1487519D01*
X519333Y1487769D01*
X518958Y1487894D01*
X518542D01*
X518292Y1487978D01*
X518083Y1488186D01*
X518000Y1488478D01*
X518125Y1488769D01*
X518417Y1488978D01*
X518750Y1489061D01*
X519083Y1488978D01*
X519375Y1488769D01*
X519500Y1488478D01*
X519417Y1488186D01*
X519208Y1487978D01*
X518958Y1487894D01*
X518542D01*
X518167Y1487769D01*
X517917Y1487519D01*
X517833Y1487228D01*
X517917Y1486936D01*
X518125Y1486728D01*
X518458Y1486603D01*
X518750Y1486561D01*
G01X523000Y1454100D02*
Y1450100D01*
X530400D01*
G01X508517Y1494500D02*
Y1497000D01*
X509558D01*
X509892Y1496875D01*
X510100Y1496708D01*
X510183Y1496375D01*
X510100Y1496042D01*
X509850Y1495833D01*
X509558Y1495708D01*
X508517D01*
G01X509558D02*
X510183Y1494500D01*
G01X511742Y1494792D02*
X512033Y1494583D01*
X512367Y1494500D01*
X512700Y1494583D01*
X512992Y1494833D01*
X513200Y1495208D01*
X513283Y1495583D01*
Y1496042D01*
X513200Y1496417D01*
X512992Y1496750D01*
X512742Y1496917D01*
X512450Y1497000D01*
X512117Y1496917D01*
X511867Y1496750D01*
X511700Y1496500D01*
X511617Y1496167D01*
X511700Y1495875D01*
X511908Y1495583D01*
X512158Y1495417D01*
X512450Y1495375D01*
X512783Y1495458D01*
X513033Y1495667D01*
X513283Y1496042D01*
G01X516050Y1494500D02*
Y1497000D01*
X514508Y1495208D01*
X516592D01*
G01X518650Y1494500D02*
Y1497000D01*
X518150Y1496500D01*
G01Y1494500D02*
X519150D01*
G01X522800Y1469000D02*
Y1465000D01*
X530200D01*
G01X499000Y1445017D02*
X496500D01*
Y1446058D01*
X496625Y1446392D01*
X496792Y1446600D01*
X497125Y1446683D01*
X497458Y1446600D01*
X497667Y1446350D01*
X497792Y1446058D01*
Y1445017D01*
G01Y1446058D02*
X499000Y1446683D01*
G01Y1448950D02*
X496500D01*
X497000Y1448450D01*
G01X499000D02*
Y1449450D01*
G01X498625Y1451133D02*
X498833Y1451383D01*
X498958Y1451675D01*
X499000Y1452050D01*
X498917Y1452425D01*
X498750Y1452717D01*
X498458Y1452925D01*
X498125Y1452967D01*
X497792Y1452883D01*
X497583Y1452675D01*
X497417Y1452383D01*
X497375Y1452092D01*
X497417Y1451800D01*
X497583Y1451425D01*
X496500Y1451550D01*
Y1452675D01*
G01X499000Y1455150D02*
X496500D01*
X497000Y1454650D01*
G01X499000D02*
Y1455650D01*
G01X500999Y1446232D02*
X504999D01*
Y1453632D01*
G01X508517Y1490500D02*
Y1493000D01*
X509558D01*
X509892Y1492875D01*
X510100Y1492708D01*
X510183Y1492375D01*
X510100Y1492042D01*
X509850Y1491833D01*
X509558Y1491708D01*
X508517D01*
G01X509558D02*
X510183Y1490500D01*
G01X511742Y1490792D02*
X512033Y1490583D01*
X512367Y1490500D01*
X512700Y1490583D01*
X512992Y1490833D01*
X513200Y1491208D01*
X513283Y1491583D01*
Y1492042D01*
X513200Y1492417D01*
X512992Y1492750D01*
X512742Y1492917D01*
X512450Y1493000D01*
X512117Y1492917D01*
X511867Y1492750D01*
X511700Y1492500D01*
X511617Y1492167D01*
X511700Y1491875D01*
X511908Y1491583D01*
X512158Y1491417D01*
X512450Y1491375D01*
X512783Y1491458D01*
X513033Y1491667D01*
X513283Y1492042D01*
G01X516050Y1490500D02*
Y1493000D01*
X514508Y1491208D01*
X516592D01*
G01X518650Y1493000D02*
X518317Y1492917D01*
X518067Y1492708D01*
X517900Y1492458D01*
X517775Y1492125D01*
X517733Y1491750D01*
X517775Y1491375D01*
X517900Y1491042D01*
X518067Y1490792D01*
X518317Y1490583D01*
X518650Y1490500D01*
X518983Y1490583D01*
X519233Y1490792D01*
X519400Y1491042D01*
X519525Y1491375D01*
X519567Y1491750D01*
X519525Y1492125D01*
X519400Y1492458D01*
X519233Y1492708D01*
X518983Y1492917D01*
X518650Y1493000D01*
G01X543434Y1431329D02*
Y1437529D01*
X531034D01*
Y1431329D01*
G01X495500Y1463983D02*
X493000D01*
Y1464817D01*
X493125Y1465150D01*
X493292Y1465400D01*
X493542Y1465608D01*
X493833Y1465775D01*
X494250Y1465817D01*
X494667Y1465775D01*
X494958Y1465608D01*
X495208Y1465400D01*
X495375Y1465150D01*
X495500Y1464817D01*
Y1463983D01*
G01X495000Y1467083D02*
X495292Y1467333D01*
X495458Y1467667D01*
X495500Y1468042D01*
X495458Y1468375D01*
X495250Y1468708D01*
X495000Y1468917D01*
X494750Y1468958D01*
X494458Y1468875D01*
X494250Y1468583D01*
X494167Y1468292D01*
Y1467917D01*
G01Y1468292D02*
X494042Y1468542D01*
X493833Y1468750D01*
X493583Y1468833D01*
X493333Y1468750D01*
X493125Y1468542D01*
X493000Y1468167D01*
X493042Y1467792D01*
X493208Y1467417D01*
G01X495208Y1470392D02*
X495417Y1470683D01*
X495500Y1471017D01*
X495417Y1471350D01*
X495167Y1471642D01*
X494792Y1471850D01*
X494417Y1471933D01*
X493958D01*
X493583Y1471850D01*
X493250Y1471642D01*
X493083Y1471392D01*
X493000Y1471100D01*
X493083Y1470767D01*
X493250Y1470517D01*
X493500Y1470350D01*
X493833Y1470267D01*
X494125Y1470350D01*
X494417Y1470558D01*
X494583Y1470808D01*
X494625Y1471100D01*
X494542Y1471433D01*
X494333Y1471683D01*
X493958Y1471933D01*
G01X521500Y1454774D02*
Y1475774D01*
G01D02*
X513500D01*
G01D02*
Y1454774D01*
G01D02*
X521500D01*
G01X524500Y1485483D02*
X522000D01*
Y1486317D01*
X522125Y1486650D01*
X522292Y1486900D01*
X522542Y1487108D01*
X522833Y1487275D01*
X523250Y1487317D01*
X523667Y1487275D01*
X523958Y1487108D01*
X524208Y1486900D01*
X524375Y1486650D01*
X524500Y1486317D01*
Y1485483D01*
G01Y1490000D02*
X522000D01*
X523792Y1488458D01*
Y1490542D01*
G01X522000Y1492600D02*
X522083Y1492267D01*
X522292Y1492017D01*
X522542Y1491850D01*
X522875Y1491725D01*
X523250Y1491683D01*
X523625Y1491725D01*
X523958Y1491850D01*
X524208Y1492017D01*
X524417Y1492267D01*
X524500Y1492600D01*
X524417Y1492933D01*
X524208Y1493183D01*
X523958Y1493350D01*
X523625Y1493475D01*
X523250Y1493517D01*
X522875Y1493475D01*
X522542Y1493350D01*
X522292Y1493183D01*
X522083Y1492933D01*
X522000Y1492600D01*
G01X531200Y1465100D02*
Y1444100D01*
G01D02*
X539200D01*
G01D02*
Y1465100D01*
G01D02*
X531200D01*
G01X590974Y107319D02*
X596024D01*
Y206019D01*
X620674D01*
Y21619D01*
X596024D01*
Y80319D01*
X590974D01*
Y107319D01*
G01X636767Y58292D02*
X636517Y58417D01*
X636225Y58500D01*
X635892D01*
X635517Y58375D01*
X635225Y58167D01*
X635017Y57917D01*
X634850Y57500D01*
X634808Y57125D01*
X634892Y56750D01*
X635017Y56500D01*
X635267Y56250D01*
X635558Y56083D01*
X635850Y56000D01*
X636142D01*
X636433Y56083D01*
X636683Y56208D01*
X636892Y56375D01*
G01X638033Y56500D02*
X638283Y56208D01*
X638617Y56042D01*
X638992Y56000D01*
X639325Y56042D01*
X639658Y56250D01*
X639867Y56500D01*
X639908Y56750D01*
X639825Y57042D01*
X639533Y57250D01*
X639242Y57333D01*
X638867D01*
G01X639242D02*
X639492Y57458D01*
X639700Y57667D01*
X639783Y57917D01*
X639700Y58167D01*
X639492Y58375D01*
X639117Y58500D01*
X638742Y58458D01*
X638367Y58292D01*
G01X641342Y56292D02*
X641633Y56083D01*
X641967Y56000D01*
X642300Y56083D01*
X642592Y56333D01*
X642800Y56708D01*
X642883Y57083D01*
Y57542D01*
X642800Y57917D01*
X642592Y58250D01*
X642342Y58417D01*
X642050Y58500D01*
X641717Y58417D01*
X641467Y58250D01*
X641300Y58000D01*
X641217Y57667D01*
X641300Y57375D01*
X641508Y57083D01*
X641758Y56917D01*
X642050Y56875D01*
X642383Y56958D01*
X642633Y57167D01*
X642883Y57542D01*
G01X644233Y56500D02*
X644483Y56208D01*
X644817Y56042D01*
X645192Y56000D01*
X645525Y56042D01*
X645858Y56250D01*
X646067Y56500D01*
X646108Y56750D01*
X646025Y57042D01*
X645733Y57250D01*
X645442Y57333D01*
X645067D01*
G01X645442D02*
X645692Y57458D01*
X645900Y57667D01*
X645983Y57917D01*
X645900Y58167D01*
X645692Y58375D01*
X645317Y58500D01*
X644942Y58458D01*
X644567Y58292D01*
G01X636767Y62292D02*
X636517Y62417D01*
X636225Y62500D01*
X635892D01*
X635517Y62375D01*
X635225Y62167D01*
X635017Y61917D01*
X634850Y61500D01*
X634808Y61125D01*
X634892Y60750D01*
X635017Y60500D01*
X635267Y60250D01*
X635558Y60083D01*
X635850Y60000D01*
X636142D01*
X636433Y60083D01*
X636683Y60208D01*
X636892Y60375D01*
G01X638033Y60500D02*
X638283Y60208D01*
X638617Y60042D01*
X638992Y60000D01*
X639325Y60042D01*
X639658Y60250D01*
X639867Y60500D01*
X639908Y60750D01*
X639825Y61042D01*
X639533Y61250D01*
X639242Y61333D01*
X638867D01*
G01X639242D02*
X639492Y61458D01*
X639700Y61667D01*
X639783Y61917D01*
X639700Y62167D01*
X639492Y62375D01*
X639117Y62500D01*
X638742Y62458D01*
X638367Y62292D01*
G01X641342Y60292D02*
X641633Y60083D01*
X641967Y60000D01*
X642300Y60083D01*
X642592Y60333D01*
X642800Y60708D01*
X642883Y61083D01*
Y61542D01*
X642800Y61917D01*
X642592Y62250D01*
X642342Y62417D01*
X642050Y62500D01*
X641717Y62417D01*
X641467Y62250D01*
X641300Y62000D01*
X641217Y61667D01*
X641300Y61375D01*
X641508Y61083D01*
X641758Y60917D01*
X642050Y60875D01*
X642383Y60958D01*
X642633Y61167D01*
X642883Y61542D01*
G01X644358Y62083D02*
X644608Y62333D01*
X644900Y62458D01*
X645233Y62500D01*
X645650Y62417D01*
X645942Y62208D01*
X646025Y61958D01*
X645983Y61708D01*
X645817Y61500D01*
X644983Y61083D01*
X644608Y60792D01*
X644358Y60375D01*
X644275Y60000D01*
X646025D01*
G01X581017Y53500D02*
Y56000D01*
X582058D01*
X582392Y55875D01*
X582600Y55708D01*
X582683Y55375D01*
X582600Y55042D01*
X582350Y54833D01*
X582058Y54708D01*
X581017D01*
G01X582058D02*
X582683Y53500D01*
G01X584867D02*
X584950Y54042D01*
X585075Y54500D01*
X585242Y54917D01*
X585450Y55375D01*
X585783Y56000D01*
X584117D01*
G01X587258Y55583D02*
X587508Y55833D01*
X587800Y55958D01*
X588133Y56000D01*
X588550Y55917D01*
X588842Y55708D01*
X588925Y55458D01*
X588883Y55208D01*
X588717Y55000D01*
X587883Y54583D01*
X587508Y54292D01*
X587258Y53875D01*
X587175Y53500D01*
X588925D01*
G01X590358Y55583D02*
X590608Y55833D01*
X590900Y55958D01*
X591233Y56000D01*
X591650Y55917D01*
X591942Y55708D01*
X592025Y55458D01*
X591983Y55208D01*
X591817Y55000D01*
X590983Y54583D01*
X590608Y54292D01*
X590358Y53875D01*
X590275Y53500D01*
X592025D01*
G01X591100Y70800D02*
Y74800D01*
X583700D01*
G01X581017Y49500D02*
Y52000D01*
X582058D01*
X582392Y51875D01*
X582600Y51708D01*
X582683Y51375D01*
X582600Y51042D01*
X582350Y50833D01*
X582058Y50708D01*
X581017D01*
G01X582058D02*
X582683Y49500D01*
G01X584867D02*
X584950Y50042D01*
X585075Y50500D01*
X585242Y50917D01*
X585450Y51375D01*
X585783Y52000D01*
X584117D01*
G01X587258Y51583D02*
X587508Y51833D01*
X587800Y51958D01*
X588133Y52000D01*
X588550Y51917D01*
X588842Y51708D01*
X588925Y51458D01*
X588883Y51208D01*
X588717Y51000D01*
X587883Y50583D01*
X587508Y50292D01*
X587258Y49875D01*
X587175Y49500D01*
X588925D01*
G01X590233Y49875D02*
X590483Y49667D01*
X590775Y49542D01*
X591150Y49500D01*
X591525Y49583D01*
X591817Y49750D01*
X592025Y50042D01*
X592067Y50375D01*
X591983Y50708D01*
X591775Y50917D01*
X591483Y51083D01*
X591192Y51125D01*
X590900Y51083D01*
X590525Y50917D01*
X590650Y52000D01*
X591775D01*
G01X589200Y62300D02*
Y66300D01*
X581800D01*
G01X581017Y57500D02*
Y60000D01*
X582058D01*
X582392Y59875D01*
X582600Y59708D01*
X582683Y59375D01*
X582600Y59042D01*
X582350Y58833D01*
X582058Y58708D01*
X581017D01*
G01X582058D02*
X582683Y57500D01*
G01X584867D02*
X584950Y58042D01*
X585075Y58500D01*
X585242Y58917D01*
X585450Y59375D01*
X585783Y60000D01*
X584117D01*
G01X587258Y59583D02*
X587508Y59833D01*
X587800Y59958D01*
X588133Y60000D01*
X588550Y59917D01*
X588842Y59708D01*
X588925Y59458D01*
X588883Y59208D01*
X588717Y59000D01*
X587883Y58583D01*
X587508Y58292D01*
X587258Y57875D01*
X587175Y57500D01*
X588925D01*
G01X591067D02*
X591150Y58042D01*
X591275Y58500D01*
X591442Y58917D01*
X591650Y59375D01*
X591983Y60000D01*
X590317D01*
G01X583800Y79000D02*
Y75000D01*
X591200D01*
G01X667200Y90400D02*
X686400D01*
Y101600D01*
X667200D01*
Y90400D01*
X667600D01*
G01X583200Y70300D02*
Y83700D01*
G01X623035Y131267D02*
X622910Y131017D01*
X622827Y130725D01*
Y130392D01*
X622952Y130017D01*
X623160Y129725D01*
X623410Y129517D01*
X623827Y129350D01*
X624202Y129308D01*
X624577Y129392D01*
X624827Y129517D01*
X625077Y129767D01*
X625244Y130058D01*
X625327Y130350D01*
Y130642D01*
X625244Y130933D01*
X625119Y131183D01*
X624952Y131392D01*
G01X625327Y133950D02*
X622827D01*
X624619Y132408D01*
Y134492D01*
G01X622827Y136550D02*
X622910Y136217D01*
X623119Y135967D01*
X623369Y135800D01*
X623702Y135675D01*
X624077Y135633D01*
X624452Y135675D01*
X624785Y135800D01*
X625035Y135967D01*
X625244Y136217D01*
X625327Y136550D01*
X625244Y136883D01*
X625035Y137133D01*
X624785Y137300D01*
X624452Y137425D01*
X624077Y137467D01*
X623702Y137425D01*
X623369Y137300D01*
X623119Y137133D01*
X622910Y136883D01*
X622827Y136550D01*
G01Y139650D02*
X622910Y139317D01*
X623119Y139067D01*
X623369Y138900D01*
X623702Y138775D01*
X624077Y138733D01*
X624452Y138775D01*
X624785Y138900D01*
X625035Y139067D01*
X625244Y139317D01*
X625327Y139650D01*
X625244Y139983D01*
X625035Y140233D01*
X624785Y140400D01*
X624452Y140525D01*
X624077Y140567D01*
X623702Y140525D01*
X623369Y140400D01*
X623119Y140233D01*
X622910Y139983D01*
X622827Y139650D01*
G01X629327Y129517D02*
X626827D01*
Y130558D01*
X626952Y130892D01*
X627119Y131100D01*
X627452Y131183D01*
X627785Y131100D01*
X627994Y130850D01*
X628119Y130558D01*
Y129517D01*
G01Y130558D02*
X629327Y131183D01*
G01Y133367D02*
X628785Y133450D01*
X628327Y133575D01*
X627910Y133742D01*
X627452Y133950D01*
X626827Y134283D01*
Y132617D01*
G01X629327Y136550D02*
X626827D01*
X627327Y136050D01*
G01X629327D02*
Y137050D01*
G01Y140150D02*
X626827D01*
X628619Y138608D01*
Y140692D01*
G01X626000Y120800D02*
X630000D01*
Y128200D01*
G01X579767Y183792D02*
X579517Y183917D01*
X579225Y184000D01*
X578892D01*
X578517Y183875D01*
X578225Y183667D01*
X578017Y183417D01*
X577850Y183000D01*
X577808Y182625D01*
X577892Y182250D01*
X578017Y182000D01*
X578267Y181750D01*
X578558Y181583D01*
X578850Y181500D01*
X579142D01*
X579433Y181583D01*
X579683Y181708D01*
X579892Y181875D01*
G01X582450Y181500D02*
Y184000D01*
X580908Y182208D01*
X582992D01*
G01X585050Y184000D02*
X584717Y183917D01*
X584467Y183708D01*
X584300Y183458D01*
X584175Y183125D01*
X584133Y182750D01*
X584175Y182375D01*
X584300Y182042D01*
X584467Y181792D01*
X584717Y181583D01*
X585050Y181500D01*
X585383Y181583D01*
X585633Y181792D01*
X585800Y182042D01*
X585925Y182375D01*
X585967Y182750D01*
X585925Y183125D01*
X585800Y183458D01*
X585633Y183708D01*
X585383Y183917D01*
X585050Y184000D01*
G01X588150Y181500D02*
Y184000D01*
X587650Y183500D01*
G01Y181500D02*
X588650D01*
G01X627800Y163000D02*
Y160500D01*
G01X626842Y163000D02*
X628758D01*
G01X630067Y160500D02*
Y163000D01*
X631067D01*
X631400Y162875D01*
X631650Y162583D01*
X631733Y162250D01*
X631650Y161917D01*
X631442Y161667D01*
X631067Y161542D01*
X630067D01*
G01X634000Y160500D02*
Y163000D01*
X633500Y162500D01*
G01Y160500D02*
X634500D01*
G01X636308Y161542D02*
X636600Y161833D01*
X636850Y162000D01*
X637183Y162083D01*
X637475Y162000D01*
X637683Y161833D01*
X637850Y161583D01*
X637892Y161292D01*
X637850Y161042D01*
X637683Y160792D01*
X637433Y160583D01*
X637142Y160500D01*
X636808Y160583D01*
X636517Y160833D01*
X636350Y161208D01*
X636308Y161625D01*
X636392Y162167D01*
X636517Y162458D01*
X636725Y162750D01*
X637017Y162958D01*
X637308Y163000D01*
X637600Y162917D01*
X637808Y162708D01*
G01X640200Y160500D02*
Y163000D01*
X639700Y162500D01*
G01Y160500D02*
X640700D01*
G01X589200Y101500D02*
X587100Y103300D01*
X589200Y105500D01*
G01X667300Y98000D02*
X669400Y96200D01*
X667300Y94000D01*
G01X638500Y136017D02*
X636000D01*
Y137058D01*
X636125Y137392D01*
X636292Y137600D01*
X636625Y137683D01*
X636958Y137600D01*
X637167Y137350D01*
X637292Y137058D01*
Y136017D01*
G01Y137058D02*
X638500Y137683D01*
G01Y139867D02*
X637958Y139950D01*
X637500Y140075D01*
X637083Y140242D01*
X636625Y140450D01*
X636000Y140783D01*
Y139117D01*
G01X638500Y143050D02*
X636000D01*
X636500Y142550D01*
G01X638500D02*
Y143550D01*
G01Y146150D02*
X638458Y146442D01*
X638333Y146775D01*
X638125Y146983D01*
X637833Y147067D01*
X637542Y146983D01*
X637292Y146733D01*
X637167Y146358D01*
Y145942D01*
X637083Y145692D01*
X636875Y145483D01*
X636583Y145400D01*
X636292Y145525D01*
X636083Y145817D01*
X636000Y146150D01*
X636083Y146483D01*
X636292Y146775D01*
X636583Y146900D01*
X636875Y146817D01*
X637083Y146608D01*
X637167Y146358D01*
Y145942D01*
X637292Y145567D01*
X637542Y145317D01*
X637833Y145233D01*
X638125Y145317D01*
X638333Y145525D01*
X638458Y145858D01*
X638500Y146150D01*
G01X584800Y122000D02*
X579300D01*
G01X584800Y130000D02*
Y122000D01*
G01X579300Y130000D02*
X584800D01*
G01X591500Y141517D02*
X589000D01*
Y142558D01*
X589125Y142892D01*
X589292Y143100D01*
X589625Y143183D01*
X589958Y143100D01*
X590167Y142850D01*
X590292Y142558D01*
Y141517D01*
G01Y142558D02*
X591500Y143183D01*
G01Y145367D02*
X590958Y145450D01*
X590500Y145575D01*
X590083Y145742D01*
X589625Y145950D01*
X589000Y146283D01*
Y144617D01*
G01X591500Y148550D02*
X589000D01*
X589500Y148050D01*
G01X591500D02*
Y149050D01*
G01X591000Y150733D02*
X591292Y150983D01*
X591458Y151317D01*
X591500Y151692D01*
X591458Y152025D01*
X591250Y152358D01*
X591000Y152567D01*
X590750Y152608D01*
X590458Y152525D01*
X590250Y152233D01*
X590167Y151942D01*
Y151567D01*
G01Y151942D02*
X590042Y152192D01*
X589833Y152400D01*
X589583Y152483D01*
X589333Y152400D01*
X589125Y152192D01*
X589000Y151817D01*
X589042Y151442D01*
X589208Y151067D01*
G01X586500Y139800D02*
X594500D01*
Y122200D01*
X586500D01*
Y139800D01*
G01X596275Y208000D02*
Y210500D01*
G01X598025D02*
Y208000D01*
G01Y209250D02*
X596275D01*
G01X599333Y208000D02*
Y210500D01*
X600167D01*
X600500Y210375D01*
X600750Y210208D01*
X600958Y209958D01*
X601125Y209667D01*
X601167Y209250D01*
X601125Y208833D01*
X600958Y208542D01*
X600750Y208292D01*
X600500Y208125D01*
X600167Y208000D01*
X599333D01*
G01X602433D02*
Y210500D01*
X603267D01*
X603600Y210375D01*
X603850Y210208D01*
X604058Y209958D01*
X604225Y209667D01*
X604267Y209250D01*
X604225Y208833D01*
X604058Y208542D01*
X603850Y208292D01*
X603600Y208125D01*
X603267Y208000D01*
X602433D01*
G01X605575Y208333D02*
X605908Y208125D01*
X606283Y208000D01*
X606617D01*
X606950Y208125D01*
X607200Y208333D01*
X607325Y208625D01*
X607242Y208917D01*
X607033Y209167D01*
X606658Y209333D01*
X606158Y209417D01*
X605867Y209583D01*
X605742Y209875D01*
X605825Y210167D01*
X606033Y210375D01*
X606325Y210500D01*
X606617D01*
X606908Y210417D01*
X607158Y210208D01*
G01X608508Y208000D02*
X609550Y210500D01*
X610592Y208000D01*
G01X610217Y208875D02*
X608883D01*
G01X611775Y208333D02*
X612108Y208125D01*
X612483Y208000D01*
X612817D01*
X613150Y208125D01*
X613400Y208333D01*
X613525Y208625D01*
X613442Y208917D01*
X613233Y209167D01*
X612858Y209333D01*
X612358Y209417D01*
X612067Y209583D01*
X611942Y209875D01*
X612025Y210167D01*
X612233Y210375D01*
X612525Y210500D01*
X612817D01*
X613108Y210417D01*
X613358Y210208D01*
G01X614958Y210083D02*
X615208Y210333D01*
X615500Y210458D01*
X615833Y210500D01*
X616250Y210417D01*
X616542Y210208D01*
X616625Y209958D01*
X616583Y209708D01*
X616417Y209500D01*
X615583Y209083D01*
X615208Y208792D01*
X614958Y208375D01*
X614875Y208000D01*
X616625D01*
G01X618850D02*
X619142Y208042D01*
X619475Y208167D01*
X619683Y208375D01*
X619767Y208667D01*
X619683Y208958D01*
X619433Y209208D01*
X619058Y209333D01*
X618642D01*
X618392Y209417D01*
X618183Y209625D01*
X618100Y209917D01*
X618225Y210208D01*
X618517Y210417D01*
X618850Y210500D01*
X619183Y210417D01*
X619475Y210208D01*
X619600Y209917D01*
X619517Y209625D01*
X619308Y209417D01*
X619058Y209333D01*
X618642D01*
X618267Y209208D01*
X618017Y208958D01*
X617933Y208667D01*
X618017Y208375D01*
X618225Y208167D01*
X618558Y208042D01*
X618850Y208000D01*
G01X590974Y560075D02*
X596024D01*
Y658775D01*
X620674D01*
Y474375D01*
X596024D01*
Y533075D01*
X590974D01*
Y560075D01*
G01X636517Y382000D02*
Y384500D01*
X637558D01*
X637892Y384375D01*
X638100Y384208D01*
X638183Y383875D01*
X638100Y383542D01*
X637850Y383333D01*
X637558Y383208D01*
X636517D01*
G01X637558D02*
X638183Y382000D01*
G01X639533Y382500D02*
X639783Y382208D01*
X640117Y382042D01*
X640492Y382000D01*
X640825Y382042D01*
X641158Y382250D01*
X641367Y382500D01*
X641408Y382750D01*
X641325Y383042D01*
X641033Y383250D01*
X640742Y383333D01*
X640367D01*
G01X640742D02*
X640992Y383458D01*
X641200Y383667D01*
X641283Y383917D01*
X641200Y384167D01*
X640992Y384375D01*
X640617Y384500D01*
X640242Y384458D01*
X639867Y384292D01*
G01X642842Y382292D02*
X643133Y382083D01*
X643467Y382000D01*
X643800Y382083D01*
X644092Y382333D01*
X644300Y382708D01*
X644383Y383083D01*
Y383542D01*
X644300Y383917D01*
X644092Y384250D01*
X643842Y384417D01*
X643550Y384500D01*
X643217Y384417D01*
X642967Y384250D01*
X642800Y384000D01*
X642717Y383667D01*
X642800Y383375D01*
X643008Y383083D01*
X643258Y382917D01*
X643550Y382875D01*
X643883Y382958D01*
X644133Y383167D01*
X644383Y383542D01*
G01X646650Y382000D02*
X646942Y382042D01*
X647275Y382167D01*
X647483Y382375D01*
X647567Y382667D01*
X647483Y382958D01*
X647233Y383208D01*
X646858Y383333D01*
X646442D01*
X646192Y383417D01*
X645983Y383625D01*
X645900Y383917D01*
X646025Y384208D01*
X646317Y384417D01*
X646650Y384500D01*
X646983Y384417D01*
X647275Y384208D01*
X647400Y383917D01*
X647317Y383625D01*
X647108Y383417D01*
X646858Y383333D01*
X646442D01*
X646067Y383208D01*
X645817Y382958D01*
X645733Y382667D01*
X645817Y382375D01*
X646025Y382167D01*
X646358Y382042D01*
X646650Y382000D01*
G01X656192Y381182D02*
Y385182D01*
X648792D01*
G01X656517Y406000D02*
Y408500D01*
X657558D01*
X657892Y408375D01*
X658100Y408208D01*
X658183Y407875D01*
X658100Y407542D01*
X657850Y407333D01*
X657558Y407208D01*
X656517D01*
G01X657558D02*
X658183Y406000D01*
G01X659533Y406500D02*
X659783Y406208D01*
X660117Y406042D01*
X660492Y406000D01*
X660825Y406042D01*
X661158Y406250D01*
X661367Y406500D01*
X661408Y406750D01*
X661325Y407042D01*
X661033Y407250D01*
X660742Y407333D01*
X660367D01*
G01X660742D02*
X660992Y407458D01*
X661200Y407667D01*
X661283Y407917D01*
X661200Y408167D01*
X660992Y408375D01*
X660617Y408500D01*
X660242Y408458D01*
X659867Y408292D01*
G01X662842Y406292D02*
X663133Y406083D01*
X663467Y406000D01*
X663800Y406083D01*
X664092Y406333D01*
X664300Y406708D01*
X664383Y407083D01*
Y407542D01*
X664300Y407917D01*
X664092Y408250D01*
X663842Y408417D01*
X663550Y408500D01*
X663217Y408417D01*
X662967Y408250D01*
X662800Y408000D01*
X662717Y407667D01*
X662800Y407375D01*
X663008Y407083D01*
X663258Y406917D01*
X663550Y406875D01*
X663883Y406958D01*
X664133Y407167D01*
X664383Y407542D01*
G01X665733Y406375D02*
X665983Y406167D01*
X666275Y406042D01*
X666650Y406000D01*
X667025Y406083D01*
X667317Y406250D01*
X667525Y406542D01*
X667567Y406875D01*
X667483Y407208D01*
X667275Y407417D01*
X666983Y407583D01*
X666692Y407625D01*
X666400Y407583D01*
X666025Y407417D01*
X666150Y408500D01*
X667275D01*
G01X670925Y400959D02*
Y404959D01*
X663525D01*
G01X660576Y381101D02*
X660243Y381143D01*
X659951Y381309D01*
X659701Y381559D01*
X659534Y381851D01*
X659451Y382184D01*
Y382518D01*
X659534Y382851D01*
X659701Y383143D01*
X659951Y383393D01*
X660243Y383559D01*
X660576Y383601D01*
X660909Y383559D01*
X661201Y383393D01*
X661451Y383143D01*
X661618Y382851D01*
X661701Y382518D01*
Y382184D01*
X661618Y381851D01*
X661451Y381559D01*
X661201Y381309D01*
X660909Y381143D01*
X660576Y381101D01*
G01X660909Y381768D02*
X661409Y381101D01*
G01X662884Y383184D02*
X663134Y383434D01*
X663426Y383559D01*
X663759Y383601D01*
X664176Y383518D01*
X664468Y383309D01*
X664551Y383059D01*
X664509Y382809D01*
X664343Y382601D01*
X663509Y382184D01*
X663134Y381893D01*
X662884Y381476D01*
X662801Y381101D01*
X664551D01*
G01X665859Y381601D02*
X666109Y381309D01*
X666443Y381143D01*
X666818Y381101D01*
X667151Y381143D01*
X667484Y381351D01*
X667693Y381601D01*
X667734Y381851D01*
X667651Y382143D01*
X667359Y382351D01*
X667068Y382434D01*
X666693D01*
G01X667068D02*
X667318Y382559D01*
X667526Y382768D01*
X667609Y383018D01*
X667526Y383268D01*
X667318Y383476D01*
X666943Y383601D01*
X666568Y383559D01*
X666193Y383393D01*
G01X669084Y382143D02*
X669376Y382434D01*
X669626Y382601D01*
X669959Y382684D01*
X670251Y382601D01*
X670459Y382434D01*
X670626Y382184D01*
X670668Y381893D01*
X670626Y381643D01*
X670459Y381393D01*
X670209Y381184D01*
X669918Y381101D01*
X669584Y381184D01*
X669293Y381434D01*
X669126Y381809D01*
X669084Y382226D01*
X669168Y382768D01*
X669293Y383059D01*
X669501Y383351D01*
X669793Y383559D01*
X670084Y383601D01*
X670376Y383518D01*
X670584Y383309D01*
G01X671600Y385600D02*
Y399600D01*
G01X658600Y385600D02*
X671600D01*
G01X658600Y399600D02*
Y385600D01*
G01X671600Y399600D02*
X658600D01*
G01X642850Y401500D02*
X642517Y401542D01*
X642225Y401708D01*
X641975Y401958D01*
X641808Y402250D01*
X641725Y402583D01*
Y402917D01*
X641808Y403250D01*
X641975Y403542D01*
X642225Y403792D01*
X642517Y403958D01*
X642850Y404000D01*
X643183Y403958D01*
X643475Y403792D01*
X643725Y403542D01*
X643892Y403250D01*
X643975Y402917D01*
Y402583D01*
X643892Y402250D01*
X643725Y401958D01*
X643475Y401708D01*
X643183Y401542D01*
X642850Y401500D01*
G01X643183Y402167D02*
X643683Y401500D01*
G01X645158Y403583D02*
X645408Y403833D01*
X645700Y403958D01*
X646033Y404000D01*
X646450Y403917D01*
X646742Y403708D01*
X646825Y403458D01*
X646783Y403208D01*
X646617Y403000D01*
X645783Y402583D01*
X645408Y402292D01*
X645158Y401875D01*
X645075Y401500D01*
X646825D01*
G01X648133Y401875D02*
X648383Y401667D01*
X648675Y401542D01*
X649050Y401500D01*
X649425Y401583D01*
X649717Y401750D01*
X649925Y402042D01*
X649967Y402375D01*
X649883Y402708D01*
X649675Y402917D01*
X649383Y403083D01*
X649092Y403125D01*
X648800Y403083D01*
X648425Y402917D01*
X648550Y404000D01*
X649675D01*
G01X651442Y401792D02*
X651733Y401583D01*
X652067Y401500D01*
X652400Y401583D01*
X652692Y401833D01*
X652900Y402208D01*
X652983Y402583D01*
Y403042D01*
X652900Y403417D01*
X652692Y403750D01*
X652442Y403917D01*
X652150Y404000D01*
X651817Y403917D01*
X651567Y403750D01*
X651400Y403500D01*
X651317Y403167D01*
X651400Y402875D01*
X651608Y402583D01*
X651858Y402417D01*
X652150Y402375D01*
X652483Y402458D01*
X652733Y402667D01*
X652983Y403042D01*
G01X643492Y386407D02*
X657492D01*
G01X643492Y399407D02*
Y386407D01*
G01X657492Y399407D02*
X643492D01*
G01X657492Y386407D02*
Y399407D01*
G01X635767Y510292D02*
X635517Y510417D01*
X635225Y510500D01*
X634892D01*
X634517Y510375D01*
X634225Y510167D01*
X634017Y509917D01*
X633850Y509500D01*
X633808Y509125D01*
X633892Y508750D01*
X634017Y508500D01*
X634267Y508250D01*
X634558Y508083D01*
X634850Y508000D01*
X635142D01*
X635433Y508083D01*
X635683Y508208D01*
X635892Y508375D01*
G01X637158Y510083D02*
X637408Y510333D01*
X637700Y510458D01*
X638033Y510500D01*
X638450Y510417D01*
X638742Y510208D01*
X638825Y509958D01*
X638783Y509708D01*
X638617Y509500D01*
X637783Y509083D01*
X637408Y508792D01*
X637158Y508375D01*
X637075Y508000D01*
X638825D01*
G01X640133Y508500D02*
X640383Y508208D01*
X640717Y508042D01*
X641092Y508000D01*
X641425Y508042D01*
X641758Y508250D01*
X641967Y508500D01*
X642008Y508750D01*
X641925Y509042D01*
X641633Y509250D01*
X641342Y509333D01*
X640967D01*
G01X641342D02*
X641592Y509458D01*
X641800Y509667D01*
X641883Y509917D01*
X641800Y510167D01*
X641592Y510375D01*
X641217Y510500D01*
X640842Y510458D01*
X640467Y510292D01*
G01X644067Y508000D02*
X644150Y508542D01*
X644275Y509000D01*
X644442Y509417D01*
X644650Y509875D01*
X644983Y510500D01*
X643317D01*
G01X635767Y514292D02*
X635517Y514417D01*
X635225Y514500D01*
X634892D01*
X634517Y514375D01*
X634225Y514167D01*
X634017Y513917D01*
X633850Y513500D01*
X633808Y513125D01*
X633892Y512750D01*
X634017Y512500D01*
X634267Y512250D01*
X634558Y512083D01*
X634850Y512000D01*
X635142D01*
X635433Y512083D01*
X635683Y512208D01*
X635892Y512375D01*
G01X637158Y514083D02*
X637408Y514333D01*
X637700Y514458D01*
X638033Y514500D01*
X638450Y514417D01*
X638742Y514208D01*
X638825Y513958D01*
X638783Y513708D01*
X638617Y513500D01*
X637783Y513083D01*
X637408Y512792D01*
X637158Y512375D01*
X637075Y512000D01*
X638825D01*
G01X640133Y512500D02*
X640383Y512208D01*
X640717Y512042D01*
X641092Y512000D01*
X641425Y512042D01*
X641758Y512250D01*
X641967Y512500D01*
X642008Y512750D01*
X641925Y513042D01*
X641633Y513250D01*
X641342Y513333D01*
X640967D01*
G01X641342D02*
X641592Y513458D01*
X641800Y513667D01*
X641883Y513917D01*
X641800Y514167D01*
X641592Y514375D01*
X641217Y514500D01*
X640842Y514458D01*
X640467Y514292D01*
G01X643358Y513042D02*
X643650Y513333D01*
X643900Y513500D01*
X644233Y513583D01*
X644525Y513500D01*
X644733Y513333D01*
X644900Y513083D01*
X644942Y512792D01*
X644900Y512542D01*
X644733Y512292D01*
X644483Y512083D01*
X644192Y512000D01*
X643858Y512083D01*
X643567Y512333D01*
X643400Y512708D01*
X643358Y513125D01*
X643442Y513667D01*
X643567Y513958D01*
X643775Y514250D01*
X644067Y514458D01*
X644358Y514500D01*
X644650Y514417D01*
X644858Y514208D01*
G01X672267Y543953D02*
X672017Y544078D01*
X671725Y544161D01*
X671392D01*
X671017Y544036D01*
X670725Y543828D01*
X670517Y543578D01*
X670350Y543161D01*
X670308Y542786D01*
X670392Y542411D01*
X670517Y542161D01*
X670767Y541911D01*
X671058Y541744D01*
X671350Y541661D01*
X671642D01*
X671933Y541744D01*
X672183Y541869D01*
X672392Y542036D01*
G01X673658Y543744D02*
X673908Y543994D01*
X674200Y544119D01*
X674533Y544161D01*
X674950Y544078D01*
X675242Y543869D01*
X675325Y543619D01*
X675283Y543369D01*
X675117Y543161D01*
X674283Y542744D01*
X673908Y542453D01*
X673658Y542036D01*
X673575Y541661D01*
X675325D01*
G01X676633Y542036D02*
X676883Y541828D01*
X677175Y541703D01*
X677550Y541661D01*
X677925Y541744D01*
X678217Y541911D01*
X678425Y542203D01*
X678467Y542536D01*
X678383Y542869D01*
X678175Y543078D01*
X677883Y543244D01*
X677592Y543286D01*
X677300Y543244D01*
X676925Y543078D01*
X677050Y544161D01*
X678175D01*
G01X679942Y541953D02*
X680233Y541744D01*
X680567Y541661D01*
X680900Y541744D01*
X681192Y541994D01*
X681400Y542369D01*
X681483Y542744D01*
Y543203D01*
X681400Y543578D01*
X681192Y543911D01*
X680942Y544078D01*
X680650Y544161D01*
X680317Y544078D01*
X680067Y543911D01*
X679900Y543661D01*
X679817Y543328D01*
X679900Y543036D01*
X680108Y542744D01*
X680358Y542578D01*
X680650Y542536D01*
X680983Y542619D01*
X681233Y542828D01*
X681483Y543203D01*
G01X659267Y551992D02*
X659017Y552117D01*
X658725Y552200D01*
X658392D01*
X658017Y552075D01*
X657725Y551867D01*
X657517Y551617D01*
X657350Y551200D01*
X657308Y550825D01*
X657392Y550450D01*
X657517Y550200D01*
X657767Y549950D01*
X658058Y549783D01*
X658350Y549700D01*
X658642D01*
X658933Y549783D01*
X659183Y549908D01*
X659392Y550075D01*
G01X660658Y551783D02*
X660908Y552033D01*
X661200Y552158D01*
X661533Y552200D01*
X661950Y552117D01*
X662242Y551908D01*
X662325Y551658D01*
X662283Y551408D01*
X662117Y551200D01*
X661283Y550783D01*
X660908Y550492D01*
X660658Y550075D01*
X660575Y549700D01*
X662325D01*
G01X663758Y550742D02*
X664050Y551033D01*
X664300Y551200D01*
X664633Y551283D01*
X664925Y551200D01*
X665133Y551033D01*
X665300Y550783D01*
X665342Y550492D01*
X665300Y550242D01*
X665133Y549992D01*
X664883Y549783D01*
X664592Y549700D01*
X664258Y549783D01*
X663967Y550033D01*
X663800Y550408D01*
X663758Y550825D01*
X663842Y551367D01*
X663967Y551658D01*
X664175Y551950D01*
X664467Y552158D01*
X664758Y552200D01*
X665050Y552117D01*
X665258Y551908D01*
G01X667650Y552200D02*
X667317Y552117D01*
X667067Y551908D01*
X666900Y551658D01*
X666775Y551325D01*
X666733Y550950D01*
X666775Y550575D01*
X666900Y550242D01*
X667067Y549992D01*
X667317Y549783D01*
X667650Y549700D01*
X667983Y549783D01*
X668233Y549992D01*
X668400Y550242D01*
X668525Y550575D01*
X668567Y550950D01*
X668525Y551325D01*
X668400Y551658D01*
X668233Y551908D01*
X667983Y552117D01*
X667650Y552200D01*
G01X581017Y496500D02*
Y499000D01*
X582058D01*
X582392Y498875D01*
X582600Y498708D01*
X582683Y498375D01*
X582600Y498042D01*
X582350Y497833D01*
X582058Y497708D01*
X581017D01*
G01X582058D02*
X582683Y496500D01*
G01X585450D02*
Y499000D01*
X583908Y497208D01*
X585992D01*
G01X588550Y496500D02*
Y499000D01*
X587008Y497208D01*
X589092D01*
G01X590358Y497542D02*
X590650Y497833D01*
X590900Y498000D01*
X591233Y498083D01*
X591525Y498000D01*
X591733Y497833D01*
X591900Y497583D01*
X591942Y497292D01*
X591900Y497042D01*
X591733Y496792D01*
X591483Y496583D01*
X591192Y496500D01*
X590858Y496583D01*
X590567Y496833D01*
X590400Y497208D01*
X590358Y497625D01*
X590442Y498167D01*
X590567Y498458D01*
X590775Y498750D01*
X591067Y498958D01*
X591358Y499000D01*
X591650Y498917D01*
X591858Y498708D01*
G01X591100Y523400D02*
Y527400D01*
X583700D01*
G01X580500Y508017D02*
X578000D01*
Y509058D01*
X578125Y509392D01*
X578292Y509600D01*
X578625Y509683D01*
X578958Y509600D01*
X579167Y509350D01*
X579292Y509058D01*
Y508017D01*
G01Y509058D02*
X580500Y509683D01*
G01Y512450D02*
X578000D01*
X579792Y510908D01*
Y512992D01*
G01X580500Y515550D02*
X578000D01*
X579792Y514008D01*
Y516092D01*
G01X580208Y517442D02*
X580417Y517733D01*
X580500Y518067D01*
X580417Y518400D01*
X580167Y518692D01*
X579792Y518900D01*
X579417Y518983D01*
X578958D01*
X578583Y518900D01*
X578250Y518692D01*
X578083Y518442D01*
X578000Y518150D01*
X578083Y517817D01*
X578250Y517567D01*
X578500Y517400D01*
X578833Y517317D01*
X579125Y517400D01*
X579417Y517608D01*
X579583Y517858D01*
X579625Y518150D01*
X579542Y518483D01*
X579333Y518733D01*
X578958Y518983D01*
G01X581550Y510850D02*
X585550D01*
Y518250D01*
G01X581017Y500500D02*
Y503000D01*
X582058D01*
X582392Y502875D01*
X582600Y502708D01*
X582683Y502375D01*
X582600Y502042D01*
X582350Y501833D01*
X582058Y501708D01*
X581017D01*
G01X582058D02*
X582683Y500500D01*
G01X585450D02*
Y503000D01*
X583908Y501208D01*
X585992D01*
G01X587133Y500875D02*
X587383Y500667D01*
X587675Y500542D01*
X588050Y500500D01*
X588425Y500583D01*
X588717Y500750D01*
X588925Y501042D01*
X588967Y501375D01*
X588883Y501708D01*
X588675Y501917D01*
X588383Y502083D01*
X588092Y502125D01*
X587800Y502083D01*
X587425Y501917D01*
X587550Y503000D01*
X588675D01*
G01X591150Y500500D02*
Y503000D01*
X590650Y502500D01*
G01Y500500D02*
X591650D01*
G01X583800Y531500D02*
Y527500D01*
X591200D01*
G01X670517Y537661D02*
Y540161D01*
X671558D01*
X671892Y540036D01*
X672100Y539869D01*
X672183Y539536D01*
X672100Y539203D01*
X671850Y538994D01*
X671558Y538869D01*
X670517D01*
G01X671558D02*
X672183Y537661D01*
G01X674950D02*
Y540161D01*
X673408Y538369D01*
X675492D01*
G01X676758Y538703D02*
X677050Y538994D01*
X677300Y539161D01*
X677633Y539244D01*
X677925Y539161D01*
X678133Y538994D01*
X678300Y538744D01*
X678342Y538453D01*
X678300Y538203D01*
X678133Y537953D01*
X677883Y537744D01*
X677592Y537661D01*
X677258Y537744D01*
X676967Y537994D01*
X676800Y538369D01*
X676758Y538786D01*
X676842Y539328D01*
X676967Y539619D01*
X677175Y539911D01*
X677467Y540119D01*
X677758Y540161D01*
X678050Y540078D01*
X678258Y539869D01*
G01X680650Y537661D02*
X680942Y537703D01*
X681275Y537828D01*
X681483Y538036D01*
X681567Y538328D01*
X681483Y538619D01*
X681233Y538869D01*
X680858Y538994D01*
X680442D01*
X680192Y539078D01*
X679983Y539286D01*
X679900Y539578D01*
X680025Y539869D01*
X680317Y540078D01*
X680650Y540161D01*
X680983Y540078D01*
X681275Y539869D01*
X681400Y539578D01*
X681317Y539286D01*
X681108Y539078D01*
X680858Y538994D01*
X680442D01*
X680067Y538869D01*
X679817Y538619D01*
X679733Y538328D01*
X679817Y538036D01*
X680025Y537828D01*
X680358Y537703D01*
X680650Y537661D01*
G01X671517Y511500D02*
Y514000D01*
X672558D01*
X672892Y513875D01*
X673100Y513708D01*
X673183Y513375D01*
X673100Y513042D01*
X672850Y512833D01*
X672558Y512708D01*
X671517D01*
G01X672558D02*
X673183Y511500D01*
G01X675950D02*
Y514000D01*
X674408Y512208D01*
X676492D01*
G01X678467Y511500D02*
X678550Y512042D01*
X678675Y512500D01*
X678842Y512917D01*
X679050Y513375D01*
X679383Y514000D01*
X677717D01*
G01X680733Y511875D02*
X680983Y511667D01*
X681275Y511542D01*
X681650Y511500D01*
X682025Y511583D01*
X682317Y511750D01*
X682525Y512042D01*
X682567Y512375D01*
X682483Y512708D01*
X682275Y512917D01*
X681983Y513083D01*
X681692Y513125D01*
X681400Y513083D01*
X681025Y512917D01*
X681150Y514000D01*
X682275D01*
G01X663517Y545761D02*
Y548261D01*
X664558D01*
X664892Y548136D01*
X665100Y547969D01*
X665183Y547636D01*
X665100Y547303D01*
X664850Y547094D01*
X664558Y546969D01*
X663517D01*
G01X664558D02*
X665183Y545761D01*
G01X667950D02*
Y548261D01*
X666408Y546469D01*
X668492D01*
G01X670467Y545761D02*
X670550Y546303D01*
X670675Y546761D01*
X670842Y547178D01*
X671050Y547636D01*
X671383Y548261D01*
X669717D01*
G01X672858Y546803D02*
X673150Y547094D01*
X673400Y547261D01*
X673733Y547344D01*
X674025Y547261D01*
X674233Y547094D01*
X674400Y546844D01*
X674442Y546553D01*
X674400Y546303D01*
X674233Y546053D01*
X673983Y545844D01*
X673692Y545761D01*
X673358Y545844D01*
X673067Y546094D01*
X672900Y546469D01*
X672858Y546886D01*
X672942Y547428D01*
X673067Y547719D01*
X673275Y548011D01*
X673567Y548219D01*
X673858Y548261D01*
X674150Y548178D01*
X674358Y547969D01*
G01X589200Y554000D02*
X587100Y555800D01*
X589200Y558000D01*
G01X668700Y568400D02*
X687900D01*
Y579600D01*
X668700D01*
Y568400D01*
X669100D01*
G01X583200Y522800D02*
Y536200D01*
G01X596275Y661500D02*
Y664000D01*
G01X598025D02*
Y661500D01*
G01Y662750D02*
X596275D01*
G01X599333Y661500D02*
Y664000D01*
X600167D01*
X600500Y663875D01*
X600750Y663708D01*
X600958Y663458D01*
X601125Y663167D01*
X601167Y662750D01*
X601125Y662333D01*
X600958Y662042D01*
X600750Y661792D01*
X600500Y661625D01*
X600167Y661500D01*
X599333D01*
G01X602433D02*
Y664000D01*
X603267D01*
X603600Y663875D01*
X603850Y663708D01*
X604058Y663458D01*
X604225Y663167D01*
X604267Y662750D01*
X604225Y662333D01*
X604058Y662042D01*
X603850Y661792D01*
X603600Y661625D01*
X603267Y661500D01*
X602433D01*
G01X605575Y661833D02*
X605908Y661625D01*
X606283Y661500D01*
X606617D01*
X606950Y661625D01*
X607200Y661833D01*
X607325Y662125D01*
X607242Y662417D01*
X607033Y662667D01*
X606658Y662833D01*
X606158Y662917D01*
X605867Y663083D01*
X605742Y663375D01*
X605825Y663667D01*
X606033Y663875D01*
X606325Y664000D01*
X606617D01*
X606908Y663917D01*
X607158Y663708D01*
G01X608508Y661500D02*
X609550Y664000D01*
X610592Y661500D01*
G01X610217Y662375D02*
X608883D01*
G01X611775Y661833D02*
X612108Y661625D01*
X612483Y661500D01*
X612817D01*
X613150Y661625D01*
X613400Y661833D01*
X613525Y662125D01*
X613442Y662417D01*
X613233Y662667D01*
X612858Y662833D01*
X612358Y662917D01*
X612067Y663083D01*
X611942Y663375D01*
X612025Y663667D01*
X612233Y663875D01*
X612525Y664000D01*
X612817D01*
X613108Y663917D01*
X613358Y663708D01*
G01X615750Y661500D02*
Y664000D01*
X615250Y663500D01*
G01Y661500D02*
X616250D01*
G01X618058Y662542D02*
X618350Y662833D01*
X618600Y663000D01*
X618933Y663083D01*
X619225Y663000D01*
X619433Y662833D01*
X619600Y662583D01*
X619642Y662292D01*
X619600Y662042D01*
X619433Y661792D01*
X619183Y661583D01*
X618892Y661500D01*
X618558Y661583D01*
X618267Y661833D01*
X618100Y662208D01*
X618058Y662625D01*
X618142Y663167D01*
X618267Y663458D01*
X618475Y663750D01*
X618767Y663958D01*
X619058Y664000D01*
X619350Y663917D01*
X619558Y663708D01*
G01X643767Y579953D02*
X643517Y580078D01*
X643225Y580161D01*
X642892D01*
X642517Y580036D01*
X642225Y579828D01*
X642017Y579578D01*
X641850Y579161D01*
X641808Y578786D01*
X641892Y578411D01*
X642017Y578161D01*
X642267Y577911D01*
X642558Y577744D01*
X642850Y577661D01*
X643142D01*
X643433Y577744D01*
X643683Y577869D01*
X643892Y578036D01*
G01X645158Y579744D02*
X645408Y579994D01*
X645700Y580119D01*
X646033Y580161D01*
X646450Y580078D01*
X646742Y579869D01*
X646825Y579619D01*
X646783Y579369D01*
X646617Y579161D01*
X645783Y578744D01*
X645408Y578453D01*
X645158Y578036D01*
X645075Y577661D01*
X646825D01*
G01X649550D02*
Y580161D01*
X648008Y578369D01*
X650092D01*
G01X651233Y578036D02*
X651483Y577828D01*
X651775Y577703D01*
X652150Y577661D01*
X652525Y577744D01*
X652817Y577911D01*
X653025Y578203D01*
X653067Y578536D01*
X652983Y578869D01*
X652775Y579078D01*
X652483Y579244D01*
X652192Y579286D01*
X651900Y579244D01*
X651525Y579078D01*
X651650Y580161D01*
X652775D01*
G01X642017Y581661D02*
Y584161D01*
X643058D01*
X643392Y584036D01*
X643600Y583869D01*
X643683Y583536D01*
X643600Y583203D01*
X643350Y582994D01*
X643058Y582869D01*
X642017D01*
G01X643058D02*
X643683Y581661D01*
G01X646450D02*
Y584161D01*
X644908Y582369D01*
X646992D01*
G01X648133Y582161D02*
X648383Y581869D01*
X648717Y581703D01*
X649092Y581661D01*
X649425Y581703D01*
X649758Y581911D01*
X649967Y582161D01*
X650008Y582411D01*
X649925Y582703D01*
X649633Y582911D01*
X649342Y582994D01*
X648967D01*
G01X649342D02*
X649592Y583119D01*
X649800Y583328D01*
X649883Y583578D01*
X649800Y583828D01*
X649592Y584036D01*
X649217Y584161D01*
X648842Y584119D01*
X648467Y583953D01*
G01X652150Y581661D02*
X652442Y581703D01*
X652775Y581828D01*
X652983Y582036D01*
X653067Y582328D01*
X652983Y582619D01*
X652733Y582869D01*
X652358Y582994D01*
X651942D01*
X651692Y583078D01*
X651483Y583286D01*
X651400Y583578D01*
X651525Y583869D01*
X651817Y584078D01*
X652150Y584161D01*
X652483Y584078D01*
X652775Y583869D01*
X652900Y583578D01*
X652817Y583286D01*
X652608Y583078D01*
X652358Y582994D01*
X651942D01*
X651567Y582869D01*
X651317Y582619D01*
X651233Y582328D01*
X651317Y582036D01*
X651525Y581828D01*
X651858Y581703D01*
X652150Y581661D01*
G01X639700Y581000D02*
Y585000D01*
X632300D01*
G01X586708Y632267D02*
X586583Y632017D01*
X586500Y631725D01*
Y631392D01*
X586625Y631017D01*
X586833Y630725D01*
X587083Y630517D01*
X587500Y630350D01*
X587875Y630308D01*
X588250Y630392D01*
X588500Y630517D01*
X588750Y630767D01*
X588917Y631058D01*
X589000Y631350D01*
Y631642D01*
X588917Y631933D01*
X588792Y632183D01*
X588625Y632392D01*
G01X586917Y633658D02*
X586667Y633908D01*
X586542Y634200D01*
X586500Y634533D01*
X586583Y634950D01*
X586792Y635242D01*
X587042Y635325D01*
X587292Y635283D01*
X587500Y635117D01*
X587917Y634283D01*
X588208Y633908D01*
X588625Y633658D01*
X589000Y633575D01*
Y635325D01*
G01Y638050D02*
X586500D01*
X588292Y636508D01*
Y638592D01*
G01X588500Y639733D02*
X588792Y639983D01*
X588958Y640317D01*
X589000Y640692D01*
X588958Y641025D01*
X588750Y641358D01*
X588500Y641567D01*
X588250Y641608D01*
X587958Y641525D01*
X587750Y641233D01*
X587667Y640942D01*
Y640567D01*
G01Y640942D02*
X587542Y641192D01*
X587333Y641400D01*
X587083Y641483D01*
X586833Y641400D01*
X586625Y641192D01*
X586500Y640817D01*
X586542Y640442D01*
X586708Y640067D01*
G01X627800Y615500D02*
Y613000D01*
G01X626842Y615500D02*
X628758D01*
G01X630067Y613000D02*
Y615500D01*
X631067D01*
X631400Y615375D01*
X631650Y615083D01*
X631733Y614750D01*
X631650Y614417D01*
X631442Y614167D01*
X631067Y614042D01*
X630067D01*
G01X634000Y613000D02*
Y615500D01*
X633500Y615000D01*
G01Y613000D02*
X634500D01*
G01X637100Y615500D02*
X636767Y615417D01*
X636517Y615208D01*
X636350Y614958D01*
X636225Y614625D01*
X636183Y614250D01*
X636225Y613875D01*
X636350Y613542D01*
X636517Y613292D01*
X636767Y613083D01*
X637100Y613000D01*
X637433Y613083D01*
X637683Y613292D01*
X637850Y613542D01*
X637975Y613875D01*
X638017Y614250D01*
X637975Y614625D01*
X637850Y614958D01*
X637683Y615208D01*
X637433Y615417D01*
X637100Y615500D01*
G01X640200Y613000D02*
Y615500D01*
X639700Y615000D01*
G01Y613000D02*
X640700D01*
G01X659400Y573000D02*
X659067Y573042D01*
X658775Y573208D01*
X658525Y573458D01*
X658358Y573750D01*
X658275Y574083D01*
Y574417D01*
X658358Y574750D01*
X658525Y575042D01*
X658775Y575292D01*
X659067Y575458D01*
X659400Y575500D01*
X659733Y575458D01*
X660025Y575292D01*
X660275Y575042D01*
X660442Y574750D01*
X660525Y574417D01*
Y574083D01*
X660442Y573750D01*
X660275Y573458D01*
X660025Y573208D01*
X659733Y573042D01*
X659400Y573000D01*
G01X659733Y573667D02*
X660233Y573000D01*
G01X662417D02*
X662500Y573542D01*
X662625Y574000D01*
X662792Y574417D01*
X663000Y574875D01*
X663333Y575500D01*
X661667D01*
G01X665600Y573000D02*
X665892Y573042D01*
X666225Y573167D01*
X666433Y573375D01*
X666517Y573667D01*
X666433Y573958D01*
X666183Y574208D01*
X665808Y574333D01*
X665392D01*
X665142Y574417D01*
X664933Y574625D01*
X664850Y574917D01*
X664975Y575208D01*
X665267Y575417D01*
X665600Y575500D01*
X665933Y575417D01*
X666225Y575208D01*
X666350Y574917D01*
X666267Y574625D01*
X666058Y574417D01*
X665808Y574333D01*
X665392D01*
X665017Y574208D01*
X664767Y573958D01*
X664683Y573667D01*
X664767Y573375D01*
X664975Y573167D01*
X665308Y573042D01*
X665600Y573000D01*
G01X668800Y576000D02*
X670900Y574200D01*
X668800Y572000D01*
G01X627517Y598000D02*
Y600500D01*
X628558D01*
X628892Y600375D01*
X629100Y600208D01*
X629183Y599875D01*
X629100Y599542D01*
X628850Y599333D01*
X628558Y599208D01*
X627517D01*
G01X628558D02*
X629183Y598000D01*
G01X631950D02*
Y600500D01*
X630408Y598708D01*
X632492D01*
G01X635050Y598000D02*
Y600500D01*
X633508Y598708D01*
X635592D01*
G01X636858Y600083D02*
X637108Y600333D01*
X637400Y600458D01*
X637733Y600500D01*
X638150Y600417D01*
X638442Y600208D01*
X638525Y599958D01*
X638483Y599708D01*
X638317Y599500D01*
X637483Y599083D01*
X637108Y598792D01*
X636858Y598375D01*
X636775Y598000D01*
X638525D01*
G01X584800Y574500D02*
X579300D01*
G01X584800Y582500D02*
Y574500D01*
G01X579300Y582500D02*
X584800D01*
G01X591500Y594017D02*
X589000D01*
Y595058D01*
X589125Y595392D01*
X589292Y595600D01*
X589625Y595683D01*
X589958Y595600D01*
X590167Y595350D01*
X590292Y595058D01*
Y594017D01*
G01Y595058D02*
X591500Y595683D01*
G01Y598450D02*
X589000D01*
X590792Y596908D01*
Y598992D01*
G01X591000Y600133D02*
X591292Y600383D01*
X591458Y600717D01*
X591500Y601092D01*
X591458Y601425D01*
X591250Y601758D01*
X591000Y601967D01*
X590750Y602008D01*
X590458Y601925D01*
X590250Y601633D01*
X590167Y601342D01*
Y600967D01*
G01Y601342D02*
X590042Y601592D01*
X589833Y601800D01*
X589583Y601883D01*
X589333Y601800D01*
X589125Y601592D01*
X589000Y601217D01*
X589042Y600842D01*
X589208Y600467D01*
G01X591500Y604067D02*
X590958Y604150D01*
X590500Y604275D01*
X590083Y604442D01*
X589625Y604650D01*
X589000Y604983D01*
Y603317D01*
G01X586500Y592300D02*
X594500D01*
Y574700D01*
X586500D01*
Y592300D01*
G01X583208Y619267D02*
X583083Y619017D01*
X583000Y618725D01*
Y618392D01*
X583125Y618017D01*
X583333Y617725D01*
X583583Y617517D01*
X584000Y617350D01*
X584375Y617308D01*
X584750Y617392D01*
X585000Y617517D01*
X585250Y617767D01*
X585417Y618058D01*
X585500Y618350D01*
Y618642D01*
X585417Y618933D01*
X585292Y619183D01*
X585125Y619392D01*
G01X583417Y620658D02*
X583167Y620908D01*
X583042Y621200D01*
X583000Y621533D01*
X583083Y621950D01*
X583292Y622242D01*
X583542Y622325D01*
X583792Y622283D01*
X584000Y622117D01*
X584417Y621283D01*
X584708Y620908D01*
X585125Y620658D01*
X585500Y620575D01*
Y622325D01*
G01Y625050D02*
X583000D01*
X584792Y623508D01*
Y625592D01*
G01X583417Y626858D02*
X583167Y627108D01*
X583042Y627400D01*
X583000Y627733D01*
X583083Y628150D01*
X583292Y628442D01*
X583542Y628525D01*
X583792Y628483D01*
X584000Y628317D01*
X584417Y627483D01*
X584708Y627108D01*
X585125Y626858D01*
X585500Y626775D01*
Y628525D01*
G01X673267Y600792D02*
X673017Y600917D01*
X672725Y601000D01*
X672392D01*
X672017Y600875D01*
X671725Y600667D01*
X671517Y600417D01*
X671350Y600000D01*
X671308Y599625D01*
X671392Y599250D01*
X671517Y599000D01*
X671767Y598750D01*
X672058Y598583D01*
X672350Y598500D01*
X672642D01*
X672933Y598583D01*
X673183Y598708D01*
X673392Y598875D01*
G01X674658Y600583D02*
X674908Y600833D01*
X675200Y600958D01*
X675533Y601000D01*
X675950Y600917D01*
X676242Y600708D01*
X676325Y600458D01*
X676283Y600208D01*
X676117Y600000D01*
X675283Y599583D01*
X674908Y599292D01*
X674658Y598875D01*
X674575Y598500D01*
X676325D01*
G01X677633Y598875D02*
X677883Y598667D01*
X678175Y598542D01*
X678550Y598500D01*
X678925Y598583D01*
X679217Y598750D01*
X679425Y599042D01*
X679467Y599375D01*
X679383Y599708D01*
X679175Y599917D01*
X678883Y600083D01*
X678592Y600125D01*
X678300Y600083D01*
X677925Y599917D01*
X678050Y601000D01*
X679175D01*
G01X682150Y598500D02*
Y601000D01*
X680608Y599208D01*
X682692D01*
G01X642017Y834000D02*
Y836500D01*
X643058D01*
X643392Y836375D01*
X643600Y836208D01*
X643683Y835875D01*
X643600Y835542D01*
X643350Y835333D01*
X643058Y835208D01*
X642017D01*
G01X643058D02*
X643683Y834000D01*
G01X645158Y836083D02*
X645408Y836333D01*
X645700Y836458D01*
X646033Y836500D01*
X646450Y836417D01*
X646742Y836208D01*
X646825Y835958D01*
X646783Y835708D01*
X646617Y835500D01*
X645783Y835083D01*
X645408Y834792D01*
X645158Y834375D01*
X645075Y834000D01*
X646825D01*
G01X648258Y836083D02*
X648508Y836333D01*
X648800Y836458D01*
X649133Y836500D01*
X649550Y836417D01*
X649842Y836208D01*
X649925Y835958D01*
X649883Y835708D01*
X649717Y835500D01*
X648883Y835083D01*
X648508Y834792D01*
X648258Y834375D01*
X648175Y834000D01*
X649925D01*
G01X651442Y834292D02*
X651733Y834083D01*
X652067Y834000D01*
X652400Y834083D01*
X652692Y834333D01*
X652900Y834708D01*
X652983Y835083D01*
Y835542D01*
X652900Y835917D01*
X652692Y836250D01*
X652442Y836417D01*
X652150Y836500D01*
X651817Y836417D01*
X651567Y836250D01*
X651400Y836000D01*
X651317Y835667D01*
X651400Y835375D01*
X651608Y835083D01*
X651858Y834917D01*
X652150Y834875D01*
X652483Y834958D01*
X652733Y835167D01*
X652983Y835542D01*
G01X661592Y833882D02*
Y837882D01*
X654192D01*
G01X584598Y834405D02*
Y838405D01*
X577198D01*
G01X599505Y854859D02*
Y858859D01*
X592105D01*
G01X590930Y835700D02*
X590597Y835742D01*
X590305Y835908D01*
X590055Y836158D01*
X589888Y836450D01*
X589805Y836783D01*
Y837117D01*
X589888Y837450D01*
X590055Y837742D01*
X590305Y837992D01*
X590597Y838158D01*
X590930Y838200D01*
X591263Y838158D01*
X591555Y837992D01*
X591805Y837742D01*
X591972Y837450D01*
X592055Y837117D01*
Y836783D01*
X591972Y836450D01*
X591805Y836158D01*
X591555Y835908D01*
X591263Y835742D01*
X590930Y835700D01*
G01X591263Y836367D02*
X591763Y835700D01*
G01X593238Y837783D02*
X593488Y838033D01*
X593780Y838158D01*
X594113Y838200D01*
X594530Y838117D01*
X594822Y837908D01*
X594905Y837658D01*
X594863Y837408D01*
X594697Y837200D01*
X593863Y836783D01*
X593488Y836492D01*
X593238Y836075D01*
X593155Y835700D01*
X594905D01*
G01X596338Y837783D02*
X596588Y838033D01*
X596880Y838158D01*
X597213Y838200D01*
X597630Y838117D01*
X597922Y837908D01*
X598005Y837658D01*
X597963Y837408D01*
X597797Y837200D01*
X596963Y836783D01*
X596588Y836492D01*
X596338Y836075D01*
X596255Y835700D01*
X598005D01*
G01X599313Y836200D02*
X599563Y835908D01*
X599897Y835742D01*
X600272Y835700D01*
X600605Y835742D01*
X600938Y835950D01*
X601147Y836200D01*
X601188Y836450D01*
X601105Y836742D01*
X600813Y836950D01*
X600522Y837033D01*
X600147D01*
G01X600522D02*
X600772Y837158D01*
X600980Y837367D01*
X601063Y837617D01*
X600980Y837867D01*
X600772Y838075D01*
X600397Y838200D01*
X600022Y838158D01*
X599647Y837992D01*
G01X600180Y839500D02*
Y853500D01*
G01X587180Y839500D02*
X600180D01*
G01X587180Y853500D02*
Y839500D01*
G01X600180Y853500D02*
X587180D01*
G01X668350Y834500D02*
X668017Y834542D01*
X667725Y834708D01*
X667475Y834958D01*
X667308Y835250D01*
X667225Y835583D01*
Y835917D01*
X667308Y836250D01*
X667475Y836542D01*
X667725Y836792D01*
X668017Y836958D01*
X668350Y837000D01*
X668683Y836958D01*
X668975Y836792D01*
X669225Y836542D01*
X669392Y836250D01*
X669475Y835917D01*
Y835583D01*
X669392Y835250D01*
X669225Y834958D01*
X668975Y834708D01*
X668683Y834542D01*
X668350Y834500D01*
G01X668683Y835167D02*
X669183Y834500D01*
G01X670658Y836583D02*
X670908Y836833D01*
X671200Y836958D01*
X671533Y837000D01*
X671950Y836917D01*
X672242Y836708D01*
X672325Y836458D01*
X672283Y836208D01*
X672117Y836000D01*
X671283Y835583D01*
X670908Y835292D01*
X670658Y834875D01*
X670575Y834500D01*
X672325D01*
G01X673758Y836583D02*
X674008Y836833D01*
X674300Y836958D01*
X674633Y837000D01*
X675050Y836917D01*
X675342Y836708D01*
X675425Y836458D01*
X675383Y836208D01*
X675217Y836000D01*
X674383Y835583D01*
X674008Y835292D01*
X673758Y834875D01*
X673675Y834500D01*
X675425D01*
G01X678150D02*
Y837000D01*
X676608Y835208D01*
X678692D01*
G01X664000Y838300D02*
X677000D01*
G01X664000Y852300D02*
Y838300D01*
G01X677000Y852300D02*
X664000D01*
G01X649650Y855300D02*
X649317Y855342D01*
X649025Y855508D01*
X648775Y855758D01*
X648608Y856050D01*
X648525Y856383D01*
Y856717D01*
X648608Y857050D01*
X648775Y857342D01*
X649025Y857592D01*
X649317Y857758D01*
X649650Y857800D01*
X649983Y857758D01*
X650275Y857592D01*
X650525Y857342D01*
X650692Y857050D01*
X650775Y856717D01*
Y856383D01*
X650692Y856050D01*
X650525Y855758D01*
X650275Y855508D01*
X649983Y855342D01*
X649650Y855300D01*
G01X649983Y855967D02*
X650483Y855300D01*
G01X651958Y857383D02*
X652208Y857633D01*
X652500Y857758D01*
X652833Y857800D01*
X653250Y857717D01*
X653542Y857508D01*
X653625Y857258D01*
X653583Y857008D01*
X653417Y856800D01*
X652583Y856383D01*
X652208Y856092D01*
X651958Y855675D01*
X651875Y855300D01*
X653625D01*
G01X656350D02*
Y857800D01*
X654808Y856008D01*
X656892D01*
G01X658950Y855300D02*
X659242Y855342D01*
X659575Y855467D01*
X659783Y855675D01*
X659867Y855967D01*
X659783Y856258D01*
X659533Y856508D01*
X659158Y856633D01*
X658742D01*
X658492Y856717D01*
X658283Y856925D01*
X658200Y857217D01*
X658325Y857508D01*
X658617Y857717D01*
X658950Y857800D01*
X659283Y857717D01*
X659575Y857508D01*
X659700Y857217D01*
X659617Y856925D01*
X659408Y856717D01*
X659158Y856633D01*
X658742D01*
X658367Y856508D01*
X658117Y856258D01*
X658033Y855967D01*
X658117Y855675D01*
X658325Y855467D01*
X658658Y855342D01*
X658950Y855300D01*
G01X648892Y839107D02*
X662892D01*
G01X648892Y852107D02*
Y839107D01*
G01X662892Y852107D02*
X648892D01*
G01X662892Y839107D02*
Y852107D01*
G01X585898Y839630D02*
Y852630D01*
G01X590974Y1012831D02*
X596024D01*
Y1111531D01*
X620674D01*
Y927131D01*
X596024D01*
Y985831D01*
X590974D01*
Y1012831D01*
G01X663017Y858500D02*
Y861000D01*
X664058D01*
X664392Y860875D01*
X664600Y860708D01*
X664683Y860375D01*
X664600Y860042D01*
X664350Y859833D01*
X664058Y859708D01*
X663017D01*
G01X664058D02*
X664683Y858500D01*
G01X666158Y860583D02*
X666408Y860833D01*
X666700Y860958D01*
X667033Y861000D01*
X667450Y860917D01*
X667742Y860708D01*
X667825Y860458D01*
X667783Y860208D01*
X667617Y860000D01*
X666783Y859583D01*
X666408Y859292D01*
X666158Y858875D01*
X666075Y858500D01*
X667825D01*
G01X669258Y860583D02*
X669508Y860833D01*
X669800Y860958D01*
X670133Y861000D01*
X670550Y860917D01*
X670842Y860708D01*
X670925Y860458D01*
X670883Y860208D01*
X670717Y860000D01*
X669883Y859583D01*
X669508Y859292D01*
X669258Y858875D01*
X669175Y858500D01*
X670925D01*
G01X672358Y859542D02*
X672650Y859833D01*
X672900Y860000D01*
X673233Y860083D01*
X673525Y860000D01*
X673733Y859833D01*
X673900Y859583D01*
X673942Y859292D01*
X673900Y859042D01*
X673733Y858792D01*
X673483Y858583D01*
X673192Y858500D01*
X672858Y858583D01*
X672567Y858833D01*
X672400Y859208D01*
X672358Y859625D01*
X672442Y860167D01*
X672567Y860458D01*
X672775Y860750D01*
X673067Y860958D01*
X673358Y861000D01*
X673650Y860917D01*
X673858Y860708D01*
G01X676325Y853659D02*
Y857659D01*
X668925D01*
G01X586097Y859700D02*
Y862200D01*
X587138D01*
X587472Y862075D01*
X587680Y861908D01*
X587763Y861575D01*
X587680Y861242D01*
X587430Y861033D01*
X587138Y860908D01*
X586097D01*
G01X587138D02*
X587763Y859700D01*
G01X589238Y861783D02*
X589488Y862033D01*
X589780Y862158D01*
X590113Y862200D01*
X590530Y862117D01*
X590822Y861908D01*
X590905Y861658D01*
X590863Y861408D01*
X590697Y861200D01*
X589863Y860783D01*
X589488Y860492D01*
X589238Y860075D01*
X589155Y859700D01*
X590905D01*
G01X593130D02*
Y862200D01*
X592630Y861700D01*
G01Y859700D02*
X593630D01*
G01X596230Y862200D02*
X595897Y862117D01*
X595647Y861908D01*
X595480Y861658D01*
X595355Y861325D01*
X595313Y860950D01*
X595355Y860575D01*
X595480Y860242D01*
X595647Y859992D01*
X595897Y859783D01*
X596230Y859700D01*
X596563Y859783D01*
X596813Y859992D01*
X596980Y860242D01*
X597105Y860575D01*
X597147Y860950D01*
X597105Y861325D01*
X596980Y861658D01*
X596813Y861908D01*
X596563Y862117D01*
X596230Y862200D01*
G01X635817Y967292D02*
X635567Y967417D01*
X635275Y967500D01*
X634942D01*
X634567Y967375D01*
X634275Y967167D01*
X634067Y966917D01*
X633900Y966500D01*
X633858Y966125D01*
X633942Y965750D01*
X634067Y965500D01*
X634317Y965250D01*
X634608Y965083D01*
X634900Y965000D01*
X635192D01*
X635483Y965083D01*
X635733Y965208D01*
X635942Y965375D01*
G01X638000Y965000D02*
X638292Y965042D01*
X638625Y965167D01*
X638833Y965375D01*
X638917Y965667D01*
X638833Y965958D01*
X638583Y966208D01*
X638208Y966333D01*
X637792D01*
X637542Y966417D01*
X637333Y966625D01*
X637250Y966917D01*
X637375Y967208D01*
X637667Y967417D01*
X638000Y967500D01*
X638333Y967417D01*
X638625Y967208D01*
X638750Y966917D01*
X638667Y966625D01*
X638458Y966417D01*
X638208Y966333D01*
X637792D01*
X637417Y966208D01*
X637167Y965958D01*
X637083Y965667D01*
X637167Y965375D01*
X637375Y965167D01*
X637708Y965042D01*
X638000Y965000D01*
G01X641100D02*
Y967500D01*
X640600Y967000D01*
G01Y965000D02*
X641600D01*
G01X635976Y963184D02*
X635726Y963309D01*
X635434Y963392D01*
X635101D01*
X634726Y963267D01*
X634434Y963059D01*
X634226Y962809D01*
X634059Y962392D01*
X634017Y962017D01*
X634101Y961642D01*
X634226Y961392D01*
X634476Y961142D01*
X634767Y960975D01*
X635059Y960892D01*
X635351D01*
X635642Y960975D01*
X635892Y961100D01*
X636101Y961267D01*
G01X638159Y960892D02*
X638451Y960934D01*
X638784Y961059D01*
X638992Y961267D01*
X639076Y961559D01*
X638992Y961850D01*
X638742Y962100D01*
X638367Y962225D01*
X637951D01*
X637701Y962309D01*
X637492Y962517D01*
X637409Y962809D01*
X637534Y963100D01*
X637826Y963309D01*
X638159Y963392D01*
X638492Y963309D01*
X638784Y963100D01*
X638909Y962809D01*
X638826Y962517D01*
X638617Y962309D01*
X638367Y962225D01*
X637951D01*
X637576Y962100D01*
X637326Y961850D01*
X637242Y961559D01*
X637326Y961267D01*
X637534Y961059D01*
X637867Y960934D01*
X638159Y960892D01*
G01X641259Y963392D02*
X640926Y963309D01*
X640676Y963100D01*
X640509Y962850D01*
X640384Y962517D01*
X640342Y962142D01*
X640384Y961767D01*
X640509Y961434D01*
X640676Y961184D01*
X640926Y960975D01*
X641259Y960892D01*
X641592Y960975D01*
X641842Y961184D01*
X642009Y961434D01*
X642134Y961767D01*
X642176Y962142D01*
X642134Y962517D01*
X642009Y962850D01*
X641842Y963100D01*
X641592Y963309D01*
X641259Y963392D01*
G01X643317Y1032792D02*
X643067Y1032917D01*
X642775Y1033000D01*
X642442D01*
X642067Y1032875D01*
X641775Y1032667D01*
X641567Y1032417D01*
X641400Y1032000D01*
X641358Y1031625D01*
X641442Y1031250D01*
X641567Y1031000D01*
X641817Y1030750D01*
X642108Y1030583D01*
X642400Y1030500D01*
X642692D01*
X642983Y1030583D01*
X643233Y1030708D01*
X643442Y1030875D01*
G01X645500Y1030500D02*
X645792Y1030542D01*
X646125Y1030667D01*
X646333Y1030875D01*
X646417Y1031167D01*
X646333Y1031458D01*
X646083Y1031708D01*
X645708Y1031833D01*
X645292D01*
X645042Y1031917D01*
X644833Y1032125D01*
X644750Y1032417D01*
X644875Y1032708D01*
X645167Y1032917D01*
X645500Y1033000D01*
X645833Y1032917D01*
X646125Y1032708D01*
X646250Y1032417D01*
X646167Y1032125D01*
X645958Y1031917D01*
X645708Y1031833D01*
X645292D01*
X644917Y1031708D01*
X644667Y1031458D01*
X644583Y1031167D01*
X644667Y1030875D01*
X644875Y1030667D01*
X645208Y1030542D01*
X645500Y1030500D01*
G01X647892Y1030792D02*
X648183Y1030583D01*
X648517Y1030500D01*
X648850Y1030583D01*
X649142Y1030833D01*
X649350Y1031208D01*
X649433Y1031583D01*
Y1032042D01*
X649350Y1032417D01*
X649142Y1032750D01*
X648892Y1032917D01*
X648600Y1033000D01*
X648267Y1032917D01*
X648017Y1032750D01*
X647850Y1032500D01*
X647767Y1032167D01*
X647850Y1031875D01*
X648058Y1031583D01*
X648308Y1031417D01*
X648600Y1031375D01*
X648933Y1031458D01*
X649183Y1031667D01*
X649433Y1032042D01*
G01X665267Y1004453D02*
X665017Y1004578D01*
X664725Y1004661D01*
X664392D01*
X664017Y1004536D01*
X663725Y1004328D01*
X663517Y1004078D01*
X663350Y1003661D01*
X663308Y1003286D01*
X663392Y1002911D01*
X663517Y1002661D01*
X663767Y1002411D01*
X664058Y1002244D01*
X664350Y1002161D01*
X664642D01*
X664933Y1002244D01*
X665183Y1002369D01*
X665392Y1002536D01*
G01X667450Y1002161D02*
Y1004661D01*
X666950Y1004161D01*
G01Y1002161D02*
X667950D01*
G01X670550Y1004661D02*
X670217Y1004578D01*
X669967Y1004369D01*
X669800Y1004119D01*
X669675Y1003786D01*
X669633Y1003411D01*
X669675Y1003036D01*
X669800Y1002703D01*
X669967Y1002453D01*
X670217Y1002244D01*
X670550Y1002161D01*
X670883Y1002244D01*
X671133Y1002453D01*
X671300Y1002703D01*
X671425Y1003036D01*
X671467Y1003411D01*
X671425Y1003786D01*
X671300Y1004119D01*
X671133Y1004369D01*
X670883Y1004578D01*
X670550Y1004661D01*
G01X674150Y1002161D02*
Y1004661D01*
X672608Y1002869D01*
X674692D01*
G01X670767Y995953D02*
X670517Y996078D01*
X670225Y996161D01*
X669892D01*
X669517Y996036D01*
X669225Y995828D01*
X669017Y995578D01*
X668850Y995161D01*
X668808Y994786D01*
X668892Y994411D01*
X669017Y994161D01*
X669267Y993911D01*
X669558Y993744D01*
X669850Y993661D01*
X670142D01*
X670433Y993744D01*
X670683Y993869D01*
X670892Y994036D01*
G01X672950Y993661D02*
Y996161D01*
X672450Y995661D01*
G01Y993661D02*
X673450D01*
G01X676050Y996161D02*
X675717Y996078D01*
X675467Y995869D01*
X675300Y995619D01*
X675175Y995286D01*
X675133Y994911D01*
X675175Y994536D01*
X675300Y994203D01*
X675467Y993953D01*
X675717Y993744D01*
X676050Y993661D01*
X676383Y993744D01*
X676633Y993953D01*
X676800Y994203D01*
X676925Y994536D01*
X676967Y994911D01*
X676925Y995286D01*
X676800Y995619D01*
X676633Y995869D01*
X676383Y996078D01*
X676050Y996161D01*
G01X678233Y994161D02*
X678483Y993869D01*
X678817Y993703D01*
X679192Y993661D01*
X679525Y993703D01*
X679858Y993911D01*
X680067Y994161D01*
X680108Y994411D01*
X680025Y994703D01*
X679733Y994911D01*
X679442Y994994D01*
X679067D01*
G01X679442D02*
X679692Y995119D01*
X679900Y995328D01*
X679983Y995578D01*
X679900Y995828D01*
X679692Y996036D01*
X679317Y996161D01*
X678942Y996119D01*
X678567Y995953D01*
G01X581517Y954500D02*
Y957000D01*
X582558D01*
X582892Y956875D01*
X583100Y956708D01*
X583183Y956375D01*
X583100Y956042D01*
X582850Y955833D01*
X582558Y955708D01*
X581517D01*
G01X582558D02*
X583183Y954500D01*
G01X584658Y956583D02*
X584908Y956833D01*
X585200Y956958D01*
X585533Y957000D01*
X585950Y956917D01*
X586242Y956708D01*
X586325Y956458D01*
X586283Y956208D01*
X586117Y956000D01*
X585283Y955583D01*
X584908Y955292D01*
X584658Y954875D01*
X584575Y954500D01*
X586325D01*
G01X587633Y955000D02*
X587883Y954708D01*
X588217Y954542D01*
X588592Y954500D01*
X588925Y954542D01*
X589258Y954750D01*
X589467Y955000D01*
X589508Y955250D01*
X589425Y955542D01*
X589133Y955750D01*
X588842Y955833D01*
X588467D01*
G01X588842D02*
X589092Y955958D01*
X589300Y956167D01*
X589383Y956417D01*
X589300Y956667D01*
X589092Y956875D01*
X588717Y957000D01*
X588342Y956958D01*
X587967Y956792D01*
G01X591650Y957000D02*
X591317Y956917D01*
X591067Y956708D01*
X590900Y956458D01*
X590775Y956125D01*
X590733Y955750D01*
X590775Y955375D01*
X590900Y955042D01*
X591067Y954792D01*
X591317Y954583D01*
X591650Y954500D01*
X591983Y954583D01*
X592233Y954792D01*
X592400Y955042D01*
X592525Y955375D01*
X592567Y955750D01*
X592525Y956125D01*
X592400Y956458D01*
X592233Y956708D01*
X591983Y956917D01*
X591650Y957000D01*
G01X588500Y967500D02*
Y971500D01*
X581100D01*
G01X581517Y958500D02*
Y961000D01*
X582558D01*
X582892Y960875D01*
X583100Y960708D01*
X583183Y960375D01*
X583100Y960042D01*
X582850Y959833D01*
X582558Y959708D01*
X581517D01*
G01X582558D02*
X583183Y958500D01*
G01X584658Y960583D02*
X584908Y960833D01*
X585200Y960958D01*
X585533Y961000D01*
X585950Y960917D01*
X586242Y960708D01*
X586325Y960458D01*
X586283Y960208D01*
X586117Y960000D01*
X585283Y959583D01*
X584908Y959292D01*
X584658Y958875D01*
X584575Y958500D01*
X586325D01*
G01X587758Y960583D02*
X588008Y960833D01*
X588300Y960958D01*
X588633Y961000D01*
X589050Y960917D01*
X589342Y960708D01*
X589425Y960458D01*
X589383Y960208D01*
X589217Y960000D01*
X588383Y959583D01*
X588008Y959292D01*
X587758Y958875D01*
X587675Y958500D01*
X589425D01*
G01X591650D02*
X591942Y958542D01*
X592275Y958667D01*
X592483Y958875D01*
X592567Y959167D01*
X592483Y959458D01*
X592233Y959708D01*
X591858Y959833D01*
X591442D01*
X591192Y959917D01*
X590983Y960125D01*
X590900Y960417D01*
X591025Y960708D01*
X591317Y960917D01*
X591650Y961000D01*
X591983Y960917D01*
X592275Y960708D01*
X592400Y960417D01*
X592317Y960125D01*
X592108Y959917D01*
X591858Y959833D01*
X591442D01*
X591067Y959708D01*
X590817Y959458D01*
X590733Y959167D01*
X590817Y958875D01*
X591025Y958667D01*
X591358Y958542D01*
X591650Y958500D01*
G01X591200Y976100D02*
Y980100D01*
X583800D01*
G01X581517Y962500D02*
Y965000D01*
X582558D01*
X582892Y964875D01*
X583100Y964708D01*
X583183Y964375D01*
X583100Y964042D01*
X582850Y963833D01*
X582558Y963708D01*
X581517D01*
G01X582558D02*
X583183Y962500D01*
G01X584658Y964583D02*
X584908Y964833D01*
X585200Y964958D01*
X585533Y965000D01*
X585950Y964917D01*
X586242Y964708D01*
X586325Y964458D01*
X586283Y964208D01*
X586117Y964000D01*
X585283Y963583D01*
X584908Y963292D01*
X584658Y962875D01*
X584575Y962500D01*
X586325D01*
G01X587633Y963000D02*
X587883Y962708D01*
X588217Y962542D01*
X588592Y962500D01*
X588925Y962542D01*
X589258Y962750D01*
X589467Y963000D01*
X589508Y963250D01*
X589425Y963542D01*
X589133Y963750D01*
X588842Y963833D01*
X588467D01*
G01X588842D02*
X589092Y963958D01*
X589300Y964167D01*
X589383Y964417D01*
X589300Y964667D01*
X589092Y964875D01*
X588717Y965000D01*
X588342Y964958D01*
X587967Y964792D01*
G01X591650Y962500D02*
Y965000D01*
X591150Y964500D01*
G01Y962500D02*
X592150D01*
G01X583800Y984500D02*
Y980500D01*
X591200D01*
G01X641017Y1034500D02*
Y1037000D01*
X642058D01*
X642392Y1036875D01*
X642600Y1036708D01*
X642683Y1036375D01*
X642600Y1036042D01*
X642350Y1035833D01*
X642058Y1035708D01*
X641017D01*
G01X642058D02*
X642683Y1034500D01*
G01X644158Y1036583D02*
X644408Y1036833D01*
X644700Y1036958D01*
X645033Y1037000D01*
X645450Y1036917D01*
X645742Y1036708D01*
X645825Y1036458D01*
X645783Y1036208D01*
X645617Y1036000D01*
X644783Y1035583D01*
X644408Y1035292D01*
X644158Y1034875D01*
X644075Y1034500D01*
X645825D01*
G01X647258Y1036583D02*
X647508Y1036833D01*
X647800Y1036958D01*
X648133Y1037000D01*
X648550Y1036917D01*
X648842Y1036708D01*
X648925Y1036458D01*
X648883Y1036208D01*
X648717Y1036000D01*
X647883Y1035583D01*
X647508Y1035292D01*
X647258Y1034875D01*
X647175Y1034500D01*
X648925D01*
G01X650233Y1035000D02*
X650483Y1034708D01*
X650817Y1034542D01*
X651192Y1034500D01*
X651525Y1034542D01*
X651858Y1034750D01*
X652067Y1035000D01*
X652108Y1035250D01*
X652025Y1035542D01*
X651733Y1035750D01*
X651442Y1035833D01*
X651067D01*
G01X651442D02*
X651692Y1035958D01*
X651900Y1036167D01*
X651983Y1036417D01*
X651900Y1036667D01*
X651692Y1036875D01*
X651317Y1037000D01*
X650942Y1036958D01*
X650567Y1036792D01*
G01X639700Y1034000D02*
Y1038000D01*
X632300D01*
G01X672017Y963500D02*
Y966000D01*
X673058D01*
X673392Y965875D01*
X673600Y965708D01*
X673683Y965375D01*
X673600Y965042D01*
X673350Y964833D01*
X673058Y964708D01*
X672017D01*
G01X673058D02*
X673683Y963500D01*
G01X675158Y965583D02*
X675408Y965833D01*
X675700Y965958D01*
X676033Y966000D01*
X676450Y965917D01*
X676742Y965708D01*
X676825Y965458D01*
X676783Y965208D01*
X676617Y965000D01*
X675783Y964583D01*
X675408Y964292D01*
X675158Y963875D01*
X675075Y963500D01*
X676825D01*
G01X679550D02*
Y966000D01*
X678008Y964208D01*
X680092D01*
G01X682150Y963500D02*
X682442Y963542D01*
X682775Y963667D01*
X682983Y963875D01*
X683067Y964167D01*
X682983Y964458D01*
X682733Y964708D01*
X682358Y964833D01*
X681942D01*
X681692Y964917D01*
X681483Y965125D01*
X681400Y965417D01*
X681525Y965708D01*
X681817Y965917D01*
X682150Y966000D01*
X682483Y965917D01*
X682775Y965708D01*
X682900Y965417D01*
X682817Y965125D01*
X682608Y964917D01*
X682358Y964833D01*
X681942D01*
X681567Y964708D01*
X681317Y964458D01*
X681233Y964167D01*
X681317Y963875D01*
X681525Y963667D01*
X681858Y963542D01*
X682150Y963500D01*
G01X663517Y998161D02*
Y1000661D01*
X664558D01*
X664892Y1000536D01*
X665100Y1000369D01*
X665183Y1000036D01*
X665100Y999703D01*
X664850Y999494D01*
X664558Y999369D01*
X663517D01*
G01X664558D02*
X665183Y998161D01*
G01X666658Y1000244D02*
X666908Y1000494D01*
X667200Y1000619D01*
X667533Y1000661D01*
X667950Y1000578D01*
X668242Y1000369D01*
X668325Y1000119D01*
X668283Y999869D01*
X668117Y999661D01*
X667283Y999244D01*
X666908Y998953D01*
X666658Y998536D01*
X666575Y998161D01*
X668325D01*
G01X671050D02*
Y1000661D01*
X669508Y998869D01*
X671592D01*
G01X672942Y998453D02*
X673233Y998244D01*
X673567Y998161D01*
X673900Y998244D01*
X674192Y998494D01*
X674400Y998869D01*
X674483Y999244D01*
Y999703D01*
X674400Y1000078D01*
X674192Y1000411D01*
X673942Y1000578D01*
X673650Y1000661D01*
X673317Y1000578D01*
X673067Y1000411D01*
X672900Y1000161D01*
X672817Y999828D01*
X672900Y999536D01*
X673108Y999244D01*
X673358Y999078D01*
X673650Y999036D01*
X673983Y999119D01*
X674233Y999328D01*
X674483Y999703D01*
G01X673000Y974517D02*
X670500D01*
Y975558D01*
X670625Y975892D01*
X670792Y976100D01*
X671125Y976183D01*
X671458Y976100D01*
X671667Y975850D01*
X671792Y975558D01*
Y974517D01*
G01Y975558D02*
X673000Y976183D01*
G01X670917Y977658D02*
X670667Y977908D01*
X670542Y978200D01*
X670500Y978533D01*
X670583Y978950D01*
X670792Y979242D01*
X671042Y979325D01*
X671292Y979283D01*
X671500Y979117D01*
X671917Y978283D01*
X672208Y977908D01*
X672625Y977658D01*
X673000Y977575D01*
Y979325D01*
G01X672625Y980633D02*
X672833Y980883D01*
X672958Y981175D01*
X673000Y981550D01*
X672917Y981925D01*
X672750Y982217D01*
X672458Y982425D01*
X672125Y982467D01*
X671792Y982383D01*
X671583Y982175D01*
X671417Y981883D01*
X671375Y981592D01*
X671417Y981300D01*
X671583Y980925D01*
X670500Y981050D01*
Y982175D01*
G01Y984650D02*
X670583Y984317D01*
X670792Y984067D01*
X671042Y983900D01*
X671375Y983775D01*
X671750Y983733D01*
X672125Y983775D01*
X672458Y983900D01*
X672708Y984067D01*
X672917Y984317D01*
X673000Y984650D01*
X672917Y984983D01*
X672708Y985233D01*
X672458Y985400D01*
X672125Y985525D01*
X671750Y985567D01*
X671375Y985525D01*
X671042Y985400D01*
X670792Y985233D01*
X670583Y984983D01*
X670500Y984650D01*
G01X669017Y989661D02*
Y992161D01*
X670058D01*
X670392Y992036D01*
X670600Y991869D01*
X670683Y991536D01*
X670600Y991203D01*
X670350Y990994D01*
X670058Y990869D01*
X669017D01*
G01X670058D02*
X670683Y989661D01*
G01X672158Y991744D02*
X672408Y991994D01*
X672700Y992119D01*
X673033Y992161D01*
X673450Y992078D01*
X673742Y991869D01*
X673825Y991619D01*
X673783Y991369D01*
X673617Y991161D01*
X672783Y990744D01*
X672408Y990453D01*
X672158Y990036D01*
X672075Y989661D01*
X673825D01*
G01X676550D02*
Y992161D01*
X675008Y990369D01*
X677092D01*
G01X678233Y990161D02*
X678483Y989869D01*
X678817Y989703D01*
X679192Y989661D01*
X679525Y989703D01*
X679858Y989911D01*
X680067Y990161D01*
X680108Y990411D01*
X680025Y990703D01*
X679733Y990911D01*
X679442Y990994D01*
X679067D01*
G01X679442D02*
X679692Y991119D01*
X679900Y991328D01*
X679983Y991578D01*
X679900Y991828D01*
X679692Y992036D01*
X679317Y992161D01*
X678942Y992119D01*
X678567Y991953D01*
G01X589200Y1007000D02*
X587100Y1008800D01*
X589200Y1011000D01*
G01X667500Y1025900D02*
X667458Y1025567D01*
X667292Y1025275D01*
X667042Y1025025D01*
X666750Y1024858D01*
X666417Y1024775D01*
X666083D01*
X665750Y1024858D01*
X665458Y1025025D01*
X665208Y1025275D01*
X665042Y1025567D01*
X665000Y1025900D01*
X665042Y1026233D01*
X665208Y1026525D01*
X665458Y1026775D01*
X665750Y1026942D01*
X666083Y1027025D01*
X666417D01*
X666750Y1026942D01*
X667042Y1026775D01*
X667292Y1026525D01*
X667458Y1026233D01*
X667500Y1025900D01*
G01X666833Y1026233D02*
X667500Y1026733D01*
G01X665417Y1028208D02*
X665167Y1028458D01*
X665042Y1028750D01*
X665000Y1029083D01*
X665083Y1029500D01*
X665292Y1029792D01*
X665542Y1029875D01*
X665792Y1029833D01*
X666000Y1029667D01*
X666417Y1028833D01*
X666708Y1028458D01*
X667125Y1028208D01*
X667500Y1028125D01*
Y1029875D01*
G01X665000Y1032100D02*
X665083Y1031767D01*
X665292Y1031517D01*
X665542Y1031350D01*
X665875Y1031225D01*
X666250Y1031183D01*
X666625Y1031225D01*
X666958Y1031350D01*
X667208Y1031517D01*
X667417Y1031767D01*
X667500Y1032100D01*
X667417Y1032433D01*
X667208Y1032683D01*
X666958Y1032850D01*
X666625Y1032975D01*
X666250Y1033017D01*
X665875Y1032975D01*
X665542Y1032850D01*
X665292Y1032683D01*
X665083Y1032433D01*
X665000Y1032100D01*
G01X668800Y1029000D02*
X670900Y1027200D01*
X668800Y1025000D01*
G01X668700Y1021400D02*
X687900D01*
Y1032600D01*
X668700D01*
Y1021400D01*
X669100D01*
G01X584800Y1027500D02*
X579300D01*
G01X584800Y1035500D02*
Y1027500D01*
G01X579300Y1035500D02*
X584800D01*
G01X583200Y975800D02*
Y989200D01*
G01X591500Y1046517D02*
X589000D01*
Y1047558D01*
X589125Y1047892D01*
X589292Y1048100D01*
X589625Y1048183D01*
X589958Y1048100D01*
X590167Y1047850D01*
X590292Y1047558D01*
Y1046517D01*
G01Y1047558D02*
X591500Y1048183D01*
G01X589417Y1049658D02*
X589167Y1049908D01*
X589042Y1050200D01*
X589000Y1050533D01*
X589083Y1050950D01*
X589292Y1051242D01*
X589542Y1051325D01*
X589792Y1051283D01*
X590000Y1051117D01*
X590417Y1050283D01*
X590708Y1049908D01*
X591125Y1049658D01*
X591500Y1049575D01*
Y1051325D01*
G01X589417Y1052758D02*
X589167Y1053008D01*
X589042Y1053300D01*
X589000Y1053633D01*
X589083Y1054050D01*
X589292Y1054342D01*
X589542Y1054425D01*
X589792Y1054383D01*
X590000Y1054217D01*
X590417Y1053383D01*
X590708Y1053008D01*
X591125Y1052758D01*
X591500Y1052675D01*
Y1054425D01*
G01X589417Y1055858D02*
X589167Y1056108D01*
X589042Y1056400D01*
X589000Y1056733D01*
X589083Y1057150D01*
X589292Y1057442D01*
X589542Y1057525D01*
X589792Y1057483D01*
X590000Y1057317D01*
X590417Y1056483D01*
X590708Y1056108D01*
X591125Y1055858D01*
X591500Y1055775D01*
Y1057525D01*
G01X586500Y1045300D02*
X594500D01*
Y1027700D01*
X586500D01*
Y1045300D01*
G01X596825Y1114500D02*
Y1117000D01*
G01X598575D02*
Y1114500D01*
G01Y1115750D02*
X596825D01*
G01X599883Y1114500D02*
Y1117000D01*
X600717D01*
X601050Y1116875D01*
X601300Y1116708D01*
X601508Y1116458D01*
X601675Y1116167D01*
X601717Y1115750D01*
X601675Y1115333D01*
X601508Y1115042D01*
X601300Y1114792D01*
X601050Y1114625D01*
X600717Y1114500D01*
X599883D01*
G01X602983D02*
Y1117000D01*
X603817D01*
X604150Y1116875D01*
X604400Y1116708D01*
X604608Y1116458D01*
X604775Y1116167D01*
X604817Y1115750D01*
X604775Y1115333D01*
X604608Y1115042D01*
X604400Y1114792D01*
X604150Y1114625D01*
X603817Y1114500D01*
X602983D01*
G01X606125Y1114833D02*
X606458Y1114625D01*
X606833Y1114500D01*
X607167D01*
X607500Y1114625D01*
X607750Y1114833D01*
X607875Y1115125D01*
X607792Y1115417D01*
X607583Y1115667D01*
X607208Y1115833D01*
X606708Y1115917D01*
X606417Y1116083D01*
X606292Y1116375D01*
X606375Y1116667D01*
X606583Y1116875D01*
X606875Y1117000D01*
X607167D01*
X607458Y1116917D01*
X607708Y1116708D01*
G01X609058Y1114500D02*
X610100Y1117000D01*
X611142Y1114500D01*
G01X610767Y1115375D02*
X609433D01*
G01X612325Y1114833D02*
X612658Y1114625D01*
X613033Y1114500D01*
X613367D01*
X613700Y1114625D01*
X613950Y1114833D01*
X614075Y1115125D01*
X613992Y1115417D01*
X613783Y1115667D01*
X613408Y1115833D01*
X612908Y1115917D01*
X612617Y1116083D01*
X612492Y1116375D01*
X612575Y1116667D01*
X612783Y1116875D01*
X613075Y1117000D01*
X613367D01*
X613658Y1116917D01*
X613908Y1116708D01*
G01X616800Y1114500D02*
Y1117000D01*
X615258Y1115208D01*
X617342D01*
G01X586208Y1082817D02*
X586083Y1082567D01*
X586000Y1082275D01*
Y1081942D01*
X586125Y1081567D01*
X586333Y1081275D01*
X586583Y1081067D01*
X587000Y1080900D01*
X587375Y1080858D01*
X587750Y1080942D01*
X588000Y1081067D01*
X588250Y1081317D01*
X588417Y1081608D01*
X588500Y1081900D01*
Y1082192D01*
X588417Y1082483D01*
X588292Y1082733D01*
X588125Y1082942D01*
G01X588500Y1085000D02*
X588458Y1085292D01*
X588333Y1085625D01*
X588125Y1085833D01*
X587833Y1085917D01*
X587542Y1085833D01*
X587292Y1085583D01*
X587167Y1085208D01*
Y1084792D01*
X587083Y1084542D01*
X586875Y1084333D01*
X586583Y1084250D01*
X586292Y1084375D01*
X586083Y1084667D01*
X586000Y1085000D01*
X586083Y1085333D01*
X586292Y1085625D01*
X586583Y1085750D01*
X586875Y1085667D01*
X587083Y1085458D01*
X587167Y1085208D01*
Y1084792D01*
X587292Y1084417D01*
X587542Y1084167D01*
X587833Y1084083D01*
X588125Y1084167D01*
X588333Y1084375D01*
X588458Y1084708D01*
X588500Y1085000D01*
G01Y1088100D02*
X588458Y1088392D01*
X588333Y1088725D01*
X588125Y1088933D01*
X587833Y1089017D01*
X587542Y1088933D01*
X587292Y1088683D01*
X587167Y1088308D01*
Y1087892D01*
X587083Y1087642D01*
X586875Y1087433D01*
X586583Y1087350D01*
X586292Y1087475D01*
X586083Y1087767D01*
X586000Y1088100D01*
X586083Y1088433D01*
X586292Y1088725D01*
X586583Y1088850D01*
X586875Y1088767D01*
X587083Y1088558D01*
X587167Y1088308D01*
Y1087892D01*
X587292Y1087517D01*
X587542Y1087267D01*
X587833Y1087183D01*
X588125Y1087267D01*
X588333Y1087475D01*
X588458Y1087808D01*
X588500Y1088100D01*
G01X627850Y1068000D02*
Y1065500D01*
G01X626892Y1068000D02*
X628808D01*
G01X630117Y1065500D02*
Y1068000D01*
X631117D01*
X631450Y1067875D01*
X631700Y1067583D01*
X631783Y1067250D01*
X631700Y1066917D01*
X631492Y1066667D01*
X631117Y1066542D01*
X630117D01*
G01X634550Y1065500D02*
Y1068000D01*
X633008Y1066208D01*
X635092D01*
G01X637150Y1065500D02*
Y1068000D01*
X636650Y1067500D01*
G01Y1065500D02*
X637650D01*
G01X632517Y1051500D02*
Y1054000D01*
X633558D01*
X633892Y1053875D01*
X634100Y1053708D01*
X634183Y1053375D01*
X634100Y1053042D01*
X633850Y1052833D01*
X633558Y1052708D01*
X632517D01*
G01X633558D02*
X634183Y1051500D01*
G01X635658Y1053583D02*
X635908Y1053833D01*
X636200Y1053958D01*
X636533Y1054000D01*
X636950Y1053917D01*
X637242Y1053708D01*
X637325Y1053458D01*
X637283Y1053208D01*
X637117Y1053000D01*
X636283Y1052583D01*
X635908Y1052292D01*
X635658Y1051875D01*
X635575Y1051500D01*
X637325D01*
G01X638758Y1053583D02*
X639008Y1053833D01*
X639300Y1053958D01*
X639633Y1054000D01*
X640050Y1053917D01*
X640342Y1053708D01*
X640425Y1053458D01*
X640383Y1053208D01*
X640217Y1053000D01*
X639383Y1052583D01*
X639008Y1052292D01*
X638758Y1051875D01*
X638675Y1051500D01*
X640425D01*
G01X641733Y1051875D02*
X641983Y1051667D01*
X642275Y1051542D01*
X642650Y1051500D01*
X643025Y1051583D01*
X643317Y1051750D01*
X643525Y1052042D01*
X643567Y1052375D01*
X643483Y1052708D01*
X643275Y1052917D01*
X642983Y1053083D01*
X642692Y1053125D01*
X642400Y1053083D01*
X642025Y1052917D01*
X642150Y1054000D01*
X643275D01*
G01X584208Y1072317D02*
X584083Y1072067D01*
X584000Y1071775D01*
Y1071442D01*
X584125Y1071067D01*
X584333Y1070775D01*
X584583Y1070567D01*
X585000Y1070400D01*
X585375Y1070358D01*
X585750Y1070442D01*
X586000Y1070567D01*
X586250Y1070817D01*
X586417Y1071108D01*
X586500Y1071400D01*
Y1071692D01*
X586417Y1071983D01*
X586292Y1072233D01*
X586125Y1072442D01*
G01X586500Y1074500D02*
X586458Y1074792D01*
X586333Y1075125D01*
X586125Y1075333D01*
X585833Y1075417D01*
X585542Y1075333D01*
X585292Y1075083D01*
X585167Y1074708D01*
Y1074292D01*
X585083Y1074042D01*
X584875Y1073833D01*
X584583Y1073750D01*
X584292Y1073875D01*
X584083Y1074167D01*
X584000Y1074500D01*
X584083Y1074833D01*
X584292Y1075125D01*
X584583Y1075250D01*
X584875Y1075167D01*
X585083Y1074958D01*
X585167Y1074708D01*
Y1074292D01*
X585292Y1073917D01*
X585542Y1073667D01*
X585833Y1073583D01*
X586125Y1073667D01*
X586333Y1073875D01*
X586458Y1074208D01*
X586500Y1074500D01*
G01Y1077517D02*
X585958Y1077600D01*
X585500Y1077725D01*
X585083Y1077892D01*
X584625Y1078100D01*
X584000Y1078433D01*
Y1076767D01*
G01X673817Y1052792D02*
X673567Y1052917D01*
X673275Y1053000D01*
X672942D01*
X672567Y1052875D01*
X672275Y1052667D01*
X672067Y1052417D01*
X671900Y1052000D01*
X671858Y1051625D01*
X671942Y1051250D01*
X672067Y1051000D01*
X672317Y1050750D01*
X672608Y1050583D01*
X672900Y1050500D01*
X673192D01*
X673483Y1050583D01*
X673733Y1050708D01*
X673942Y1050875D01*
G01X675292Y1050792D02*
X675583Y1050583D01*
X675917Y1050500D01*
X676250Y1050583D01*
X676542Y1050833D01*
X676750Y1051208D01*
X676833Y1051583D01*
Y1052042D01*
X676750Y1052417D01*
X676542Y1052750D01*
X676292Y1052917D01*
X676000Y1053000D01*
X675667Y1052917D01*
X675417Y1052750D01*
X675250Y1052500D01*
X675167Y1052167D01*
X675250Y1051875D01*
X675458Y1051583D01*
X675708Y1051417D01*
X676000Y1051375D01*
X676333Y1051458D01*
X676583Y1051667D01*
X676833Y1052042D01*
G01X678392Y1050792D02*
X678683Y1050583D01*
X679017Y1050500D01*
X679350Y1050583D01*
X679642Y1050833D01*
X679850Y1051208D01*
X679933Y1051583D01*
Y1052042D01*
X679850Y1052417D01*
X679642Y1052750D01*
X679392Y1052917D01*
X679100Y1053000D01*
X678767Y1052917D01*
X678517Y1052750D01*
X678350Y1052500D01*
X678267Y1052167D01*
X678350Y1051875D01*
X678558Y1051583D01*
X678808Y1051417D01*
X679100Y1051375D01*
X679433Y1051458D01*
X679683Y1051667D01*
X679933Y1052042D01*
G01X636667Y1282400D02*
Y1284900D01*
X637708D01*
X638042Y1284775D01*
X638250Y1284608D01*
X638333Y1284275D01*
X638250Y1283942D01*
X638000Y1283733D01*
X637708Y1283608D01*
X636667D01*
G01X637708D02*
X638333Y1282400D01*
G01X640600D02*
Y1284900D01*
X640100Y1284400D01*
G01Y1282400D02*
X641100D01*
G01X643700Y1284900D02*
X643367Y1284817D01*
X643117Y1284608D01*
X642950Y1284358D01*
X642825Y1284025D01*
X642783Y1283650D01*
X642825Y1283275D01*
X642950Y1282942D01*
X643117Y1282692D01*
X643367Y1282483D01*
X643700Y1282400D01*
X644033Y1282483D01*
X644283Y1282692D01*
X644450Y1282942D01*
X644575Y1283275D01*
X644617Y1283650D01*
X644575Y1284025D01*
X644450Y1284358D01*
X644283Y1284608D01*
X644033Y1284817D01*
X643700Y1284900D01*
G01X646800Y1282400D02*
Y1284900D01*
X646300Y1284400D01*
G01Y1282400D02*
X647300D01*
G01X649108Y1284483D02*
X649358Y1284733D01*
X649650Y1284858D01*
X649983Y1284900D01*
X650400Y1284817D01*
X650692Y1284608D01*
X650775Y1284358D01*
X650733Y1284108D01*
X650567Y1283900D01*
X649733Y1283483D01*
X649358Y1283192D01*
X649108Y1282775D01*
X649025Y1282400D01*
X650775D01*
G01X665700Y1318800D02*
Y1287800D01*
X621700D01*
Y1318800D01*
X665700D01*
G01X596226Y1417130D02*
Y1419630D01*
X597267D01*
X597601Y1419505D01*
X597809Y1419338D01*
X597892Y1419005D01*
X597809Y1418672D01*
X597559Y1418463D01*
X597267Y1418338D01*
X596226D01*
G01X597267D02*
X597892Y1417130D01*
G01X600159D02*
Y1419630D01*
X599659Y1419130D01*
G01Y1417130D02*
X600659D01*
G01X603259Y1419630D02*
X602926Y1419547D01*
X602676Y1419338D01*
X602509Y1419088D01*
X602384Y1418755D01*
X602342Y1418380D01*
X602384Y1418005D01*
X602509Y1417672D01*
X602676Y1417422D01*
X602926Y1417213D01*
X603259Y1417130D01*
X603592Y1417213D01*
X603842Y1417422D01*
X604009Y1417672D01*
X604134Y1418005D01*
X604176Y1418380D01*
X604134Y1418755D01*
X604009Y1419088D01*
X603842Y1419338D01*
X603592Y1419547D01*
X603259Y1419630D01*
G01X606359Y1417130D02*
Y1419630D01*
X605859Y1419130D01*
G01Y1417130D02*
X606859D01*
G01X609459Y1419630D02*
X609126Y1419547D01*
X608876Y1419338D01*
X608709Y1419088D01*
X608584Y1418755D01*
X608542Y1418380D01*
X608584Y1418005D01*
X608709Y1417672D01*
X608876Y1417422D01*
X609126Y1417213D01*
X609459Y1417130D01*
X609792Y1417213D01*
X610042Y1417422D01*
X610209Y1417672D01*
X610334Y1418005D01*
X610376Y1418380D01*
X610334Y1418755D01*
X610209Y1419088D01*
X610042Y1419338D01*
X609792Y1419547D01*
X609459Y1419630D01*
G01X641495Y1427719D02*
Y1423719D01*
X648895D01*
G01X618772Y1416279D02*
X616272D01*
Y1417320D01*
X616397Y1417654D01*
X616564Y1417862D01*
X616897Y1417945D01*
X617230Y1417862D01*
X617439Y1417612D01*
X617564Y1417320D01*
Y1416279D01*
G01Y1417320D02*
X618772Y1417945D01*
G01Y1420212D02*
X616272D01*
X616772Y1419712D01*
G01X618772D02*
Y1420712D01*
G01X616272Y1423312D02*
X616355Y1422979D01*
X616564Y1422729D01*
X616814Y1422562D01*
X617147Y1422437D01*
X617522Y1422395D01*
X617897Y1422437D01*
X618230Y1422562D01*
X618480Y1422729D01*
X618689Y1422979D01*
X618772Y1423312D01*
X618689Y1423645D01*
X618480Y1423895D01*
X618230Y1424062D01*
X617897Y1424187D01*
X617522Y1424229D01*
X617147Y1424187D01*
X616814Y1424062D01*
X616564Y1423895D01*
X616355Y1423645D01*
X616272Y1423312D01*
G01X618772Y1426412D02*
X616272D01*
X616772Y1425912D01*
G01X618772D02*
Y1426912D01*
G01X618272Y1428595D02*
X618564Y1428845D01*
X618730Y1429179D01*
X618772Y1429554D01*
X618730Y1429887D01*
X618522Y1430220D01*
X618272Y1430429D01*
X618022Y1430470D01*
X617730Y1430387D01*
X617522Y1430095D01*
X617439Y1429804D01*
Y1429429D01*
G01Y1429804D02*
X617314Y1430054D01*
X617105Y1430262D01*
X616855Y1430345D01*
X616605Y1430262D01*
X616397Y1430054D01*
X616272Y1429679D01*
X616314Y1429304D01*
X616480Y1428929D01*
G01X653795Y1424219D02*
X657795D01*
Y1431619D01*
G01X635817Y1425753D02*
X633317D01*
Y1426794D01*
X633442Y1427128D01*
X633609Y1427336D01*
X633942Y1427419D01*
X634275Y1427336D01*
X634484Y1427086D01*
X634609Y1426794D01*
Y1425753D01*
G01Y1426794D02*
X635817Y1427419D01*
G01Y1429686D02*
X633317D01*
X633817Y1429186D01*
G01X635817D02*
Y1430186D01*
G01X633317Y1432786D02*
X633400Y1432453D01*
X633609Y1432203D01*
X633859Y1432036D01*
X634192Y1431911D01*
X634567Y1431869D01*
X634942Y1431911D01*
X635275Y1432036D01*
X635525Y1432203D01*
X635734Y1432453D01*
X635817Y1432786D01*
X635734Y1433119D01*
X635525Y1433369D01*
X635275Y1433536D01*
X634942Y1433661D01*
X634567Y1433703D01*
X634192Y1433661D01*
X633859Y1433536D01*
X633609Y1433369D01*
X633400Y1433119D01*
X633317Y1432786D01*
G01X635817Y1435886D02*
X633317D01*
X633817Y1435386D01*
G01X635817D02*
Y1436386D01*
G01Y1439486D02*
X633317D01*
X635109Y1437944D01*
Y1440028D01*
G01X612480Y1418029D02*
X612355Y1417779D01*
X612272Y1417487D01*
Y1417154D01*
X612397Y1416779D01*
X612605Y1416487D01*
X612855Y1416279D01*
X613272Y1416112D01*
X613647Y1416070D01*
X614022Y1416154D01*
X614272Y1416279D01*
X614522Y1416529D01*
X614689Y1416820D01*
X614772Y1417112D01*
Y1417404D01*
X614689Y1417695D01*
X614564Y1417945D01*
X614397Y1418154D01*
G01Y1419295D02*
X614605Y1419545D01*
X614730Y1419837D01*
X614772Y1420212D01*
X614689Y1420587D01*
X614522Y1420879D01*
X614230Y1421087D01*
X613897Y1421129D01*
X613564Y1421045D01*
X613355Y1420837D01*
X613189Y1420545D01*
X613147Y1420254D01*
X613189Y1419962D01*
X613355Y1419587D01*
X612272Y1419712D01*
Y1420837D01*
G01X614397Y1422395D02*
X614605Y1422645D01*
X614730Y1422937D01*
X614772Y1423312D01*
X614689Y1423687D01*
X614522Y1423979D01*
X614230Y1424187D01*
X613897Y1424229D01*
X613564Y1424145D01*
X613355Y1423937D01*
X613189Y1423645D01*
X613147Y1423354D01*
X613189Y1423062D01*
X613355Y1422687D01*
X612272Y1422812D01*
Y1423937D01*
G01Y1426412D02*
X612355Y1426079D01*
X612564Y1425829D01*
X612814Y1425662D01*
X613147Y1425537D01*
X613522Y1425495D01*
X613897Y1425537D01*
X614230Y1425662D01*
X614480Y1425829D01*
X614689Y1426079D01*
X614772Y1426412D01*
X614689Y1426745D01*
X614480Y1426995D01*
X614230Y1427162D01*
X613897Y1427287D01*
X613522Y1427329D01*
X613147Y1427287D01*
X612814Y1427162D01*
X612564Y1426995D01*
X612355Y1426745D01*
X612272Y1426412D01*
G01X628325Y1428303D02*
X628200Y1428053D01*
X628117Y1427761D01*
Y1427428D01*
X628242Y1427053D01*
X628450Y1426761D01*
X628700Y1426553D01*
X629117Y1426386D01*
X629492Y1426344D01*
X629867Y1426428D01*
X630117Y1426553D01*
X630367Y1426803D01*
X630534Y1427094D01*
X630617Y1427386D01*
Y1427678D01*
X630534Y1427969D01*
X630409Y1428219D01*
X630242Y1428428D01*
G01Y1429569D02*
X630450Y1429819D01*
X630575Y1430111D01*
X630617Y1430486D01*
X630534Y1430861D01*
X630367Y1431153D01*
X630075Y1431361D01*
X629742Y1431403D01*
X629409Y1431319D01*
X629200Y1431111D01*
X629034Y1430819D01*
X628992Y1430528D01*
X629034Y1430236D01*
X629200Y1429861D01*
X628117Y1429986D01*
Y1431111D01*
G01X630242Y1432669D02*
X630450Y1432919D01*
X630575Y1433211D01*
X630617Y1433586D01*
X630534Y1433961D01*
X630367Y1434253D01*
X630075Y1434461D01*
X629742Y1434503D01*
X629409Y1434419D01*
X629200Y1434211D01*
X629034Y1433919D01*
X628992Y1433628D01*
X629034Y1433336D01*
X629200Y1432961D01*
X628117Y1433086D01*
Y1434211D01*
G01X630617Y1436686D02*
X628117D01*
X628617Y1436186D01*
G01X630617D02*
Y1437186D01*
G01X674000Y1427700D02*
X670000D01*
Y1420300D01*
G01X636867Y1382300D02*
Y1384800D01*
X637908D01*
X638242Y1384675D01*
X638450Y1384508D01*
X638533Y1384175D01*
X638450Y1383842D01*
X638200Y1383633D01*
X637908Y1383508D01*
X636867D01*
G01X637908D02*
X638533Y1382300D01*
G01X640800D02*
Y1384800D01*
X640300Y1384300D01*
G01Y1382300D02*
X641300D01*
G01X643900Y1384800D02*
X643567Y1384717D01*
X643317Y1384508D01*
X643150Y1384258D01*
X643025Y1383925D01*
X642983Y1383550D01*
X643025Y1383175D01*
X643150Y1382842D01*
X643317Y1382592D01*
X643567Y1382383D01*
X643900Y1382300D01*
X644233Y1382383D01*
X644483Y1382592D01*
X644650Y1382842D01*
X644775Y1383175D01*
X644817Y1383550D01*
X644775Y1383925D01*
X644650Y1384258D01*
X644483Y1384508D01*
X644233Y1384717D01*
X643900Y1384800D01*
G01X647000D02*
X646667Y1384717D01*
X646417Y1384508D01*
X646250Y1384258D01*
X646125Y1383925D01*
X646083Y1383550D01*
X646125Y1383175D01*
X646250Y1382842D01*
X646417Y1382592D01*
X646667Y1382383D01*
X647000Y1382300D01*
X647333Y1382383D01*
X647583Y1382592D01*
X647750Y1382842D01*
X647875Y1383175D01*
X647917Y1383550D01*
X647875Y1383925D01*
X647750Y1384258D01*
X647583Y1384508D01*
X647333Y1384717D01*
X647000Y1384800D01*
G01X649392Y1382592D02*
X649683Y1382383D01*
X650017Y1382300D01*
X650350Y1382383D01*
X650642Y1382633D01*
X650850Y1383008D01*
X650933Y1383383D01*
Y1383842D01*
X650850Y1384217D01*
X650642Y1384550D01*
X650392Y1384717D01*
X650100Y1384800D01*
X649767Y1384717D01*
X649517Y1384550D01*
X649350Y1384300D01*
X649267Y1383967D01*
X649350Y1383675D01*
X649558Y1383383D01*
X649808Y1383217D01*
X650100Y1383175D01*
X650433Y1383258D01*
X650683Y1383467D01*
X650933Y1383842D01*
G01X621700Y1386900D02*
Y1417900D01*
X665700D01*
Y1386900D01*
X621700D01*
G01X670708Y1491767D02*
X670583Y1491517D01*
X670500Y1491225D01*
Y1490892D01*
X670625Y1490517D01*
X670833Y1490225D01*
X671083Y1490017D01*
X671500Y1489850D01*
X671875Y1489808D01*
X672250Y1489892D01*
X672500Y1490017D01*
X672750Y1490267D01*
X672917Y1490558D01*
X673000Y1490850D01*
Y1491142D01*
X672917Y1491433D01*
X672792Y1491683D01*
X672625Y1491892D01*
G01Y1493033D02*
X672833Y1493283D01*
X672958Y1493575D01*
X673000Y1493950D01*
X672917Y1494325D01*
X672750Y1494617D01*
X672458Y1494825D01*
X672125Y1494867D01*
X671792Y1494783D01*
X671583Y1494575D01*
X671417Y1494283D01*
X671375Y1493992D01*
X671417Y1493700D01*
X671583Y1493325D01*
X670500Y1493450D01*
Y1494575D01*
G01X672500Y1496133D02*
X672792Y1496383D01*
X672958Y1496717D01*
X673000Y1497092D01*
X672958Y1497425D01*
X672750Y1497758D01*
X672500Y1497967D01*
X672250Y1498008D01*
X671958Y1497925D01*
X671750Y1497633D01*
X671667Y1497342D01*
Y1496967D01*
G01Y1497342D02*
X671542Y1497592D01*
X671333Y1497800D01*
X671083Y1497883D01*
X670833Y1497800D01*
X670625Y1497592D01*
X670500Y1497217D01*
X670542Y1496842D01*
X670708Y1496467D01*
G01X672708Y1499442D02*
X672917Y1499733D01*
X673000Y1500067D01*
X672917Y1500400D01*
X672667Y1500692D01*
X672292Y1500900D01*
X671917Y1500983D01*
X671458D01*
X671083Y1500900D01*
X670750Y1500692D01*
X670583Y1500442D01*
X670500Y1500150D01*
X670583Y1499817D01*
X670750Y1499567D01*
X671000Y1499400D01*
X671333Y1499317D01*
X671625Y1499400D01*
X671917Y1499608D01*
X672083Y1499858D01*
X672125Y1500150D01*
X672042Y1500483D01*
X671833Y1500733D01*
X671458Y1500983D01*
G01X671578Y1461976D02*
X671453Y1461726D01*
X671370Y1461434D01*
Y1461101D01*
X671495Y1460726D01*
X671703Y1460434D01*
X671953Y1460226D01*
X672370Y1460059D01*
X672745Y1460017D01*
X673120Y1460101D01*
X673370Y1460226D01*
X673620Y1460476D01*
X673787Y1460767D01*
X673870Y1461059D01*
Y1461351D01*
X673787Y1461642D01*
X673662Y1461892D01*
X673495Y1462101D01*
G01Y1463242D02*
X673703Y1463492D01*
X673828Y1463784D01*
X673870Y1464159D01*
X673787Y1464534D01*
X673620Y1464826D01*
X673328Y1465034D01*
X672995Y1465076D01*
X672662Y1464992D01*
X672453Y1464784D01*
X672287Y1464492D01*
X672245Y1464201D01*
X672287Y1463909D01*
X672453Y1463534D01*
X671370Y1463659D01*
Y1464784D01*
G01X672828Y1466467D02*
X672537Y1466759D01*
X672370Y1467009D01*
X672287Y1467342D01*
X672370Y1467634D01*
X672537Y1467842D01*
X672787Y1468009D01*
X673078Y1468051D01*
X673328Y1468009D01*
X673578Y1467842D01*
X673787Y1467592D01*
X673870Y1467301D01*
X673787Y1466967D01*
X673537Y1466676D01*
X673162Y1466509D01*
X672745Y1466467D01*
X672203Y1466551D01*
X671912Y1466676D01*
X671620Y1466884D01*
X671412Y1467176D01*
X671370Y1467467D01*
X671453Y1467759D01*
X671662Y1467967D01*
G01X673578Y1469651D02*
X673787Y1469942D01*
X673870Y1470276D01*
X673787Y1470609D01*
X673537Y1470901D01*
X673162Y1471109D01*
X672787Y1471192D01*
X672328D01*
X671953Y1471109D01*
X671620Y1470901D01*
X671453Y1470651D01*
X671370Y1470359D01*
X671453Y1470026D01*
X671620Y1469776D01*
X671870Y1469609D01*
X672203Y1469526D01*
X672495Y1469609D01*
X672787Y1469817D01*
X672953Y1470067D01*
X672995Y1470359D01*
X672912Y1470692D01*
X672703Y1470942D01*
X672328Y1471192D01*
G01X673700Y1428000D02*
Y1432000D01*
X666300D01*
G01X608938Y1434006D02*
Y1436506D01*
X609979D01*
X610313Y1436381D01*
X610521Y1436214D01*
X610604Y1435881D01*
X610521Y1435548D01*
X610271Y1435339D01*
X609979Y1435214D01*
X608938D01*
G01X609979D02*
X610604Y1434006D01*
G01X612871D02*
Y1436506D01*
X612371Y1436006D01*
G01Y1434006D02*
X613371D01*
G01X615971Y1436506D02*
X615638Y1436423D01*
X615388Y1436214D01*
X615221Y1435964D01*
X615096Y1435631D01*
X615054Y1435256D01*
X615096Y1434881D01*
X615221Y1434548D01*
X615388Y1434298D01*
X615638Y1434089D01*
X615971Y1434006D01*
X616304Y1434089D01*
X616554Y1434298D01*
X616721Y1434548D01*
X616846Y1434881D01*
X616888Y1435256D01*
X616846Y1435631D01*
X616721Y1435964D01*
X616554Y1436214D01*
X616304Y1436423D01*
X615971Y1436506D01*
G01X619071Y1434006D02*
Y1436506D01*
X618571Y1436006D01*
G01Y1434006D02*
X619571D01*
G01X622171D02*
Y1436506D01*
X621671Y1436006D01*
G01Y1434006D02*
X622671D01*
G01X641595Y1443419D02*
Y1439419D01*
X648995D01*
G01X657795Y1442119D02*
X653795D01*
Y1434719D01*
G01X630000Y1446017D02*
X627500D01*
Y1447058D01*
X627625Y1447392D01*
X627792Y1447600D01*
X628125Y1447683D01*
X628458Y1447600D01*
X628667Y1447350D01*
X628792Y1447058D01*
Y1446017D01*
G01Y1447058D02*
X630000Y1447683D01*
G01X629708Y1449242D02*
X629917Y1449533D01*
X630000Y1449867D01*
X629917Y1450200D01*
X629667Y1450492D01*
X629292Y1450700D01*
X628917Y1450783D01*
X628458D01*
X628083Y1450700D01*
X627750Y1450492D01*
X627583Y1450242D01*
X627500Y1449950D01*
X627583Y1449617D01*
X627750Y1449367D01*
X628000Y1449200D01*
X628333Y1449117D01*
X628625Y1449200D01*
X628917Y1449408D01*
X629083Y1449658D01*
X629125Y1449950D01*
X629042Y1450283D01*
X628833Y1450533D01*
X628458Y1450783D01*
G01X629500Y1452133D02*
X629792Y1452383D01*
X629958Y1452717D01*
X630000Y1453092D01*
X629958Y1453425D01*
X629750Y1453758D01*
X629500Y1453967D01*
X629250Y1454008D01*
X628958Y1453925D01*
X628750Y1453633D01*
X628667Y1453342D01*
Y1452967D01*
G01Y1453342D02*
X628542Y1453592D01*
X628333Y1453800D01*
X628083Y1453883D01*
X627833Y1453800D01*
X627625Y1453592D01*
X627500Y1453217D01*
X627542Y1452842D01*
X627708Y1452467D01*
G01X629500Y1455233D02*
X629792Y1455483D01*
X629958Y1455817D01*
X630000Y1456192D01*
X629958Y1456525D01*
X629750Y1456858D01*
X629500Y1457067D01*
X629250Y1457108D01*
X628958Y1457025D01*
X628750Y1456733D01*
X628667Y1456442D01*
Y1456067D01*
G01Y1456442D02*
X628542Y1456692D01*
X628333Y1456900D01*
X628083Y1456983D01*
X627833Y1456900D01*
X627625Y1456692D01*
X627500Y1456317D01*
X627542Y1455942D01*
X627708Y1455567D01*
G01X626500Y1459300D02*
X630500D01*
Y1466700D01*
G01X639017Y1464500D02*
Y1467000D01*
X640058D01*
X640392Y1466875D01*
X640600Y1466708D01*
X640683Y1466375D01*
X640600Y1466042D01*
X640350Y1465833D01*
X640058Y1465708D01*
X639017D01*
G01X640058D02*
X640683Y1464500D01*
G01X642242Y1464792D02*
X642533Y1464583D01*
X642867Y1464500D01*
X643200Y1464583D01*
X643492Y1464833D01*
X643700Y1465208D01*
X643783Y1465583D01*
Y1466042D01*
X643700Y1466417D01*
X643492Y1466750D01*
X643242Y1466917D01*
X642950Y1467000D01*
X642617Y1466917D01*
X642367Y1466750D01*
X642200Y1466500D01*
X642117Y1466167D01*
X642200Y1465875D01*
X642408Y1465583D01*
X642658Y1465417D01*
X642950Y1465375D01*
X643283Y1465458D01*
X643533Y1465667D01*
X643783Y1466042D01*
G01X645133Y1465000D02*
X645383Y1464708D01*
X645717Y1464542D01*
X646092Y1464500D01*
X646425Y1464542D01*
X646758Y1464750D01*
X646967Y1465000D01*
X647008Y1465250D01*
X646925Y1465542D01*
X646633Y1465750D01*
X646342Y1465833D01*
X645967D01*
G01X646342D02*
X646592Y1465958D01*
X646800Y1466167D01*
X646883Y1466417D01*
X646800Y1466667D01*
X646592Y1466875D01*
X646217Y1467000D01*
X645842Y1466958D01*
X645467Y1466792D01*
G01X648233Y1464875D02*
X648483Y1464667D01*
X648775Y1464542D01*
X649150Y1464500D01*
X649525Y1464583D01*
X649817Y1464750D01*
X650025Y1465042D01*
X650067Y1465375D01*
X649983Y1465708D01*
X649775Y1465917D01*
X649483Y1466083D01*
X649192Y1466125D01*
X648900Y1466083D01*
X648525Y1465917D01*
X648650Y1467000D01*
X649775D01*
G01X630800Y1466500D02*
Y1462500D01*
X638200D01*
G01X643767Y1451292D02*
X643517Y1451417D01*
X643225Y1451500D01*
X642892D01*
X642517Y1451375D01*
X642225Y1451167D01*
X642017Y1450917D01*
X641850Y1450500D01*
X641808Y1450125D01*
X641892Y1449750D01*
X642017Y1449500D01*
X642267Y1449250D01*
X642558Y1449083D01*
X642850Y1449000D01*
X643142D01*
X643433Y1449083D01*
X643683Y1449208D01*
X643892Y1449375D01*
G01X645033D02*
X645283Y1449167D01*
X645575Y1449042D01*
X645950Y1449000D01*
X646325Y1449083D01*
X646617Y1449250D01*
X646825Y1449542D01*
X646867Y1449875D01*
X646783Y1450208D01*
X646575Y1450417D01*
X646283Y1450583D01*
X645992Y1450625D01*
X645700Y1450583D01*
X645325Y1450417D01*
X645450Y1451500D01*
X646575D01*
G01X649550Y1449000D02*
Y1451500D01*
X648008Y1449708D01*
X650092D01*
G01X652150Y1449000D02*
Y1451500D01*
X651650Y1451000D01*
G01Y1449000D02*
X652650D01*
G01X651300Y1494267D02*
X650967Y1494309D01*
X650675Y1494475D01*
X650425Y1494725D01*
X650258Y1495017D01*
X650175Y1495350D01*
Y1495684D01*
X650258Y1496017D01*
X650425Y1496309D01*
X650675Y1496559D01*
X650967Y1496725D01*
X651300Y1496767D01*
X651633Y1496725D01*
X651925Y1496559D01*
X652175Y1496309D01*
X652342Y1496017D01*
X652425Y1495684D01*
Y1495350D01*
X652342Y1495017D01*
X652175Y1494725D01*
X651925Y1494475D01*
X651633Y1494309D01*
X651300Y1494267D01*
G01X651633Y1494934D02*
X652133Y1494267D01*
G01X654400D02*
Y1496767D01*
X653900Y1496267D01*
G01Y1494267D02*
X654900D01*
G01X656792Y1494559D02*
X657083Y1494350D01*
X657417Y1494267D01*
X657750Y1494350D01*
X658042Y1494600D01*
X658250Y1494975D01*
X658333Y1495350D01*
Y1495809D01*
X658250Y1496184D01*
X658042Y1496517D01*
X657792Y1496684D01*
X657500Y1496767D01*
X657167Y1496684D01*
X656917Y1496517D01*
X656750Y1496267D01*
X656667Y1495934D01*
X656750Y1495642D01*
X656958Y1495350D01*
X657208Y1495184D01*
X657500Y1495142D01*
X657833Y1495225D01*
X658083Y1495434D01*
X658333Y1495809D01*
G01X659683Y1494767D02*
X659933Y1494475D01*
X660267Y1494309D01*
X660642Y1494267D01*
X660975Y1494309D01*
X661308Y1494517D01*
X661517Y1494767D01*
X661558Y1495017D01*
X661475Y1495309D01*
X661183Y1495517D01*
X660892Y1495600D01*
X660517D01*
G01X660892D02*
X661142Y1495725D01*
X661350Y1495934D01*
X661433Y1496184D01*
X661350Y1496434D01*
X661142Y1496642D01*
X660767Y1496767D01*
X660392Y1496725D01*
X660017Y1496559D01*
G01X669500Y1491500D02*
X655500D01*
G01X669500Y1478500D02*
Y1491500D01*
G01X655500Y1478500D02*
X669500D01*
G01X655500Y1491500D02*
Y1478500D01*
G01X654717Y1474797D02*
Y1477297D01*
X655758D01*
X656092Y1477172D01*
X656300Y1477005D01*
X656383Y1476672D01*
X656300Y1476339D01*
X656050Y1476130D01*
X655758Y1476005D01*
X654717D01*
G01X655758D02*
X656383Y1474797D01*
G01X657942Y1475089D02*
X658233Y1474880D01*
X658567Y1474797D01*
X658900Y1474880D01*
X659192Y1475130D01*
X659400Y1475505D01*
X659483Y1475880D01*
Y1476339D01*
X659400Y1476714D01*
X659192Y1477047D01*
X658942Y1477214D01*
X658650Y1477297D01*
X658317Y1477214D01*
X658067Y1477047D01*
X657900Y1476797D01*
X657817Y1476464D01*
X657900Y1476172D01*
X658108Y1475880D01*
X658358Y1475714D01*
X658650Y1475672D01*
X658983Y1475755D01*
X659233Y1475964D01*
X659483Y1476339D01*
G01X661042Y1475089D02*
X661333Y1474880D01*
X661667Y1474797D01*
X662000Y1474880D01*
X662292Y1475130D01*
X662500Y1475505D01*
X662583Y1475880D01*
Y1476339D01*
X662500Y1476714D01*
X662292Y1477047D01*
X662042Y1477214D01*
X661750Y1477297D01*
X661417Y1477214D01*
X661167Y1477047D01*
X661000Y1476797D01*
X660917Y1476464D01*
X661000Y1476172D01*
X661208Y1475880D01*
X661458Y1475714D01*
X661750Y1475672D01*
X662083Y1475755D01*
X662333Y1475964D01*
X662583Y1476339D01*
G01X664850Y1474797D02*
X665142Y1474839D01*
X665475Y1474964D01*
X665683Y1475172D01*
X665767Y1475464D01*
X665683Y1475755D01*
X665433Y1476005D01*
X665058Y1476130D01*
X664642D01*
X664392Y1476214D01*
X664183Y1476422D01*
X664100Y1476714D01*
X664225Y1477005D01*
X664517Y1477214D01*
X664850Y1477297D01*
X665183Y1477214D01*
X665475Y1477005D01*
X665600Y1476714D01*
X665517Y1476422D01*
X665308Y1476214D01*
X665058Y1476130D01*
X664642D01*
X664267Y1476005D01*
X664017Y1475755D01*
X663933Y1475464D01*
X664017Y1475172D01*
X664225Y1474964D01*
X664558Y1474839D01*
X664850Y1474797D01*
G01X656600Y1470000D02*
Y1466000D01*
X664000D01*
G01X642017Y1445000D02*
Y1447500D01*
X643058D01*
X643392Y1447375D01*
X643600Y1447208D01*
X643683Y1446875D01*
X643600Y1446542D01*
X643350Y1446333D01*
X643058Y1446208D01*
X642017D01*
G01X643058D02*
X643683Y1445000D01*
G01X645242Y1445292D02*
X645533Y1445083D01*
X645867Y1445000D01*
X646200Y1445083D01*
X646492Y1445333D01*
X646700Y1445708D01*
X646783Y1446083D01*
Y1446542D01*
X646700Y1446917D01*
X646492Y1447250D01*
X646242Y1447417D01*
X645950Y1447500D01*
X645617Y1447417D01*
X645367Y1447250D01*
X645200Y1447000D01*
X645117Y1446667D01*
X645200Y1446375D01*
X645408Y1446083D01*
X645658Y1445917D01*
X645950Y1445875D01*
X646283Y1445958D01*
X646533Y1446167D01*
X646783Y1446542D01*
G01X649050Y1445000D02*
X649342Y1445042D01*
X649675Y1445167D01*
X649883Y1445375D01*
X649967Y1445667D01*
X649883Y1445958D01*
X649633Y1446208D01*
X649258Y1446333D01*
X648842D01*
X648592Y1446417D01*
X648383Y1446625D01*
X648300Y1446917D01*
X648425Y1447208D01*
X648717Y1447417D01*
X649050Y1447500D01*
X649383Y1447417D01*
X649675Y1447208D01*
X649800Y1446917D01*
X649717Y1446625D01*
X649508Y1446417D01*
X649258Y1446333D01*
X648842D01*
X648467Y1446208D01*
X648217Y1445958D01*
X648133Y1445667D01*
X648217Y1445375D01*
X648425Y1445167D01*
X648758Y1445042D01*
X649050Y1445000D01*
G01X652650D02*
Y1447500D01*
X651108Y1445708D01*
X653192D01*
G01X659800Y1446000D02*
Y1442000D01*
X667200D01*
G01X654813Y1471077D02*
Y1473577D01*
X655854D01*
X656188Y1473452D01*
X656396Y1473285D01*
X656479Y1472952D01*
X656396Y1472619D01*
X656146Y1472410D01*
X655854Y1472285D01*
X654813D01*
G01X655854D02*
X656479Y1471077D01*
G01X658746D02*
Y1473577D01*
X658246Y1473077D01*
G01Y1471077D02*
X659246D01*
G01X661846Y1473577D02*
X661513Y1473494D01*
X661263Y1473285D01*
X661096Y1473035D01*
X660971Y1472702D01*
X660929Y1472327D01*
X660971Y1471952D01*
X661096Y1471619D01*
X661263Y1471369D01*
X661513Y1471160D01*
X661846Y1471077D01*
X662179Y1471160D01*
X662429Y1471369D01*
X662596Y1471619D01*
X662721Y1471952D01*
X662763Y1472327D01*
X662721Y1472702D01*
X662596Y1473035D01*
X662429Y1473285D01*
X662179Y1473494D01*
X661846Y1473577D01*
G01X664946D02*
X664613Y1473494D01*
X664363Y1473285D01*
X664196Y1473035D01*
X664071Y1472702D01*
X664029Y1472327D01*
X664071Y1471952D01*
X664196Y1471619D01*
X664363Y1471369D01*
X664613Y1471160D01*
X664946Y1471077D01*
X665279Y1471160D01*
X665529Y1471369D01*
X665696Y1471619D01*
X665821Y1471952D01*
X665863Y1472327D01*
X665821Y1472702D01*
X665696Y1473035D01*
X665529Y1473285D01*
X665279Y1473494D01*
X664946Y1473577D01*
G01X668046D02*
X667713Y1473494D01*
X667463Y1473285D01*
X667296Y1473035D01*
X667171Y1472702D01*
X667129Y1472327D01*
X667171Y1471952D01*
X667296Y1471619D01*
X667463Y1471369D01*
X667713Y1471160D01*
X668046Y1471077D01*
X668379Y1471160D01*
X668629Y1471369D01*
X668796Y1471619D01*
X668921Y1471952D01*
X668963Y1472327D01*
X668921Y1472702D01*
X668796Y1473035D01*
X668629Y1473285D01*
X668379Y1473494D01*
X668046Y1473577D01*
G01X656600Y1466000D02*
Y1462000D01*
X664000D01*
G01X649500Y1477517D02*
X647000D01*
Y1478558D01*
X647125Y1478892D01*
X647292Y1479100D01*
X647625Y1479183D01*
X647958Y1479100D01*
X648167Y1478850D01*
X648292Y1478558D01*
Y1477517D01*
G01Y1478558D02*
X649500Y1479183D01*
G01X649208Y1480742D02*
X649417Y1481033D01*
X649500Y1481367D01*
X649417Y1481700D01*
X649167Y1481992D01*
X648792Y1482200D01*
X648417Y1482283D01*
X647958D01*
X647583Y1482200D01*
X647250Y1481992D01*
X647083Y1481742D01*
X647000Y1481450D01*
X647083Y1481117D01*
X647250Y1480867D01*
X647500Y1480700D01*
X647833Y1480617D01*
X648125Y1480700D01*
X648417Y1480908D01*
X648583Y1481158D01*
X648625Y1481450D01*
X648542Y1481783D01*
X648333Y1482033D01*
X647958Y1482283D01*
G01X649500Y1484550D02*
X649458Y1484842D01*
X649333Y1485175D01*
X649125Y1485383D01*
X648833Y1485467D01*
X648542Y1485383D01*
X648292Y1485133D01*
X648167Y1484758D01*
Y1484342D01*
X648083Y1484092D01*
X647875Y1483883D01*
X647583Y1483800D01*
X647292Y1483925D01*
X647083Y1484217D01*
X647000Y1484550D01*
X647083Y1484883D01*
X647292Y1485175D01*
X647583Y1485300D01*
X647875Y1485217D01*
X648083Y1485008D01*
X648167Y1484758D01*
Y1484342D01*
X648292Y1483967D01*
X648542Y1483717D01*
X648833Y1483633D01*
X649125Y1483717D01*
X649333Y1483925D01*
X649458Y1484258D01*
X649500Y1484550D01*
G01X649000Y1486733D02*
X649292Y1486983D01*
X649458Y1487317D01*
X649500Y1487692D01*
X649458Y1488025D01*
X649250Y1488358D01*
X649000Y1488567D01*
X648750Y1488608D01*
X648458Y1488525D01*
X648250Y1488233D01*
X648167Y1487942D01*
Y1487567D01*
G01Y1487942D02*
X648042Y1488192D01*
X647833Y1488400D01*
X647583Y1488483D01*
X647333Y1488400D01*
X647125Y1488192D01*
X647000Y1487817D01*
X647042Y1487442D01*
X647208Y1487067D01*
G01X655000Y1486700D02*
X651000D01*
Y1479300D01*
G01X640467Y1453000D02*
Y1455500D01*
X641508D01*
X641842Y1455375D01*
X642050Y1455208D01*
X642133Y1454875D01*
X642050Y1454542D01*
X641800Y1454333D01*
X641508Y1454208D01*
X640467D01*
G01X641508D02*
X642133Y1453000D01*
G01X644400D02*
Y1455500D01*
X643900Y1455000D01*
G01Y1453000D02*
X644900D01*
G01X647500Y1455500D02*
X647167Y1455417D01*
X646917Y1455208D01*
X646750Y1454958D01*
X646625Y1454625D01*
X646583Y1454250D01*
X646625Y1453875D01*
X646750Y1453542D01*
X646917Y1453292D01*
X647167Y1453083D01*
X647500Y1453000D01*
X647833Y1453083D01*
X648083Y1453292D01*
X648250Y1453542D01*
X648375Y1453875D01*
X648417Y1454250D01*
X648375Y1454625D01*
X648250Y1454958D01*
X648083Y1455208D01*
X647833Y1455417D01*
X647500Y1455500D01*
G01X649808Y1454042D02*
X650100Y1454333D01*
X650350Y1454500D01*
X650683Y1454583D01*
X650975Y1454500D01*
X651183Y1454333D01*
X651350Y1454083D01*
X651392Y1453792D01*
X651350Y1453542D01*
X651183Y1453292D01*
X650933Y1453083D01*
X650642Y1453000D01*
X650308Y1453083D01*
X650017Y1453333D01*
X649850Y1453708D01*
X649808Y1454125D01*
X649892Y1454667D01*
X650017Y1454958D01*
X650225Y1455250D01*
X650517Y1455458D01*
X650808Y1455500D01*
X651100Y1455417D01*
X651308Y1455208D01*
G01X653700Y1455500D02*
X653367Y1455417D01*
X653117Y1455208D01*
X652950Y1454958D01*
X652825Y1454625D01*
X652783Y1454250D01*
X652825Y1453875D01*
X652950Y1453542D01*
X653117Y1453292D01*
X653367Y1453083D01*
X653700Y1453000D01*
X654033Y1453083D01*
X654283Y1453292D01*
X654450Y1453542D01*
X654575Y1453875D01*
X654617Y1454250D01*
X654575Y1454625D01*
X654450Y1454958D01*
X654283Y1455208D01*
X654033Y1455417D01*
X653700Y1455500D01*
G01X656600D02*
Y1451500D01*
X664000D01*
G01X640467Y1457000D02*
Y1459500D01*
X641508D01*
X641842Y1459375D01*
X642050Y1459208D01*
X642133Y1458875D01*
X642050Y1458542D01*
X641800Y1458333D01*
X641508Y1458208D01*
X640467D01*
G01X641508D02*
X642133Y1457000D01*
G01X644400D02*
Y1459500D01*
X643900Y1459000D01*
G01Y1457000D02*
X644900D01*
G01X647500Y1459500D02*
X647167Y1459417D01*
X646917Y1459208D01*
X646750Y1458958D01*
X646625Y1458625D01*
X646583Y1458250D01*
X646625Y1457875D01*
X646750Y1457542D01*
X646917Y1457292D01*
X647167Y1457083D01*
X647500Y1457000D01*
X647833Y1457083D01*
X648083Y1457292D01*
X648250Y1457542D01*
X648375Y1457875D01*
X648417Y1458250D01*
X648375Y1458625D01*
X648250Y1458958D01*
X648083Y1459208D01*
X647833Y1459417D01*
X647500Y1459500D01*
G01X649683Y1457375D02*
X649933Y1457167D01*
X650225Y1457042D01*
X650600Y1457000D01*
X650975Y1457083D01*
X651267Y1457250D01*
X651475Y1457542D01*
X651517Y1457875D01*
X651433Y1458208D01*
X651225Y1458417D01*
X650933Y1458583D01*
X650642Y1458625D01*
X650350Y1458583D01*
X649975Y1458417D01*
X650100Y1459500D01*
X651225D01*
G01X653700Y1457000D02*
X653992Y1457042D01*
X654325Y1457167D01*
X654533Y1457375D01*
X654617Y1457667D01*
X654533Y1457958D01*
X654283Y1458208D01*
X653908Y1458333D01*
X653492D01*
X653242Y1458417D01*
X653033Y1458625D01*
X652950Y1458917D01*
X653075Y1459208D01*
X653367Y1459417D01*
X653700Y1459500D01*
X654033Y1459417D01*
X654325Y1459208D01*
X654450Y1458917D01*
X654367Y1458625D01*
X654158Y1458417D01*
X653908Y1458333D01*
X653492D01*
X653117Y1458208D01*
X652867Y1457958D01*
X652783Y1457667D01*
X652867Y1457375D01*
X653075Y1457167D01*
X653408Y1457042D01*
X653700Y1457000D01*
G01X656600Y1459500D02*
Y1455500D01*
X664000D01*
G01X668234Y1505700D02*
Y1508200D01*
X669818D01*
G01X669234Y1506992D02*
X668234D01*
G01X671293Y1508200D02*
Y1505700D01*
X672959D01*
G01X676059D02*
X674393D01*
Y1508200D01*
X676059D01*
G01X675393Y1506992D02*
X674393D01*
G01X677409Y1505700D02*
Y1508200D01*
X678243D01*
X678576Y1508075D01*
X678826Y1507908D01*
X679034Y1507658D01*
X679201Y1507367D01*
X679243Y1506950D01*
X679201Y1506533D01*
X679034Y1506242D01*
X678826Y1505992D01*
X678576Y1505825D01*
X678243Y1505700D01*
X677409D01*
G01X680634Y1507783D02*
X680884Y1508033D01*
X681176Y1508158D01*
X681509Y1508200D01*
X681926Y1508117D01*
X682218Y1507908D01*
X682301Y1507658D01*
X682259Y1507408D01*
X682093Y1507200D01*
X681259Y1506783D01*
X680884Y1506492D01*
X680634Y1506075D01*
X680551Y1505700D01*
X682301D01*
G01X715187Y107319D02*
X720237D01*
Y206019D01*
X744887D01*
Y21619D01*
X720237D01*
Y80319D01*
X715187D01*
Y107319D01*
G01X750767Y44792D02*
X750517Y44917D01*
X750225Y45000D01*
X749892D01*
X749517Y44875D01*
X749225Y44667D01*
X749017Y44417D01*
X748850Y44000D01*
X748808Y43625D01*
X748892Y43250D01*
X749017Y43000D01*
X749267Y42750D01*
X749558Y42583D01*
X749850Y42500D01*
X750142D01*
X750433Y42583D01*
X750683Y42708D01*
X750892Y42875D01*
G01X753450Y42500D02*
Y45000D01*
X751908Y43208D01*
X753992D01*
G01X756050Y45000D02*
X755717Y44917D01*
X755467Y44708D01*
X755300Y44458D01*
X755175Y44125D01*
X755133Y43750D01*
X755175Y43375D01*
X755300Y43042D01*
X755467Y42792D01*
X755717Y42583D01*
X756050Y42500D01*
X756383Y42583D01*
X756633Y42792D01*
X756800Y43042D01*
X756925Y43375D01*
X756967Y43750D01*
X756925Y44125D01*
X756800Y44458D01*
X756633Y44708D01*
X756383Y44917D01*
X756050Y45000D01*
G01X758358Y43542D02*
X758650Y43833D01*
X758900Y44000D01*
X759233Y44083D01*
X759525Y44000D01*
X759733Y43833D01*
X759900Y43583D01*
X759942Y43292D01*
X759900Y43042D01*
X759733Y42792D01*
X759483Y42583D01*
X759192Y42500D01*
X758858Y42583D01*
X758567Y42833D01*
X758400Y43208D01*
X758358Y43625D01*
X758442Y44167D01*
X758567Y44458D01*
X758775Y44750D01*
X759067Y44958D01*
X759358Y45000D01*
X759650Y44917D01*
X759858Y44708D01*
G01X750639Y48872D02*
X750389Y48997D01*
X750097Y49080D01*
X749764D01*
X749389Y48955D01*
X749097Y48747D01*
X748889Y48497D01*
X748722Y48080D01*
X748680Y47705D01*
X748764Y47330D01*
X748889Y47080D01*
X749139Y46830D01*
X749430Y46663D01*
X749722Y46580D01*
X750014D01*
X750305Y46663D01*
X750555Y46788D01*
X750764Y46955D01*
G01X753322Y46580D02*
Y49080D01*
X751780Y47288D01*
X753864D01*
G01X755922Y49080D02*
X755589Y48997D01*
X755339Y48788D01*
X755172Y48538D01*
X755047Y48205D01*
X755005Y47830D01*
X755047Y47455D01*
X755172Y47122D01*
X755339Y46872D01*
X755589Y46663D01*
X755922Y46580D01*
X756255Y46663D01*
X756505Y46872D01*
X756672Y47122D01*
X756797Y47455D01*
X756839Y47830D01*
X756797Y48205D01*
X756672Y48538D01*
X756505Y48788D01*
X756255Y48997D01*
X755922Y49080D01*
G01X758105Y46955D02*
X758355Y46747D01*
X758647Y46622D01*
X759022Y46580D01*
X759397Y46663D01*
X759689Y46830D01*
X759897Y47122D01*
X759939Y47455D01*
X759855Y47788D01*
X759647Y47997D01*
X759355Y48163D01*
X759064Y48205D01*
X758772Y48163D01*
X758397Y47997D01*
X758522Y49080D01*
X759647D01*
G01X676167Y79392D02*
X675917Y79517D01*
X675625Y79600D01*
X675292D01*
X674917Y79475D01*
X674625Y79267D01*
X674417Y79017D01*
X674250Y78600D01*
X674208Y78225D01*
X674292Y77850D01*
X674417Y77600D01*
X674667Y77350D01*
X674958Y77183D01*
X675250Y77100D01*
X675542D01*
X675833Y77183D01*
X676083Y77308D01*
X676292Y77475D01*
G01X678850Y77100D02*
Y79600D01*
X677308Y77808D01*
X679392D01*
G01X681450Y77100D02*
Y79600D01*
X680950Y79100D01*
G01Y77100D02*
X681950D01*
G01X683633Y77475D02*
X683883Y77267D01*
X684175Y77142D01*
X684550Y77100D01*
X684925Y77183D01*
X685217Y77350D01*
X685425Y77642D01*
X685467Y77975D01*
X685383Y78308D01*
X685175Y78517D01*
X684883Y78683D01*
X684592Y78725D01*
X684300Y78683D01*
X683925Y78517D01*
X684050Y79600D01*
X685175D01*
G01X694647Y21867D02*
X694522Y21617D01*
X694439Y21325D01*
Y20992D01*
X694564Y20617D01*
X694772Y20325D01*
X695022Y20117D01*
X695439Y19950D01*
X695814Y19908D01*
X696189Y19992D01*
X696439Y20117D01*
X696689Y20367D01*
X696856Y20658D01*
X696939Y20950D01*
Y21242D01*
X696856Y21533D01*
X696731Y21783D01*
X696564Y21992D01*
G01X696939Y24550D02*
X694439D01*
X696231Y23008D01*
Y25092D01*
G01X696939Y27150D02*
X694439D01*
X694939Y26650D01*
G01X696939D02*
Y27650D01*
G01X695897Y29458D02*
X695606Y29750D01*
X695439Y30000D01*
X695356Y30333D01*
X695439Y30625D01*
X695606Y30833D01*
X695856Y31000D01*
X696147Y31042D01*
X696397Y31000D01*
X696647Y30833D01*
X696856Y30583D01*
X696939Y30292D01*
X696856Y29958D01*
X696606Y29667D01*
X696231Y29500D01*
X695814Y29458D01*
X695272Y29542D01*
X694981Y29667D01*
X694689Y29875D01*
X694481Y30167D01*
X694439Y30458D01*
X694522Y30750D01*
X694731Y30958D01*
G01X690000Y66417D02*
X687500D01*
Y67458D01*
X687625Y67792D01*
X687792Y68000D01*
X688125Y68083D01*
X688458Y68000D01*
X688667Y67750D01*
X688792Y67458D01*
Y66417D01*
G01Y67458D02*
X690000Y68083D01*
G01Y70267D02*
X689458Y70350D01*
X689000Y70475D01*
X688583Y70642D01*
X688125Y70850D01*
X687500Y71183D01*
Y69517D01*
G01X690000Y73950D02*
X687500D01*
X689292Y72408D01*
Y74492D01*
G01X690000Y77050D02*
X687500D01*
X689292Y75508D01*
Y77592D01*
G01X697700Y76500D02*
Y80500D01*
X690300D01*
G01X715200Y60017D02*
X712700D01*
Y61058D01*
X712825Y61392D01*
X712992Y61600D01*
X713325Y61683D01*
X713658Y61600D01*
X713867Y61350D01*
X713992Y61058D01*
Y60017D01*
G01Y61058D02*
X715200Y61683D01*
G01Y63867D02*
X714658Y63950D01*
X714200Y64075D01*
X713783Y64242D01*
X713325Y64450D01*
X712700Y64783D01*
Y63117D01*
G01X715200Y67550D02*
X712700D01*
X714492Y66008D01*
Y68092D01*
G01X714825Y69233D02*
X715033Y69483D01*
X715158Y69775D01*
X715200Y70150D01*
X715117Y70525D01*
X714950Y70817D01*
X714658Y71025D01*
X714325Y71067D01*
X713992Y70983D01*
X713783Y70775D01*
X713617Y70483D01*
X713575Y70192D01*
X713617Y69900D01*
X713783Y69525D01*
X712700Y69650D01*
Y70775D01*
G01X714500Y79200D02*
X710500D01*
Y71800D01*
G01X718700Y60017D02*
X716200D01*
Y61058D01*
X716325Y61392D01*
X716492Y61600D01*
X716825Y61683D01*
X717158Y61600D01*
X717367Y61350D01*
X717492Y61058D01*
Y60017D01*
G01Y61058D02*
X718700Y61683D01*
G01Y63867D02*
X718158Y63950D01*
X717700Y64075D01*
X717283Y64242D01*
X716825Y64450D01*
X716200Y64783D01*
Y63117D01*
G01X718700Y67550D02*
X716200D01*
X717992Y66008D01*
Y68092D01*
G01X718700Y70150D02*
X718658Y70442D01*
X718533Y70775D01*
X718325Y70983D01*
X718033Y71067D01*
X717742Y70983D01*
X717492Y70733D01*
X717367Y70358D01*
Y69942D01*
X717283Y69692D01*
X717075Y69483D01*
X716783Y69400D01*
X716492Y69525D01*
X716283Y69817D01*
X716200Y70150D01*
X716283Y70483D01*
X716492Y70775D01*
X716783Y70900D01*
X717075Y70817D01*
X717283Y70608D01*
X717367Y70358D01*
Y69942D01*
X717492Y69567D01*
X717742Y69317D01*
X718033Y69233D01*
X718325Y69317D01*
X718533Y69525D01*
X718658Y69858D01*
X718700Y70150D01*
G01X719000Y79200D02*
X715000D01*
Y71800D01*
G01X700517Y83500D02*
Y86000D01*
X701558D01*
X701892Y85875D01*
X702100Y85708D01*
X702183Y85375D01*
X702100Y85042D01*
X701850Y84833D01*
X701558Y84708D01*
X700517D01*
G01X701558D02*
X702183Y83500D01*
G01X704367D02*
X704450Y84042D01*
X704575Y84500D01*
X704742Y84917D01*
X704950Y85375D01*
X705283Y86000D01*
X703617D01*
G01X706633Y83875D02*
X706883Y83667D01*
X707175Y83542D01*
X707550Y83500D01*
X707925Y83583D01*
X708217Y83750D01*
X708425Y84042D01*
X708467Y84375D01*
X708383Y84708D01*
X708175Y84917D01*
X707883Y85083D01*
X707592Y85125D01*
X707300Y85083D01*
X706925Y84917D01*
X707050Y86000D01*
X708175D01*
G01X710650D02*
X710317Y85917D01*
X710067Y85708D01*
X709900Y85458D01*
X709775Y85125D01*
X709733Y84750D01*
X709775Y84375D01*
X709900Y84042D01*
X710067Y83792D01*
X710317Y83583D01*
X710650Y83500D01*
X710983Y83583D01*
X711233Y83792D01*
X711400Y84042D01*
X711525Y84375D01*
X711567Y84750D01*
X711525Y85125D01*
X711400Y85458D01*
X711233Y85708D01*
X710983Y85917D01*
X710650Y86000D01*
G01X702000Y71800D02*
X706000D01*
Y79200D01*
G01X711200Y28017D02*
X708700D01*
Y29058D01*
X708825Y29392D01*
X708992Y29600D01*
X709325Y29683D01*
X709658Y29600D01*
X709867Y29350D01*
X709992Y29058D01*
Y28017D01*
G01Y29058D02*
X711200Y29683D01*
G01Y31867D02*
X710658Y31950D01*
X710200Y32075D01*
X709783Y32242D01*
X709325Y32450D01*
X708700Y32783D01*
Y31117D01*
G01X710825Y34133D02*
X711033Y34383D01*
X711158Y34675D01*
X711200Y35050D01*
X711117Y35425D01*
X710950Y35717D01*
X710658Y35925D01*
X710325Y35967D01*
X709992Y35883D01*
X709783Y35675D01*
X709617Y35383D01*
X709575Y35092D01*
X709617Y34800D01*
X709783Y34425D01*
X708700Y34550D01*
Y35675D01*
G01X711200Y38150D02*
X708700D01*
X709200Y37650D01*
G01X711200D02*
Y38650D01*
G01X712000Y39800D02*
X716000D01*
Y47200D01*
G01X700939Y20117D02*
X698439D01*
Y21158D01*
X698564Y21492D01*
X698731Y21700D01*
X699064Y21783D01*
X699397Y21700D01*
X699606Y21450D01*
X699731Y21158D01*
Y20117D01*
G01Y21158D02*
X700939Y21783D01*
G01Y23967D02*
X700397Y24050D01*
X699939Y24175D01*
X699522Y24342D01*
X699064Y24550D01*
X698439Y24883D01*
Y23217D01*
G01X700564Y26233D02*
X700772Y26483D01*
X700897Y26775D01*
X700939Y27150D01*
X700856Y27525D01*
X700689Y27817D01*
X700397Y28025D01*
X700064Y28067D01*
X699731Y27983D01*
X699522Y27775D01*
X699356Y27483D01*
X699314Y27192D01*
X699356Y26900D01*
X699522Y26525D01*
X698439Y26650D01*
Y27775D01*
G01X698856Y29458D02*
X698606Y29708D01*
X698481Y30000D01*
X698439Y30333D01*
X698522Y30750D01*
X698731Y31042D01*
X698981Y31125D01*
X699231Y31083D01*
X699439Y30917D01*
X699856Y30083D01*
X700147Y29708D01*
X700564Y29458D01*
X700939Y29375D01*
Y31125D01*
G01X701600Y42800D02*
X697600D01*
Y35400D01*
G01X706700Y30617D02*
X704200D01*
Y31658D01*
X704325Y31992D01*
X704492Y32200D01*
X704825Y32283D01*
X705158Y32200D01*
X705367Y31950D01*
X705492Y31658D01*
Y30617D01*
G01Y31658D02*
X706700Y32283D01*
G01Y34467D02*
X706158Y34550D01*
X705700Y34675D01*
X705283Y34842D01*
X704825Y35050D01*
X704200Y35383D01*
Y33717D01*
G01X706325Y36733D02*
X706533Y36983D01*
X706658Y37275D01*
X706700Y37650D01*
X706617Y38025D01*
X706450Y38317D01*
X706158Y38525D01*
X705825Y38567D01*
X705492Y38483D01*
X705283Y38275D01*
X705117Y37983D01*
X705075Y37692D01*
X705117Y37400D01*
X705283Y37025D01*
X704200Y37150D01*
Y38275D01*
G01X706200Y39833D02*
X706492Y40083D01*
X706658Y40417D01*
X706700Y40792D01*
X706658Y41125D01*
X706450Y41458D01*
X706200Y41667D01*
X705950Y41708D01*
X705658Y41625D01*
X705450Y41333D01*
X705367Y41042D01*
Y40667D01*
G01Y41042D02*
X705242Y41292D01*
X705033Y41500D01*
X704783Y41583D01*
X704533Y41500D01*
X704325Y41292D01*
X704200Y40917D01*
X704242Y40542D01*
X704408Y40167D01*
G01X706700Y43050D02*
Y47050D01*
X699300D01*
G01X695017Y56000D02*
Y58500D01*
X696058D01*
X696392Y58375D01*
X696600Y58208D01*
X696683Y57875D01*
X696600Y57542D01*
X696350Y57333D01*
X696058Y57208D01*
X695017D01*
G01X696058D02*
X696683Y56000D01*
G01X698867D02*
X698950Y56542D01*
X699075Y57000D01*
X699242Y57417D01*
X699450Y57875D01*
X699783Y58500D01*
X698117D01*
G01X701133Y56375D02*
X701383Y56167D01*
X701675Y56042D01*
X702050Y56000D01*
X702425Y56083D01*
X702717Y56250D01*
X702925Y56542D01*
X702967Y56875D01*
X702883Y57208D01*
X702675Y57417D01*
X702383Y57583D01*
X702092Y57625D01*
X701800Y57583D01*
X701425Y57417D01*
X701550Y58500D01*
X702675D01*
G01X705650Y56000D02*
Y58500D01*
X704108Y56708D01*
X706192D01*
G01X710300Y59400D02*
Y55400D01*
X717700D01*
G01X691483Y48800D02*
Y51300D01*
X692317D01*
X692650Y51175D01*
X692900Y51008D01*
X693108Y50758D01*
X693275Y50467D01*
X693317Y50050D01*
X693275Y49633D01*
X693108Y49342D01*
X692900Y49092D01*
X692650Y48925D01*
X692317Y48800D01*
X691483D01*
G01X694708Y50883D02*
X694958Y51133D01*
X695250Y51258D01*
X695583Y51300D01*
X696000Y51217D01*
X696292Y51008D01*
X696375Y50758D01*
X696333Y50508D01*
X696167Y50300D01*
X695333Y49883D01*
X694958Y49592D01*
X694708Y49175D01*
X694625Y48800D01*
X696375D01*
G01X697892Y49092D02*
X698183Y48883D01*
X698517Y48800D01*
X698850Y48883D01*
X699142Y49133D01*
X699350Y49508D01*
X699433Y49883D01*
Y50342D01*
X699350Y50717D01*
X699142Y51050D01*
X698892Y51217D01*
X698600Y51300D01*
X698267Y51217D01*
X698017Y51050D01*
X697850Y50800D01*
X697767Y50467D01*
X697850Y50175D01*
X698058Y49883D01*
X698308Y49717D01*
X698600Y49675D01*
X698933Y49758D01*
X699183Y49967D01*
X699433Y50342D01*
G01X701500Y54800D02*
X717600D01*
G01X701500Y47800D02*
Y54800D01*
G01X717600Y47800D02*
X701500D01*
G01X717600Y54800D02*
Y47800D01*
G01X696000Y61850D02*
X695958Y61517D01*
X695792Y61225D01*
X695542Y60975D01*
X695250Y60808D01*
X694917Y60725D01*
X694583D01*
X694250Y60808D01*
X693958Y60975D01*
X693708Y61225D01*
X693542Y61517D01*
X693500Y61850D01*
X693542Y62183D01*
X693708Y62475D01*
X693958Y62725D01*
X694250Y62892D01*
X694583Y62975D01*
X694917D01*
X695250Y62892D01*
X695542Y62725D01*
X695792Y62475D01*
X695958Y62183D01*
X696000Y61850D01*
G01X695333Y62183D02*
X696000Y62683D01*
G01Y64950D02*
X693500D01*
X694000Y64450D01*
G01X696000D02*
Y65450D01*
G01Y68550D02*
X693500D01*
X695292Y67008D01*
Y69092D01*
G01X695708Y70442D02*
X695917Y70733D01*
X696000Y71067D01*
X695917Y71400D01*
X695667Y71692D01*
X695292Y71900D01*
X694917Y71983D01*
X694458D01*
X694083Y71900D01*
X693750Y71692D01*
X693583Y71442D01*
X693500Y71150D01*
X693583Y70817D01*
X693750Y70567D01*
X694000Y70400D01*
X694333Y70317D01*
X694625Y70400D01*
X694917Y70608D01*
X695083Y70858D01*
X695125Y71150D01*
X695042Y71483D01*
X694833Y71733D01*
X694458Y71983D01*
G01X697300Y71200D02*
Y59800D01*
G01X710700Y71200D02*
X697300D01*
G01X710700Y59800D02*
Y71200D01*
G01X697300Y59800D02*
X710700D01*
G01X752367Y118853D02*
X752117Y118978D01*
X751825Y119061D01*
X751492D01*
X751117Y118936D01*
X750825Y118728D01*
X750617Y118478D01*
X750450Y118061D01*
X750408Y117686D01*
X750492Y117311D01*
X750617Y117061D01*
X750867Y116811D01*
X751158Y116644D01*
X751450Y116561D01*
X751742D01*
X752033Y116644D01*
X752283Y116769D01*
X752492Y116936D01*
G01X755050Y116561D02*
Y119061D01*
X753508Y117269D01*
X755592D01*
G01X757650Y116561D02*
Y119061D01*
X757150Y118561D01*
G01Y116561D02*
X758150D01*
G01X761250D02*
Y119061D01*
X759708Y117269D01*
X761792D01*
G01X750617Y120561D02*
Y123061D01*
X751658D01*
X751992Y122936D01*
X752200Y122769D01*
X752283Y122436D01*
X752200Y122103D01*
X751950Y121894D01*
X751658Y121769D01*
X750617D01*
G01X751658D02*
X752283Y120561D01*
G01X754467D02*
X754550Y121103D01*
X754675Y121561D01*
X754842Y121978D01*
X755050Y122436D01*
X755383Y123061D01*
X753717D01*
G01X756733Y121061D02*
X756983Y120769D01*
X757317Y120603D01*
X757692Y120561D01*
X758025Y120603D01*
X758358Y120811D01*
X758567Y121061D01*
X758608Y121311D01*
X758525Y121603D01*
X758233Y121811D01*
X757942Y121894D01*
X757567D01*
G01X757942D02*
X758192Y122019D01*
X758400Y122228D01*
X758483Y122478D01*
X758400Y122728D01*
X758192Y122936D01*
X757817Y123061D01*
X757442Y123019D01*
X757067Y122853D01*
G01X760667Y120561D02*
X760750Y121103D01*
X760875Y121561D01*
X761042Y121978D01*
X761250Y122436D01*
X761583Y123061D01*
X759917D01*
G01X753700Y128500D02*
Y132500D01*
X746300D01*
G01X692267Y156292D02*
X692017Y156417D01*
X691725Y156500D01*
X691392D01*
X691017Y156375D01*
X690725Y156167D01*
X690517Y155917D01*
X690350Y155500D01*
X690308Y155125D01*
X690392Y154750D01*
X690517Y154500D01*
X690767Y154250D01*
X691058Y154083D01*
X691350Y154000D01*
X691642D01*
X691933Y154083D01*
X692183Y154208D01*
X692392Y154375D01*
G01X694950Y154000D02*
Y156500D01*
X693408Y154708D01*
X695492D01*
G01X697550Y156500D02*
X697217Y156417D01*
X696967Y156208D01*
X696800Y155958D01*
X696675Y155625D01*
X696633Y155250D01*
X696675Y154875D01*
X696800Y154542D01*
X696967Y154292D01*
X697217Y154083D01*
X697550Y154000D01*
X697883Y154083D01*
X698133Y154292D01*
X698300Y154542D01*
X698425Y154875D01*
X698467Y155250D01*
X698425Y155625D01*
X698300Y155958D01*
X698133Y156208D01*
X697883Y156417D01*
X697550Y156500D01*
G01X700567Y154000D02*
X700650Y154542D01*
X700775Y155000D01*
X700942Y155417D01*
X701150Y155875D01*
X701483Y156500D01*
X699817D01*
G01X703267Y183792D02*
X703017Y183917D01*
X702725Y184000D01*
X702392D01*
X702017Y183875D01*
X701725Y183667D01*
X701517Y183417D01*
X701350Y183000D01*
X701308Y182625D01*
X701392Y182250D01*
X701517Y182000D01*
X701767Y181750D01*
X702058Y181583D01*
X702350Y181500D01*
X702642D01*
X702933Y181583D01*
X703183Y181708D01*
X703392Y181875D01*
G01X705950Y181500D02*
Y184000D01*
X704408Y182208D01*
X706492D01*
G01X708550Y181500D02*
Y184000D01*
X708050Y183500D01*
G01Y181500D02*
X709050D01*
G01X710733Y182000D02*
X710983Y181708D01*
X711317Y181542D01*
X711692Y181500D01*
X712025Y181542D01*
X712358Y181750D01*
X712567Y182000D01*
X712608Y182250D01*
X712525Y182542D01*
X712233Y182750D01*
X711942Y182833D01*
X711567D01*
G01X711942D02*
X712192Y182958D01*
X712400Y183167D01*
X712483Y183417D01*
X712400Y183667D01*
X712192Y183875D01*
X711817Y184000D01*
X711442Y183958D01*
X711067Y183792D01*
G01X704800Y156500D02*
Y154000D01*
G01X703842Y156500D02*
X705758D01*
G01X707067Y154000D02*
Y156500D01*
X708067D01*
X708400Y156375D01*
X708650Y156083D01*
X708733Y155750D01*
X708650Y155417D01*
X708442Y155167D01*
X708067Y155042D01*
X707067D01*
G01X711000Y154000D02*
Y156500D01*
X710500Y156000D01*
G01Y154000D02*
X711500D01*
G01X713308Y155042D02*
X713600Y155333D01*
X713850Y155500D01*
X714183Y155583D01*
X714475Y155500D01*
X714683Y155333D01*
X714850Y155083D01*
X714892Y154792D01*
X714850Y154542D01*
X714683Y154292D01*
X714433Y154083D01*
X714142Y154000D01*
X713808Y154083D01*
X713517Y154333D01*
X713350Y154708D01*
X713308Y155125D01*
X713392Y155667D01*
X713517Y155958D01*
X713725Y156250D01*
X714017Y156458D01*
X714308Y156500D01*
X714600Y156417D01*
X714808Y156208D01*
G01X716408Y155042D02*
X716700Y155333D01*
X716950Y155500D01*
X717283Y155583D01*
X717575Y155500D01*
X717783Y155333D01*
X717950Y155083D01*
X717992Y154792D01*
X717950Y154542D01*
X717783Y154292D01*
X717533Y154083D01*
X717242Y154000D01*
X716908Y154083D01*
X716617Y154333D01*
X716450Y154708D01*
X716408Y155125D01*
X716492Y155667D01*
X716617Y155958D01*
X716825Y156250D01*
X717117Y156458D01*
X717408Y156500D01*
X717700Y156417D01*
X717908Y156208D01*
G01X698850Y118500D02*
X698517Y118542D01*
X698225Y118708D01*
X697975Y118958D01*
X697808Y119250D01*
X697725Y119583D01*
Y119917D01*
X697808Y120250D01*
X697975Y120542D01*
X698225Y120792D01*
X698517Y120958D01*
X698850Y121000D01*
X699183Y120958D01*
X699475Y120792D01*
X699725Y120542D01*
X699892Y120250D01*
X699975Y119917D01*
Y119583D01*
X699892Y119250D01*
X699725Y118958D01*
X699475Y118708D01*
X699183Y118542D01*
X698850Y118500D01*
G01X699183Y119167D02*
X699683Y118500D01*
G01X701950D02*
Y121000D01*
X701450Y120500D01*
G01Y118500D02*
X702450D01*
G01X705550D02*
Y121000D01*
X704008Y119208D01*
X706092D01*
G01X708150Y118500D02*
X708442Y118542D01*
X708775Y118667D01*
X708983Y118875D01*
X709067Y119167D01*
X708983Y119458D01*
X708733Y119708D01*
X708358Y119833D01*
X707942D01*
X707692Y119917D01*
X707483Y120125D01*
X707400Y120417D01*
X707525Y120708D01*
X707817Y120917D01*
X708150Y121000D01*
X708483Y120917D01*
X708775Y120708D01*
X708900Y120417D01*
X708817Y120125D01*
X708608Y119917D01*
X708358Y119833D01*
X707942D01*
X707567Y119708D01*
X707317Y119458D01*
X707233Y119167D01*
X707317Y118875D01*
X707525Y118667D01*
X707858Y118542D01*
X708150Y118500D01*
G01X713200Y101500D02*
X711100Y103300D01*
X713200Y105500D01*
G01X713300Y109100D02*
X694100D01*
Y97900D01*
X713300D01*
Y109100D01*
X712900D01*
G01X674350Y111500D02*
X674017Y111542D01*
X673725Y111708D01*
X673475Y111958D01*
X673308Y112250D01*
X673225Y112583D01*
Y112917D01*
X673308Y113250D01*
X673475Y113542D01*
X673725Y113792D01*
X674017Y113958D01*
X674350Y114000D01*
X674683Y113958D01*
X674975Y113792D01*
X675225Y113542D01*
X675392Y113250D01*
X675475Y112917D01*
Y112583D01*
X675392Y112250D01*
X675225Y111958D01*
X674975Y111708D01*
X674683Y111542D01*
X674350Y111500D01*
G01X674683Y112167D02*
X675183Y111500D01*
G01X677450D02*
Y114000D01*
X676950Y113500D01*
G01Y111500D02*
X677950D01*
G01X679633Y111875D02*
X679883Y111667D01*
X680175Y111542D01*
X680550Y111500D01*
X680925Y111583D01*
X681217Y111750D01*
X681425Y112042D01*
X681467Y112375D01*
X681383Y112708D01*
X681175Y112917D01*
X680883Y113083D01*
X680592Y113125D01*
X680300Y113083D01*
X679925Y112917D01*
X680050Y114000D01*
X681175D01*
G01X683650D02*
X683317Y113917D01*
X683067Y113708D01*
X682900Y113458D01*
X682775Y113125D01*
X682733Y112750D01*
X682775Y112375D01*
X682900Y112042D01*
X683067Y111792D01*
X683317Y111583D01*
X683650Y111500D01*
X683983Y111583D01*
X684233Y111792D01*
X684400Y112042D01*
X684525Y112375D01*
X684567Y112750D01*
X684525Y113125D01*
X684400Y113458D01*
X684233Y113708D01*
X683983Y113917D01*
X683650Y114000D01*
G01X755000Y136017D02*
X752500D01*
Y137058D01*
X752625Y137392D01*
X752792Y137600D01*
X753125Y137683D01*
X753458Y137600D01*
X753667Y137350D01*
X753792Y137058D01*
Y136017D01*
G01Y137058D02*
X755000Y137683D01*
G01Y139867D02*
X754458Y139950D01*
X754000Y140075D01*
X753583Y140242D01*
X753125Y140450D01*
X752500Y140783D01*
Y139117D01*
G01X755000Y143550D02*
X752500D01*
X754292Y142008D01*
Y144092D01*
G01X755000Y146150D02*
X752500D01*
X753000Y145650D01*
G01X755000D02*
Y146650D01*
G01X692267Y152292D02*
X692017Y152417D01*
X691725Y152500D01*
X691392D01*
X691017Y152375D01*
X690725Y152167D01*
X690517Y151917D01*
X690350Y151500D01*
X690308Y151125D01*
X690392Y150750D01*
X690517Y150500D01*
X690767Y150250D01*
X691058Y150083D01*
X691350Y150000D01*
X691642D01*
X691933Y150083D01*
X692183Y150208D01*
X692392Y150375D01*
G01X694950Y150000D02*
Y152500D01*
X693408Y150708D01*
X695492D01*
G01X697550Y152500D02*
X697217Y152417D01*
X696967Y152208D01*
X696800Y151958D01*
X696675Y151625D01*
X696633Y151250D01*
X696675Y150875D01*
X696800Y150542D01*
X696967Y150292D01*
X697217Y150083D01*
X697550Y150000D01*
X697883Y150083D01*
X698133Y150292D01*
X698300Y150542D01*
X698425Y150875D01*
X698467Y151250D01*
X698425Y151625D01*
X698300Y151958D01*
X698133Y152208D01*
X697883Y152417D01*
X697550Y152500D01*
G01X700650Y150000D02*
X700942Y150042D01*
X701275Y150167D01*
X701483Y150375D01*
X701567Y150667D01*
X701483Y150958D01*
X701233Y151208D01*
X700858Y151333D01*
X700442D01*
X700192Y151417D01*
X699983Y151625D01*
X699900Y151917D01*
X700025Y152208D01*
X700317Y152417D01*
X700650Y152500D01*
X700983Y152417D01*
X701275Y152208D01*
X701400Y151917D01*
X701317Y151625D01*
X701108Y151417D01*
X700858Y151333D01*
X700442D01*
X700067Y151208D01*
X699817Y150958D01*
X699733Y150667D01*
X699817Y150375D01*
X700025Y150167D01*
X700358Y150042D01*
X700650Y150000D01*
G01X708800Y122000D02*
X703300D01*
G01X708800Y130000D02*
Y122000D01*
G01X703300Y130000D02*
X708800D01*
G01X691200D02*
X696700D01*
G01X691200Y122000D02*
Y130000D01*
G01X696700Y122000D02*
X691200D01*
G01X716500Y141017D02*
X714000D01*
Y142058D01*
X714125Y142392D01*
X714292Y142600D01*
X714625Y142683D01*
X714958Y142600D01*
X715167Y142350D01*
X715292Y142058D01*
Y141017D01*
G01Y142058D02*
X716500Y142683D01*
G01Y144867D02*
X715958Y144950D01*
X715500Y145075D01*
X715083Y145242D01*
X714625Y145450D01*
X714000Y145783D01*
Y144117D01*
G01X716000Y147133D02*
X716292Y147383D01*
X716458Y147717D01*
X716500Y148092D01*
X716458Y148425D01*
X716250Y148758D01*
X716000Y148967D01*
X715750Y149008D01*
X715458Y148925D01*
X715250Y148633D01*
X715167Y148342D01*
Y147967D01*
G01Y148342D02*
X715042Y148592D01*
X714833Y148800D01*
X714583Y148883D01*
X714333Y148800D01*
X714125Y148592D01*
X714000Y148217D01*
X714042Y147842D01*
X714208Y147467D01*
G01X715458Y150358D02*
X715167Y150650D01*
X715000Y150900D01*
X714917Y151233D01*
X715000Y151525D01*
X715167Y151733D01*
X715417Y151900D01*
X715708Y151942D01*
X715958Y151900D01*
X716208Y151733D01*
X716417Y151483D01*
X716500Y151192D01*
X716417Y150858D01*
X716167Y150567D01*
X715792Y150400D01*
X715375Y150358D01*
X714833Y150442D01*
X714542Y150567D01*
X714250Y150775D01*
X714042Y151067D01*
X714000Y151358D01*
X714083Y151650D01*
X714292Y151858D01*
G01X710500Y139800D02*
X718500D01*
Y122200D01*
X710500D01*
Y139800D01*
G01X690517Y158000D02*
Y160500D01*
X691558D01*
X691892Y160375D01*
X692100Y160208D01*
X692183Y159875D01*
X692100Y159542D01*
X691850Y159333D01*
X691558Y159208D01*
X690517D01*
G01X691558D02*
X692183Y158000D01*
G01X694367D02*
X694450Y158542D01*
X694575Y159000D01*
X694742Y159417D01*
X694950Y159875D01*
X695283Y160500D01*
X693617D01*
G01X696633Y158500D02*
X696883Y158208D01*
X697217Y158042D01*
X697592Y158000D01*
X697925Y158042D01*
X698258Y158250D01*
X698467Y158500D01*
X698508Y158750D01*
X698425Y159042D01*
X698133Y159250D01*
X697842Y159333D01*
X697467D01*
G01X697842D02*
X698092Y159458D01*
X698300Y159667D01*
X698383Y159917D01*
X698300Y160167D01*
X698092Y160375D01*
X697717Y160500D01*
X697342Y160458D01*
X696967Y160292D01*
G01X700650Y158000D02*
X700942Y158042D01*
X701275Y158167D01*
X701483Y158375D01*
X701567Y158667D01*
X701483Y158958D01*
X701233Y159208D01*
X700858Y159333D01*
X700442D01*
X700192Y159417D01*
X699983Y159625D01*
X699900Y159917D01*
X700025Y160208D01*
X700317Y160417D01*
X700650Y160500D01*
X700983Y160417D01*
X701275Y160208D01*
X701400Y159917D01*
X701317Y159625D01*
X701108Y159417D01*
X700858Y159333D01*
X700442D01*
X700067Y159208D01*
X699817Y158958D01*
X699733Y158667D01*
X699817Y158375D01*
X700025Y158167D01*
X700358Y158042D01*
X700650Y158000D01*
G01X686700Y136500D02*
Y144500D01*
X704300D01*
Y136500D01*
X686700D01*
G01X674767Y148292D02*
X674517Y148417D01*
X674225Y148500D01*
X673892D01*
X673517Y148375D01*
X673225Y148167D01*
X673017Y147917D01*
X672850Y147500D01*
X672808Y147125D01*
X672892Y146750D01*
X673017Y146500D01*
X673267Y146250D01*
X673558Y146083D01*
X673850Y146000D01*
X674142D01*
X674433Y146083D01*
X674683Y146208D01*
X674892Y146375D01*
G01X677450Y146000D02*
Y148500D01*
X675908Y146708D01*
X677992D01*
G01X680050Y146000D02*
Y148500D01*
X679550Y148000D01*
G01Y146000D02*
X680550D01*
G01X683150D02*
Y148500D01*
X682650Y148000D01*
G01Y146000D02*
X683650D01*
G01X700267Y172792D02*
X700017Y172917D01*
X699725Y173000D01*
X699392D01*
X699017Y172875D01*
X698725Y172667D01*
X698517Y172417D01*
X698350Y172000D01*
X698308Y171625D01*
X698392Y171250D01*
X698517Y171000D01*
X698767Y170750D01*
X699058Y170583D01*
X699350Y170500D01*
X699642D01*
X699933Y170583D01*
X700183Y170708D01*
X700392Y170875D01*
G01X702950Y170500D02*
Y173000D01*
X701408Y171208D01*
X703492D01*
G01X705550Y170500D02*
Y173000D01*
X705050Y172500D01*
G01Y170500D02*
X706050D01*
G01X707858Y172583D02*
X708108Y172833D01*
X708400Y172958D01*
X708733Y173000D01*
X709150Y172917D01*
X709442Y172708D01*
X709525Y172458D01*
X709483Y172208D01*
X709317Y172000D01*
X708483Y171583D01*
X708108Y171292D01*
X707858Y170875D01*
X707775Y170500D01*
X709525D01*
G01X720775Y209500D02*
Y212000D01*
G01X722525D02*
Y209500D01*
G01Y210750D02*
X720775D01*
G01X723833Y209500D02*
Y212000D01*
X724667D01*
X725000Y211875D01*
X725250Y211708D01*
X725458Y211458D01*
X725625Y211167D01*
X725667Y210750D01*
X725625Y210333D01*
X725458Y210042D01*
X725250Y209792D01*
X725000Y209625D01*
X724667Y209500D01*
X723833D01*
G01X726933D02*
Y212000D01*
X727767D01*
X728100Y211875D01*
X728350Y211708D01*
X728558Y211458D01*
X728725Y211167D01*
X728767Y210750D01*
X728725Y210333D01*
X728558Y210042D01*
X728350Y209792D01*
X728100Y209625D01*
X727767Y209500D01*
X726933D01*
G01X730075Y209833D02*
X730408Y209625D01*
X730783Y209500D01*
X731117D01*
X731450Y209625D01*
X731700Y209833D01*
X731825Y210125D01*
X731742Y210417D01*
X731533Y210667D01*
X731158Y210833D01*
X730658Y210917D01*
X730367Y211083D01*
X730242Y211375D01*
X730325Y211667D01*
X730533Y211875D01*
X730825Y212000D01*
X731117D01*
X731408Y211917D01*
X731658Y211708D01*
G01X733008Y209500D02*
X734050Y212000D01*
X735092Y209500D01*
G01X734717Y210375D02*
X733383D01*
G01X736275Y209833D02*
X736608Y209625D01*
X736983Y209500D01*
X737317D01*
X737650Y209625D01*
X737900Y209833D01*
X738025Y210125D01*
X737942Y210417D01*
X737733Y210667D01*
X737358Y210833D01*
X736858Y210917D01*
X736567Y211083D01*
X736442Y211375D01*
X736525Y211667D01*
X736733Y211875D01*
X737025Y212000D01*
X737317D01*
X737608Y211917D01*
X737858Y211708D01*
G01X739458Y211583D02*
X739708Y211833D01*
X740000Y211958D01*
X740333Y212000D01*
X740750Y211917D01*
X741042Y211708D01*
X741125Y211458D01*
X741083Y211208D01*
X740917Y211000D01*
X740083Y210583D01*
X739708Y210292D01*
X739458Y209875D01*
X739375Y209500D01*
X741125D01*
G01X742642Y209792D02*
X742933Y209583D01*
X743267Y209500D01*
X743600Y209583D01*
X743892Y209833D01*
X744100Y210208D01*
X744183Y210583D01*
Y211042D01*
X744100Y211417D01*
X743892Y211750D01*
X743642Y211917D01*
X743350Y212000D01*
X743017Y211917D01*
X742767Y211750D01*
X742600Y211500D01*
X742517Y211167D01*
X742600Y210875D01*
X742808Y210583D01*
X743058Y210417D01*
X743350Y210375D01*
X743683Y210458D01*
X743933Y210667D01*
X744183Y211042D01*
G01X685467Y268500D02*
Y266000D01*
X687133D01*
G01X690233D02*
X688567D01*
Y268500D01*
X690233D01*
G01X689567Y267292D02*
X688567D01*
G01X691583Y266000D02*
Y268500D01*
X692417D01*
X692750Y268375D01*
X693000Y268208D01*
X693208Y267958D01*
X693375Y267667D01*
X693417Y267250D01*
X693375Y266833D01*
X693208Y266542D01*
X693000Y266292D01*
X692750Y266125D01*
X692417Y266000D01*
X691583D01*
G01X695600D02*
Y268500D01*
X695100Y268000D01*
G01Y266000D02*
X696100D01*
G01X698700D02*
X698992Y266042D01*
X699325Y266167D01*
X699533Y266375D01*
X699617Y266667D01*
X699533Y266958D01*
X699283Y267208D01*
X698908Y267333D01*
X698492D01*
X698242Y267417D01*
X698033Y267625D01*
X697950Y267917D01*
X698075Y268208D01*
X698367Y268417D01*
X698700Y268500D01*
X699033Y268417D01*
X699325Y268208D01*
X699450Y267917D01*
X699367Y267625D01*
X699158Y267417D01*
X698908Y267333D01*
X698492D01*
X698117Y267208D01*
X697867Y266958D01*
X697783Y266667D01*
X697867Y266375D01*
X698075Y266167D01*
X698408Y266042D01*
X698700Y266000D01*
G01X686742Y251880D02*
Y263080D01*
X695542D01*
Y251880D01*
X686742D01*
G01X715187Y560075D02*
X720237D01*
Y658775D01*
X744887D01*
Y474375D01*
X720237D01*
Y533075D01*
X715187D01*
Y560075D01*
G01X681891Y400321D02*
X679391D01*
Y401362D01*
X679516Y401696D01*
X679683Y401904D01*
X680016Y401987D01*
X680349Y401904D01*
X680558Y401654D01*
X680683Y401362D01*
Y400321D01*
G01Y401362D02*
X681891Y401987D01*
G01Y404754D02*
X679391D01*
X681183Y403212D01*
Y405296D01*
G01X681891Y407354D02*
X679391D01*
X679891Y406854D01*
G01X681891D02*
Y407854D01*
G01X679808Y409662D02*
X679558Y409912D01*
X679433Y410204D01*
X679391Y410537D01*
X679474Y410954D01*
X679683Y411246D01*
X679933Y411329D01*
X680183Y411287D01*
X680391Y411121D01*
X680808Y410287D01*
X681099Y409912D01*
X681516Y409662D01*
X681891Y409579D01*
Y411329D01*
G01X685891Y400321D02*
X683391D01*
Y401362D01*
X683516Y401696D01*
X683683Y401904D01*
X684016Y401987D01*
X684349Y401904D01*
X684558Y401654D01*
X684683Y401362D01*
Y400321D01*
G01Y401362D02*
X685891Y401987D01*
G01Y404754D02*
X683391D01*
X685183Y403212D01*
Y405296D01*
G01X683808Y406562D02*
X683558Y406812D01*
X683433Y407104D01*
X683391Y407437D01*
X683474Y407854D01*
X683683Y408146D01*
X683933Y408229D01*
X684183Y408187D01*
X684391Y408021D01*
X684808Y407187D01*
X685099Y406812D01*
X685516Y406562D01*
X685891Y406479D01*
Y408229D01*
G01X684849Y409662D02*
X684558Y409954D01*
X684391Y410204D01*
X684308Y410537D01*
X684391Y410829D01*
X684558Y411037D01*
X684808Y411204D01*
X685099Y411246D01*
X685349Y411204D01*
X685599Y411037D01*
X685808Y410787D01*
X685891Y410496D01*
X685808Y410162D01*
X685558Y409871D01*
X685183Y409704D01*
X684766Y409662D01*
X684224Y409746D01*
X683933Y409871D01*
X683641Y410079D01*
X683433Y410371D01*
X683391Y410662D01*
X683474Y410954D01*
X683683Y411162D01*
G01X760139Y510428D02*
X759889Y510553D01*
X759597Y510636D01*
X759264D01*
X758889Y510511D01*
X758597Y510303D01*
X758389Y510053D01*
X758222Y509636D01*
X758180Y509261D01*
X758264Y508886D01*
X758389Y508636D01*
X758639Y508386D01*
X758930Y508219D01*
X759222Y508136D01*
X759514D01*
X759805Y508219D01*
X760055Y508344D01*
X760264Y508511D01*
G01X761530Y510219D02*
X761780Y510469D01*
X762072Y510594D01*
X762405Y510636D01*
X762822Y510553D01*
X763114Y510344D01*
X763197Y510094D01*
X763155Y509844D01*
X762989Y509636D01*
X762155Y509219D01*
X761780Y508928D01*
X761530Y508511D01*
X761447Y508136D01*
X763197D01*
G01X764505Y508511D02*
X764755Y508303D01*
X765047Y508178D01*
X765422Y508136D01*
X765797Y508219D01*
X766089Y508386D01*
X766297Y508678D01*
X766339Y509011D01*
X766255Y509344D01*
X766047Y509553D01*
X765755Y509719D01*
X765464Y509761D01*
X765172Y509719D01*
X764797Y509553D01*
X764922Y510636D01*
X766047D01*
G01X768522D02*
X768189Y510553D01*
X767939Y510344D01*
X767772Y510094D01*
X767647Y509761D01*
X767605Y509386D01*
X767647Y509011D01*
X767772Y508678D01*
X767939Y508428D01*
X768189Y508219D01*
X768522Y508136D01*
X768855Y508219D01*
X769105Y508428D01*
X769272Y508678D01*
X769397Y509011D01*
X769439Y509386D01*
X769397Y509761D01*
X769272Y510094D01*
X769105Y510344D01*
X768855Y510553D01*
X768522Y510636D01*
G01X760267Y514292D02*
X760017Y514417D01*
X759725Y514500D01*
X759392D01*
X759017Y514375D01*
X758725Y514167D01*
X758517Y513917D01*
X758350Y513500D01*
X758308Y513125D01*
X758392Y512750D01*
X758517Y512500D01*
X758767Y512250D01*
X759058Y512083D01*
X759350Y512000D01*
X759642D01*
X759933Y512083D01*
X760183Y512208D01*
X760392Y512375D01*
G01X761658Y514083D02*
X761908Y514333D01*
X762200Y514458D01*
X762533Y514500D01*
X762950Y514417D01*
X763242Y514208D01*
X763325Y513958D01*
X763283Y513708D01*
X763117Y513500D01*
X762283Y513083D01*
X761908Y512792D01*
X761658Y512375D01*
X761575Y512000D01*
X763325D01*
G01X766050D02*
Y514500D01*
X764508Y512708D01*
X766592D01*
G01X767942Y512292D02*
X768233Y512083D01*
X768567Y512000D01*
X768900Y512083D01*
X769192Y512333D01*
X769400Y512708D01*
X769483Y513083D01*
Y513542D01*
X769400Y513917D01*
X769192Y514250D01*
X768942Y514417D01*
X768650Y514500D01*
X768317Y514417D01*
X768067Y514250D01*
X767900Y514000D01*
X767817Y513667D01*
X767900Y513375D01*
X768108Y513083D01*
X768358Y512917D01*
X768650Y512875D01*
X768983Y512958D01*
X769233Y513167D01*
X769483Y513542D01*
G01X747708Y560267D02*
X747583Y560017D01*
X747500Y559725D01*
Y559392D01*
X747625Y559017D01*
X747833Y558725D01*
X748083Y558517D01*
X748500Y558350D01*
X748875Y558308D01*
X749250Y558392D01*
X749500Y558517D01*
X749750Y558767D01*
X749917Y559058D01*
X750000Y559350D01*
Y559642D01*
X749917Y559933D01*
X749792Y560183D01*
X749625Y560392D01*
G01X747917Y561658D02*
X747667Y561908D01*
X747542Y562200D01*
X747500Y562533D01*
X747583Y562950D01*
X747792Y563242D01*
X748042Y563325D01*
X748292Y563283D01*
X748500Y563117D01*
X748917Y562283D01*
X749208Y561908D01*
X749625Y561658D01*
X750000Y561575D01*
Y563325D01*
G01X749625Y564633D02*
X749833Y564883D01*
X749958Y565175D01*
X750000Y565550D01*
X749917Y565925D01*
X749750Y566217D01*
X749458Y566425D01*
X749125Y566467D01*
X748792Y566383D01*
X748583Y566175D01*
X748417Y565883D01*
X748375Y565592D01*
X748417Y565300D01*
X748583Y564925D01*
X747500Y565050D01*
Y566175D01*
G01X750000Y568650D02*
X749958Y568942D01*
X749833Y569275D01*
X749625Y569483D01*
X749333Y569567D01*
X749042Y569483D01*
X748792Y569233D01*
X748667Y568858D01*
Y568442D01*
X748583Y568192D01*
X748375Y567983D01*
X748083Y567900D01*
X747792Y568025D01*
X747583Y568317D01*
X747500Y568650D01*
X747583Y568983D01*
X747792Y569275D01*
X748083Y569400D01*
X748375Y569317D01*
X748583Y569108D01*
X748667Y568858D01*
Y568442D01*
X748792Y568067D01*
X749042Y567817D01*
X749333Y567733D01*
X749625Y567817D01*
X749833Y568025D01*
X749958Y568358D01*
X750000Y568650D01*
G01X754000Y558517D02*
X751500D01*
Y559558D01*
X751625Y559892D01*
X751792Y560100D01*
X752125Y560183D01*
X752458Y560100D01*
X752667Y559850D01*
X752792Y559558D01*
Y558517D01*
G01Y559558D02*
X754000Y560183D01*
G01Y562950D02*
X751500D01*
X753292Y561408D01*
Y563492D01*
G01X752958Y564758D02*
X752667Y565050D01*
X752500Y565300D01*
X752417Y565633D01*
X752500Y565925D01*
X752667Y566133D01*
X752917Y566300D01*
X753208Y566342D01*
X753458Y566300D01*
X753708Y566133D01*
X753917Y565883D01*
X754000Y565592D01*
X753917Y565258D01*
X753667Y564967D01*
X753292Y564800D01*
X752875Y564758D01*
X752333Y564842D01*
X752042Y564967D01*
X751750Y565175D01*
X751542Y565467D01*
X751500Y565758D01*
X751583Y566050D01*
X751792Y566258D01*
G01X754000Y568650D02*
X751500D01*
X752000Y568150D01*
G01X754000D02*
Y569150D01*
G01X683300Y545500D02*
Y541500D01*
X690700D01*
G01X707517Y503500D02*
Y506000D01*
X708558D01*
X708892Y505875D01*
X709100Y505708D01*
X709183Y505375D01*
X709100Y505042D01*
X708850Y504833D01*
X708558Y504708D01*
X707517D01*
G01X708558D02*
X709183Y503500D01*
G01X711950D02*
Y506000D01*
X710408Y504208D01*
X712492D01*
G01X713758Y504542D02*
X714050Y504833D01*
X714300Y505000D01*
X714633Y505083D01*
X714925Y505000D01*
X715133Y504833D01*
X715300Y504583D01*
X715342Y504292D01*
X715300Y504042D01*
X715133Y503792D01*
X714883Y503583D01*
X714592Y503500D01*
X714258Y503583D01*
X713967Y503833D01*
X713800Y504208D01*
X713758Y504625D01*
X713842Y505167D01*
X713967Y505458D01*
X714175Y505750D01*
X714467Y505958D01*
X714758Y506000D01*
X715050Y505917D01*
X715258Y505708D01*
G01X716942Y503792D02*
X717233Y503583D01*
X717567Y503500D01*
X717900Y503583D01*
X718192Y503833D01*
X718400Y504208D01*
X718483Y504583D01*
Y505042D01*
X718400Y505417D01*
X718192Y505750D01*
X717942Y505917D01*
X717650Y506000D01*
X717317Y505917D01*
X717067Y505750D01*
X716900Y505500D01*
X716817Y505167D01*
X716900Y504875D01*
X717108Y504583D01*
X717358Y504417D01*
X717650Y504375D01*
X717983Y504458D01*
X718233Y504667D01*
X718483Y505042D01*
G01X715100Y523300D02*
Y527300D01*
X707700D01*
G01X706000Y499017D02*
X703500D01*
Y500058D01*
X703625Y500392D01*
X703792Y500600D01*
X704125Y500683D01*
X704458Y500600D01*
X704667Y500350D01*
X704792Y500058D01*
Y499017D01*
G01Y500058D02*
X706000Y500683D01*
G01Y503450D02*
X703500D01*
X705292Y501908D01*
Y503992D01*
G01X706000Y505967D02*
X705458Y506050D01*
X705000Y506175D01*
X704583Y506342D01*
X704125Y506550D01*
X703500Y506883D01*
Y505217D01*
G01X706000Y509150D02*
X703500D01*
X704000Y508650D01*
G01X706000D02*
Y509650D01*
G01X705800Y511500D02*
X709800D01*
Y518900D01*
G01X707517Y507500D02*
Y510000D01*
X708558D01*
X708892Y509875D01*
X709100Y509708D01*
X709183Y509375D01*
X709100Y509042D01*
X708850Y508833D01*
X708558Y508708D01*
X707517D01*
G01X708558D02*
X709183Y507500D01*
G01X711950D02*
Y510000D01*
X710408Y508208D01*
X712492D01*
G01X714467Y507500D02*
X714550Y508042D01*
X714675Y508500D01*
X714842Y508917D01*
X715050Y509375D01*
X715383Y510000D01*
X713717D01*
G01X716733Y508000D02*
X716983Y507708D01*
X717317Y507542D01*
X717692Y507500D01*
X718025Y507542D01*
X718358Y507750D01*
X718567Y508000D01*
X718608Y508250D01*
X718525Y508542D01*
X718233Y508750D01*
X717942Y508833D01*
X717567D01*
G01X717942D02*
X718192Y508958D01*
X718400Y509167D01*
X718483Y509417D01*
X718400Y509667D01*
X718192Y509875D01*
X717817Y510000D01*
X717442Y509958D01*
X717067Y509792D01*
G01X707800Y531500D02*
Y527500D01*
X715200D01*
G01X675800Y520000D02*
Y516000D01*
X683200D01*
G01Y547000D02*
Y551000D01*
X675800D01*
G01X676500Y522517D02*
X674000D01*
Y523558D01*
X674125Y523892D01*
X674292Y524100D01*
X674625Y524183D01*
X674958Y524100D01*
X675167Y523850D01*
X675292Y523558D01*
Y522517D01*
G01Y523558D02*
X676500Y524183D01*
G01Y526950D02*
X674000D01*
X675792Y525408D01*
Y527492D01*
G01X676500Y529467D02*
X675958Y529550D01*
X675500Y529675D01*
X675083Y529842D01*
X674625Y530050D01*
X674000Y530383D01*
Y528717D01*
G01X676500Y532567D02*
X675958Y532650D01*
X675500Y532775D01*
X675083Y532942D01*
X674625Y533150D01*
X674000Y533483D01*
Y531817D01*
G01X679000Y520300D02*
X683000D01*
Y527700D01*
G01X694500Y502517D02*
X692000D01*
Y503558D01*
X692125Y503892D01*
X692292Y504100D01*
X692625Y504183D01*
X692958Y504100D01*
X693167Y503850D01*
X693292Y503558D01*
Y502517D01*
G01Y503558D02*
X694500Y504183D01*
G01Y506950D02*
X692000D01*
X693792Y505408D01*
Y507492D01*
G01X694500Y509467D02*
X693958Y509550D01*
X693500Y509675D01*
X693083Y509842D01*
X692625Y510050D01*
X692000Y510383D01*
Y508717D01*
G01X694500Y512650D02*
X694458Y512942D01*
X694333Y513275D01*
X694125Y513483D01*
X693833Y513567D01*
X693542Y513483D01*
X693292Y513233D01*
X693167Y512858D01*
Y512442D01*
X693083Y512192D01*
X692875Y511983D01*
X692583Y511900D01*
X692292Y512025D01*
X692083Y512317D01*
X692000Y512650D01*
X692083Y512983D01*
X692292Y513275D01*
X692583Y513400D01*
X692875Y513317D01*
X693083Y513108D01*
X693167Y512858D01*
Y512442D01*
X693292Y512067D01*
X693542Y511817D01*
X693833Y511733D01*
X694125Y511817D01*
X694333Y512025D01*
X694458Y512358D01*
X694500Y512650D01*
G01X695500Y521700D02*
X691500D01*
Y514300D01*
G01X700400Y571000D02*
X700067Y571042D01*
X699775Y571208D01*
X699525Y571458D01*
X699358Y571750D01*
X699275Y572083D01*
Y572417D01*
X699358Y572750D01*
X699525Y573042D01*
X699775Y573292D01*
X700067Y573458D01*
X700400Y573500D01*
X700733Y573458D01*
X701025Y573292D01*
X701275Y573042D01*
X701442Y572750D01*
X701525Y572417D01*
Y572083D01*
X701442Y571750D01*
X701275Y571458D01*
X701025Y571208D01*
X700733Y571042D01*
X700400Y571000D01*
G01X700733Y571667D02*
X701233Y571000D01*
G01X703417D02*
X703500Y571542D01*
X703625Y572000D01*
X703792Y572417D01*
X704000Y572875D01*
X704333Y573500D01*
X702667D01*
G01X705683Y571375D02*
X705933Y571167D01*
X706225Y571042D01*
X706600Y571000D01*
X706975Y571083D01*
X707267Y571250D01*
X707475Y571542D01*
X707517Y571875D01*
X707433Y572208D01*
X707225Y572417D01*
X706933Y572583D01*
X706642Y572625D01*
X706350Y572583D01*
X705975Y572417D01*
X706100Y573500D01*
X707225D01*
G01X713200Y554000D02*
X711100Y555800D01*
X713200Y558000D01*
G01X713300Y561600D02*
X694100D01*
Y550400D01*
X713300D01*
Y561600D01*
X712900D01*
G01X688500Y504983D02*
X686000D01*
Y505817D01*
X686125Y506150D01*
X686292Y506400D01*
X686542Y506608D01*
X686833Y506775D01*
X687250Y506817D01*
X687667Y506775D01*
X687958Y506608D01*
X688208Y506400D01*
X688375Y506150D01*
X688500Y505817D01*
Y504983D01*
G01Y509000D02*
X686000D01*
X686500Y508500D01*
G01X688500D02*
Y509500D01*
G01Y512017D02*
X687958Y512100D01*
X687500Y512225D01*
X687083Y512392D01*
X686625Y512600D01*
X686000Y512933D01*
Y511267D01*
G01X691000Y530500D02*
Y514400D01*
G01X684000Y530500D02*
X691000D01*
G01X684000Y514400D02*
Y530500D01*
G01X691000Y514400D02*
X684000D01*
G01X695000Y529400D02*
X694958Y529067D01*
X694792Y528775D01*
X694542Y528525D01*
X694250Y528358D01*
X693917Y528275D01*
X693583D01*
X693250Y528358D01*
X692958Y528525D01*
X692708Y528775D01*
X692542Y529067D01*
X692500Y529400D01*
X692542Y529733D01*
X692708Y530025D01*
X692958Y530275D01*
X693250Y530442D01*
X693583Y530525D01*
X693917D01*
X694250Y530442D01*
X694542Y530275D01*
X694792Y530025D01*
X694958Y529733D01*
X695000Y529400D01*
G01X694333Y529733D02*
X695000Y530233D01*
G01Y532417D02*
X694458Y532500D01*
X694000Y532625D01*
X693583Y532792D01*
X693125Y533000D01*
X692500Y533333D01*
Y531667D01*
G01X695000Y535517D02*
X694458Y535600D01*
X694000Y535725D01*
X693583Y535892D01*
X693125Y536100D01*
X692500Y536433D01*
Y534767D01*
G01X707200Y536200D02*
X695800D01*
G01X707200Y522800D02*
Y536200D01*
G01X695800Y522800D02*
X707200D01*
G01X695800Y536200D02*
Y522800D01*
G01X720775Y662500D02*
Y665000D01*
G01X722525D02*
Y662500D01*
G01Y663750D02*
X720775D01*
G01X723833Y662500D02*
Y665000D01*
X724667D01*
X725000Y664875D01*
X725250Y664708D01*
X725458Y664458D01*
X725625Y664167D01*
X725667Y663750D01*
X725625Y663333D01*
X725458Y663042D01*
X725250Y662792D01*
X725000Y662625D01*
X724667Y662500D01*
X723833D01*
G01X726933D02*
Y665000D01*
X727767D01*
X728100Y664875D01*
X728350Y664708D01*
X728558Y664458D01*
X728725Y664167D01*
X728767Y663750D01*
X728725Y663333D01*
X728558Y663042D01*
X728350Y662792D01*
X728100Y662625D01*
X727767Y662500D01*
X726933D01*
G01X730075Y662833D02*
X730408Y662625D01*
X730783Y662500D01*
X731117D01*
X731450Y662625D01*
X731700Y662833D01*
X731825Y663125D01*
X731742Y663417D01*
X731533Y663667D01*
X731158Y663833D01*
X730658Y663917D01*
X730367Y664083D01*
X730242Y664375D01*
X730325Y664667D01*
X730533Y664875D01*
X730825Y665000D01*
X731117D01*
X731408Y664917D01*
X731658Y664708D01*
G01X733008Y662500D02*
X734050Y665000D01*
X735092Y662500D01*
G01X734717Y663375D02*
X733383D01*
G01X736275Y662833D02*
X736608Y662625D01*
X736983Y662500D01*
X737317D01*
X737650Y662625D01*
X737900Y662833D01*
X738025Y663125D01*
X737942Y663417D01*
X737733Y663667D01*
X737358Y663833D01*
X736858Y663917D01*
X736567Y664083D01*
X736442Y664375D01*
X736525Y664667D01*
X736733Y664875D01*
X737025Y665000D01*
X737317D01*
X737608Y664917D01*
X737858Y664708D01*
G01X740250Y662500D02*
Y665000D01*
X739750Y664500D01*
G01Y662500D02*
X740750D01*
G01X743267D02*
X743350Y663042D01*
X743475Y663500D01*
X743642Y663917D01*
X743850Y664375D01*
X744183Y665000D01*
X742517D01*
G01X750200Y573600D02*
X754200D01*
Y581000D01*
G01X693567Y609292D02*
X693317Y609417D01*
X693025Y609500D01*
X692692D01*
X692317Y609375D01*
X692025Y609167D01*
X691817Y608917D01*
X691650Y608500D01*
X691608Y608125D01*
X691692Y607750D01*
X691817Y607500D01*
X692067Y607250D01*
X692358Y607083D01*
X692650Y607000D01*
X692942D01*
X693233Y607083D01*
X693483Y607208D01*
X693692Y607375D01*
G01X694958Y609083D02*
X695208Y609333D01*
X695500Y609458D01*
X695833Y609500D01*
X696250Y609417D01*
X696542Y609208D01*
X696625Y608958D01*
X696583Y608708D01*
X696417Y608500D01*
X695583Y608083D01*
X695208Y607792D01*
X694958Y607375D01*
X694875Y607000D01*
X696625D01*
G01X697933Y607375D02*
X698183Y607167D01*
X698475Y607042D01*
X698850Y607000D01*
X699225Y607083D01*
X699517Y607250D01*
X699725Y607542D01*
X699767Y607875D01*
X699683Y608208D01*
X699475Y608417D01*
X699183Y608583D01*
X698892Y608625D01*
X698600Y608583D01*
X698225Y608417D01*
X698350Y609500D01*
X699475D01*
G01X701950Y607000D02*
Y609500D01*
X701450Y609000D01*
G01Y607000D02*
X702450D01*
G01X710708Y632267D02*
X710583Y632017D01*
X710500Y631725D01*
Y631392D01*
X710625Y631017D01*
X710833Y630725D01*
X711083Y630517D01*
X711500Y630350D01*
X711875Y630308D01*
X712250Y630392D01*
X712500Y630517D01*
X712750Y630767D01*
X712917Y631058D01*
X713000Y631350D01*
Y631642D01*
X712917Y631933D01*
X712792Y632183D01*
X712625Y632392D01*
G01X710917Y633658D02*
X710667Y633908D01*
X710542Y634200D01*
X710500Y634533D01*
X710583Y634950D01*
X710792Y635242D01*
X711042Y635325D01*
X711292Y635283D01*
X711500Y635117D01*
X711917Y634283D01*
X712208Y633908D01*
X712625Y633658D01*
X713000Y633575D01*
Y635325D01*
G01X712625Y636633D02*
X712833Y636883D01*
X712958Y637175D01*
X713000Y637550D01*
X712917Y637925D01*
X712750Y638217D01*
X712458Y638425D01*
X712125Y638467D01*
X711792Y638383D01*
X711583Y638175D01*
X711417Y637883D01*
X711375Y637592D01*
X711417Y637300D01*
X711583Y636925D01*
X710500Y637050D01*
Y638175D01*
G01X711958Y639858D02*
X711667Y640150D01*
X711500Y640400D01*
X711417Y640733D01*
X711500Y641025D01*
X711667Y641233D01*
X711917Y641400D01*
X712208Y641442D01*
X712458Y641400D01*
X712708Y641233D01*
X712917Y640983D01*
X713000Y640692D01*
X712917Y640358D01*
X712667Y640067D01*
X712292Y639900D01*
X711875Y639858D01*
X711333Y639942D01*
X711042Y640067D01*
X710750Y640275D01*
X710542Y640567D01*
X710500Y640858D01*
X710583Y641150D01*
X710792Y641358D01*
G01X750300Y615500D02*
Y613000D01*
G01X749342Y615500D02*
X751258D01*
G01X752567Y613000D02*
Y615500D01*
X753567D01*
X753900Y615375D01*
X754150Y615083D01*
X754233Y614750D01*
X754150Y614417D01*
X753942Y614167D01*
X753567Y614042D01*
X752567D01*
G01X756500Y613000D02*
Y615500D01*
X756000Y615000D01*
G01Y613000D02*
X757000D01*
G01X759600Y615500D02*
X759267Y615417D01*
X759017Y615208D01*
X758850Y614958D01*
X758725Y614625D01*
X758683Y614250D01*
X758725Y613875D01*
X758850Y613542D01*
X759017Y613292D01*
X759267Y613083D01*
X759600Y613000D01*
X759933Y613083D01*
X760183Y613292D01*
X760350Y613542D01*
X760475Y613875D01*
X760517Y614250D01*
X760475Y614625D01*
X760350Y614958D01*
X760183Y615208D01*
X759933Y615417D01*
X759600Y615500D01*
G01X761908Y614042D02*
X762200Y614333D01*
X762450Y614500D01*
X762783Y614583D01*
X763075Y614500D01*
X763283Y614333D01*
X763450Y614083D01*
X763492Y613792D01*
X763450Y613542D01*
X763283Y613292D01*
X763033Y613083D01*
X762742Y613000D01*
X762408Y613083D01*
X762117Y613333D01*
X761950Y613708D01*
X761908Y614125D01*
X761992Y614667D01*
X762117Y614958D01*
X762325Y615250D01*
X762617Y615458D01*
X762908Y615500D01*
X763200Y615417D01*
X763408Y615208D01*
G01X749200Y587617D02*
X746700D01*
Y588658D01*
X746825Y588992D01*
X746992Y589200D01*
X747325Y589283D01*
X747658Y589200D01*
X747867Y588950D01*
X747992Y588658D01*
Y587617D01*
G01Y588658D02*
X749200Y589283D01*
G01Y592050D02*
X746700D01*
X748492Y590508D01*
Y592592D01*
G01X748158Y593858D02*
X747867Y594150D01*
X747700Y594400D01*
X747617Y594733D01*
X747700Y595025D01*
X747867Y595233D01*
X748117Y595400D01*
X748408Y595442D01*
X748658Y595400D01*
X748908Y595233D01*
X749117Y594983D01*
X749200Y594692D01*
X749117Y594358D01*
X748867Y594067D01*
X748492Y593900D01*
X748075Y593858D01*
X747533Y593942D01*
X747242Y594067D01*
X746950Y594275D01*
X746742Y594567D01*
X746700Y594858D01*
X746783Y595150D01*
X746992Y595358D01*
G01X748825Y596833D02*
X749033Y597083D01*
X749158Y597375D01*
X749200Y597750D01*
X749117Y598125D01*
X748950Y598417D01*
X748658Y598625D01*
X748325Y598667D01*
X747992Y598583D01*
X747783Y598375D01*
X747617Y598083D01*
X747575Y597792D01*
X747617Y597500D01*
X747783Y597125D01*
X746700Y597250D01*
Y598375D01*
G01X693767Y604953D02*
X693517Y605078D01*
X693225Y605161D01*
X692892D01*
X692517Y605036D01*
X692225Y604828D01*
X692017Y604578D01*
X691850Y604161D01*
X691808Y603786D01*
X691892Y603411D01*
X692017Y603161D01*
X692267Y602911D01*
X692558Y602744D01*
X692850Y602661D01*
X693142D01*
X693433Y602744D01*
X693683Y602869D01*
X693892Y603036D01*
G01X695158Y604744D02*
X695408Y604994D01*
X695700Y605119D01*
X696033Y605161D01*
X696450Y605078D01*
X696742Y604869D01*
X696825Y604619D01*
X696783Y604369D01*
X696617Y604161D01*
X695783Y603744D01*
X695408Y603453D01*
X695158Y603036D01*
X695075Y602661D01*
X696825D01*
G01X698133Y603036D02*
X698383Y602828D01*
X698675Y602703D01*
X699050Y602661D01*
X699425Y602744D01*
X699717Y602911D01*
X699925Y603203D01*
X699967Y603536D01*
X699883Y603869D01*
X699675Y604078D01*
X699383Y604244D01*
X699092Y604286D01*
X698800Y604244D01*
X698425Y604078D01*
X698550Y605161D01*
X699675D01*
G01X701358Y604744D02*
X701608Y604994D01*
X701900Y605119D01*
X702233Y605161D01*
X702650Y605078D01*
X702942Y604869D01*
X703025Y604619D01*
X702983Y604369D01*
X702817Y604161D01*
X701983Y603744D01*
X701608Y603453D01*
X701358Y603036D01*
X701275Y602661D01*
X703025D01*
G01X708800Y574500D02*
X703300D01*
G01X708800Y582500D02*
Y574500D01*
G01X703300Y582500D02*
X708800D01*
G01X691200D02*
X696700D01*
G01X691200Y574500D02*
Y582500D01*
G01X696700Y574500D02*
X691200D01*
G01X716000Y593517D02*
X713500D01*
Y594558D01*
X713625Y594892D01*
X713792Y595100D01*
X714125Y595183D01*
X714458Y595100D01*
X714667Y594850D01*
X714792Y594558D01*
Y593517D01*
G01Y594558D02*
X716000Y595183D01*
G01Y597950D02*
X713500D01*
X715292Y596408D01*
Y598492D01*
G01X714958Y599758D02*
X714667Y600050D01*
X714500Y600300D01*
X714417Y600633D01*
X714500Y600925D01*
X714667Y601133D01*
X714917Y601300D01*
X715208Y601342D01*
X715458Y601300D01*
X715708Y601133D01*
X715917Y600883D01*
X716000Y600592D01*
X715917Y600258D01*
X715667Y599967D01*
X715292Y599800D01*
X714875Y599758D01*
X714333Y599842D01*
X714042Y599967D01*
X713750Y600175D01*
X713542Y600467D01*
X713500Y600758D01*
X713583Y601050D01*
X713792Y601258D01*
G01X713500Y603650D02*
X713583Y603317D01*
X713792Y603067D01*
X714042Y602900D01*
X714375Y602775D01*
X714750Y602733D01*
X715125Y602775D01*
X715458Y602900D01*
X715708Y603067D01*
X715917Y603317D01*
X716000Y603650D01*
X715917Y603983D01*
X715708Y604233D01*
X715458Y604400D01*
X715125Y604525D01*
X714750Y604567D01*
X714375Y604525D01*
X714042Y604400D01*
X713792Y604233D01*
X713583Y603983D01*
X713500Y603650D01*
G01X710500Y592300D02*
X718500D01*
Y574700D01*
X710500D01*
Y592300D01*
G01X692017Y611000D02*
Y613500D01*
X693058D01*
X693392Y613375D01*
X693600Y613208D01*
X693683Y612875D01*
X693600Y612542D01*
X693350Y612333D01*
X693058Y612208D01*
X692017D01*
G01X693058D02*
X693683Y611000D01*
G01X696450D02*
Y613500D01*
X694908Y611708D01*
X696992D01*
G01X698258Y612042D02*
X698550Y612333D01*
X698800Y612500D01*
X699133Y612583D01*
X699425Y612500D01*
X699633Y612333D01*
X699800Y612083D01*
X699842Y611792D01*
X699800Y611542D01*
X699633Y611292D01*
X699383Y611083D01*
X699092Y611000D01*
X698758Y611083D01*
X698467Y611333D01*
X698300Y611708D01*
X698258Y612125D01*
X698342Y612667D01*
X698467Y612958D01*
X698675Y613250D01*
X698967Y613458D01*
X699258Y613500D01*
X699550Y613417D01*
X699758Y613208D01*
G01X701358Y613083D02*
X701608Y613333D01*
X701900Y613458D01*
X702233Y613500D01*
X702650Y613417D01*
X702942Y613208D01*
X703025Y612958D01*
X702983Y612708D01*
X702817Y612500D01*
X701983Y612083D01*
X701608Y611792D01*
X701358Y611375D01*
X701275Y611000D01*
X703025D01*
G01X686700Y589000D02*
Y597000D01*
X704300D01*
Y589000D01*
X686700D01*
G01X707708Y619267D02*
X707583Y619017D01*
X707500Y618725D01*
Y618392D01*
X707625Y618017D01*
X707833Y617725D01*
X708083Y617517D01*
X708500Y617350D01*
X708875Y617308D01*
X709250Y617392D01*
X709500Y617517D01*
X709750Y617767D01*
X709917Y618058D01*
X710000Y618350D01*
Y618642D01*
X709917Y618933D01*
X709792Y619183D01*
X709625Y619392D01*
G01X707917Y620658D02*
X707667Y620908D01*
X707542Y621200D01*
X707500Y621533D01*
X707583Y621950D01*
X707792Y622242D01*
X708042Y622325D01*
X708292Y622283D01*
X708500Y622117D01*
X708917Y621283D01*
X709208Y620908D01*
X709625Y620658D01*
X710000Y620575D01*
Y622325D01*
G01X709625Y623633D02*
X709833Y623883D01*
X709958Y624175D01*
X710000Y624550D01*
X709917Y624925D01*
X709750Y625217D01*
X709458Y625425D01*
X709125Y625467D01*
X708792Y625383D01*
X708583Y625175D01*
X708417Y624883D01*
X708375Y624592D01*
X708417Y624300D01*
X708583Y623925D01*
X707500Y624050D01*
Y625175D01*
G01X709625Y626733D02*
X709833Y626983D01*
X709958Y627275D01*
X710000Y627650D01*
X709917Y628025D01*
X709750Y628317D01*
X709458Y628525D01*
X709125Y628567D01*
X708792Y628483D01*
X708583Y628275D01*
X708417Y627983D01*
X708375Y627692D01*
X708417Y627400D01*
X708583Y627025D01*
X707500Y627150D01*
Y628275D01*
G01X686017Y721000D02*
Y718500D01*
X687683D01*
G01X690783D02*
X689117D01*
Y721000D01*
X690783D01*
G01X690117Y719792D02*
X689117D01*
G01X692133Y718500D02*
Y721000D01*
X692967D01*
X693300Y720875D01*
X693550Y720708D01*
X693758Y720458D01*
X693925Y720167D01*
X693967Y719750D01*
X693925Y719333D01*
X693758Y719042D01*
X693550Y718792D01*
X693300Y718625D01*
X692967Y718500D01*
X692133D01*
G01X695358Y719542D02*
X695650Y719833D01*
X695900Y720000D01*
X696233Y720083D01*
X696525Y720000D01*
X696733Y719833D01*
X696900Y719583D01*
X696942Y719292D01*
X696900Y719042D01*
X696733Y718792D01*
X696483Y718583D01*
X696192Y718500D01*
X695858Y718583D01*
X695567Y718833D01*
X695400Y719208D01*
X695358Y719625D01*
X695442Y720167D01*
X695567Y720458D01*
X695775Y720750D01*
X696067Y720958D01*
X696358Y721000D01*
X696650Y720917D01*
X696858Y720708D01*
G01X686742Y704636D02*
Y715836D01*
X695542D01*
Y704636D01*
X686742D01*
G01X682200Y852217D02*
X679700D01*
Y853258D01*
X679825Y853592D01*
X679992Y853800D01*
X680325Y853883D01*
X680658Y853800D01*
X680867Y853550D01*
X680992Y853258D01*
Y852217D01*
G01Y853258D02*
X682200Y853883D01*
G01X680117Y855358D02*
X679867Y855608D01*
X679742Y855900D01*
X679700Y856233D01*
X679783Y856650D01*
X679992Y856942D01*
X680242Y857025D01*
X680492Y856983D01*
X680700Y856817D01*
X681117Y855983D01*
X681408Y855608D01*
X681825Y855358D01*
X682200Y855275D01*
Y857025D01*
G01Y859250D02*
X682158Y859542D01*
X682033Y859875D01*
X681825Y860083D01*
X681533Y860167D01*
X681242Y860083D01*
X680992Y859833D01*
X680867Y859458D01*
Y859042D01*
X680783Y858792D01*
X680575Y858583D01*
X680283Y858500D01*
X679992Y858625D01*
X679783Y858917D01*
X679700Y859250D01*
X679783Y859583D01*
X679992Y859875D01*
X680283Y860000D01*
X680575Y859917D01*
X680783Y859708D01*
X680867Y859458D01*
Y859042D01*
X680992Y858667D01*
X681242Y858417D01*
X681533Y858333D01*
X681825Y858417D01*
X682033Y858625D01*
X682158Y858958D01*
X682200Y859250D01*
G01Y862850D02*
X679700D01*
X681492Y861308D01*
Y863392D01*
G01X686200Y852217D02*
X683700D01*
Y853258D01*
X683825Y853592D01*
X683992Y853800D01*
X684325Y853883D01*
X684658Y853800D01*
X684867Y853550D01*
X684992Y853258D01*
Y852217D01*
G01Y853258D02*
X686200Y853883D01*
G01X684117Y855358D02*
X683867Y855608D01*
X683742Y855900D01*
X683700Y856233D01*
X683783Y856650D01*
X683992Y856942D01*
X684242Y857025D01*
X684492Y856983D01*
X684700Y856817D01*
X685117Y855983D01*
X685408Y855608D01*
X685825Y855358D01*
X686200Y855275D01*
Y857025D01*
G01Y859250D02*
X686158Y859542D01*
X686033Y859875D01*
X685825Y860083D01*
X685533Y860167D01*
X685242Y860083D01*
X684992Y859833D01*
X684867Y859458D01*
Y859042D01*
X684783Y858792D01*
X684575Y858583D01*
X684283Y858500D01*
X683992Y858625D01*
X683783Y858917D01*
X683700Y859250D01*
X683783Y859583D01*
X683992Y859875D01*
X684283Y860000D01*
X684575Y859917D01*
X684783Y859708D01*
X684867Y859458D01*
Y859042D01*
X684992Y858667D01*
X685242Y858417D01*
X685533Y858333D01*
X685825Y858417D01*
X686033Y858625D01*
X686158Y858958D01*
X686200Y859250D01*
G01X685825Y861433D02*
X686033Y861683D01*
X686158Y861975D01*
X686200Y862350D01*
X686117Y862725D01*
X685950Y863017D01*
X685658Y863225D01*
X685325Y863267D01*
X684992Y863183D01*
X684783Y862975D01*
X684617Y862683D01*
X684575Y862392D01*
X684617Y862100D01*
X684783Y861725D01*
X683700Y861850D01*
Y862975D01*
G01X677000Y838300D02*
Y852300D01*
G01X715187Y1012831D02*
X720237D01*
Y1111531D01*
X744887D01*
Y927131D01*
X720237D01*
Y985831D01*
X715187D01*
Y1012831D01*
G01X760317Y967292D02*
X760067Y967417D01*
X759775Y967500D01*
X759442D01*
X759067Y967375D01*
X758775Y967167D01*
X758567Y966917D01*
X758400Y966500D01*
X758358Y966125D01*
X758442Y965750D01*
X758567Y965500D01*
X758817Y965250D01*
X759108Y965083D01*
X759400Y965000D01*
X759692D01*
X759983Y965083D01*
X760233Y965208D01*
X760442Y965375D01*
G01X761792Y965292D02*
X762083Y965083D01*
X762417Y965000D01*
X762750Y965083D01*
X763042Y965333D01*
X763250Y965708D01*
X763333Y966083D01*
Y966542D01*
X763250Y966917D01*
X763042Y967250D01*
X762792Y967417D01*
X762500Y967500D01*
X762167Y967417D01*
X761917Y967250D01*
X761750Y967000D01*
X761667Y966667D01*
X761750Y966375D01*
X761958Y966083D01*
X762208Y965917D01*
X762500Y965875D01*
X762833Y965958D01*
X763083Y966167D01*
X763333Y966542D01*
G01X766100Y965000D02*
Y967500D01*
X764558Y965708D01*
X766642D01*
G01X760317Y963292D02*
X760067Y963417D01*
X759775Y963500D01*
X759442D01*
X759067Y963375D01*
X758775Y963167D01*
X758567Y962917D01*
X758400Y962500D01*
X758358Y962125D01*
X758442Y961750D01*
X758567Y961500D01*
X758817Y961250D01*
X759108Y961083D01*
X759400Y961000D01*
X759692D01*
X759983Y961083D01*
X760233Y961208D01*
X760442Y961375D01*
G01X761792Y961292D02*
X762083Y961083D01*
X762417Y961000D01*
X762750Y961083D01*
X763042Y961333D01*
X763250Y961708D01*
X763333Y962083D01*
Y962542D01*
X763250Y962917D01*
X763042Y963250D01*
X762792Y963417D01*
X762500Y963500D01*
X762167Y963417D01*
X761917Y963250D01*
X761750Y963000D01*
X761667Y962667D01*
X761750Y962375D01*
X761958Y962083D01*
X762208Y961917D01*
X762500Y961875D01*
X762833Y961958D01*
X763083Y962167D01*
X763333Y962542D01*
G01X764683Y961500D02*
X764933Y961208D01*
X765267Y961042D01*
X765642Y961000D01*
X765975Y961042D01*
X766308Y961250D01*
X766517Y961500D01*
X766558Y961750D01*
X766475Y962042D01*
X766183Y962250D01*
X765892Y962333D01*
X765517D01*
G01X765892D02*
X766142Y962458D01*
X766350Y962667D01*
X766433Y962917D01*
X766350Y963167D01*
X766142Y963375D01*
X765767Y963500D01*
X765392Y963458D01*
X765017Y963292D01*
G01X759567Y1033453D02*
X759317Y1033578D01*
X759025Y1033661D01*
X758692D01*
X758317Y1033536D01*
X758025Y1033328D01*
X757817Y1033078D01*
X757650Y1032661D01*
X757608Y1032286D01*
X757692Y1031911D01*
X757817Y1031661D01*
X758067Y1031411D01*
X758358Y1031244D01*
X758650Y1031161D01*
X758942D01*
X759233Y1031244D01*
X759483Y1031369D01*
X759692Y1031536D01*
G01X761750Y1031161D02*
Y1033661D01*
X761250Y1033161D01*
G01Y1031161D02*
X762250D01*
G01X764850Y1033661D02*
X764517Y1033578D01*
X764267Y1033369D01*
X764100Y1033119D01*
X763975Y1032786D01*
X763933Y1032411D01*
X763975Y1032036D01*
X764100Y1031703D01*
X764267Y1031453D01*
X764517Y1031244D01*
X764850Y1031161D01*
X765183Y1031244D01*
X765433Y1031453D01*
X765600Y1031703D01*
X765725Y1032036D01*
X765767Y1032411D01*
X765725Y1032786D01*
X765600Y1033119D01*
X765433Y1033369D01*
X765183Y1033578D01*
X764850Y1033661D01*
G01X767158Y1033244D02*
X767408Y1033494D01*
X767700Y1033619D01*
X768033Y1033661D01*
X768450Y1033578D01*
X768742Y1033369D01*
X768825Y1033119D01*
X768783Y1032869D01*
X768617Y1032661D01*
X767783Y1032244D01*
X767408Y1031953D01*
X767158Y1031536D01*
X767075Y1031161D01*
X768825D01*
G01X675800Y973000D02*
Y969000D01*
X683200D01*
G01Y1000000D02*
Y1004000D01*
X675800D01*
G01X679000Y973300D02*
X683000D01*
Y980700D01*
G01X694500Y956017D02*
X692000D01*
Y957058D01*
X692125Y957392D01*
X692292Y957600D01*
X692625Y957683D01*
X692958Y957600D01*
X693167Y957350D01*
X693292Y957058D01*
Y956017D01*
G01Y957058D02*
X694500Y957683D01*
G01X692417Y959158D02*
X692167Y959408D01*
X692042Y959700D01*
X692000Y960033D01*
X692083Y960450D01*
X692292Y960742D01*
X692542Y960825D01*
X692792Y960783D01*
X693000Y960617D01*
X693417Y959783D01*
X693708Y959408D01*
X694125Y959158D01*
X694500Y959075D01*
Y960825D01*
G01X694125Y962133D02*
X694333Y962383D01*
X694458Y962675D01*
X694500Y963050D01*
X694417Y963425D01*
X694250Y963717D01*
X693958Y963925D01*
X693625Y963967D01*
X693292Y963883D01*
X693083Y963675D01*
X692917Y963383D01*
X692875Y963092D01*
X692917Y962800D01*
X693083Y962425D01*
X692000Y962550D01*
Y963675D01*
G01X694500Y966150D02*
X692000D01*
X692500Y965650D01*
G01X694500D02*
Y966650D01*
G01X695500Y974700D02*
X691500D01*
Y967300D01*
G01X706017Y954000D02*
Y956500D01*
X707058D01*
X707392Y956375D01*
X707600Y956208D01*
X707683Y955875D01*
X707600Y955542D01*
X707350Y955333D01*
X707058Y955208D01*
X706017D01*
G01X707058D02*
X707683Y954000D01*
G01X709158Y956083D02*
X709408Y956333D01*
X709700Y956458D01*
X710033Y956500D01*
X710450Y956417D01*
X710742Y956208D01*
X710825Y955958D01*
X710783Y955708D01*
X710617Y955500D01*
X709783Y955083D01*
X709408Y954792D01*
X709158Y954375D01*
X709075Y954000D01*
X710825D01*
G01X713550D02*
Y956500D01*
X712008Y954708D01*
X714092D01*
G01X715358Y955042D02*
X715650Y955333D01*
X715900Y955500D01*
X716233Y955583D01*
X716525Y955500D01*
X716733Y955333D01*
X716900Y955083D01*
X716942Y954792D01*
X716900Y954542D01*
X716733Y954292D01*
X716483Y954083D01*
X716192Y954000D01*
X715858Y954083D01*
X715567Y954333D01*
X715400Y954708D01*
X715358Y955125D01*
X715442Y955667D01*
X715567Y955958D01*
X715775Y956250D01*
X716067Y956458D01*
X716358Y956500D01*
X716650Y956417D01*
X716858Y956208D01*
G01X712900Y967600D02*
Y971600D01*
X705500D01*
G01X706017Y958500D02*
Y961000D01*
X707058D01*
X707392Y960875D01*
X707600Y960708D01*
X707683Y960375D01*
X707600Y960042D01*
X707350Y959833D01*
X707058Y959708D01*
X706017D01*
G01X707058D02*
X707683Y958500D01*
G01X709158Y960583D02*
X709408Y960833D01*
X709700Y960958D01*
X710033Y961000D01*
X710450Y960917D01*
X710742Y960708D01*
X710825Y960458D01*
X710783Y960208D01*
X710617Y960000D01*
X709783Y959583D01*
X709408Y959292D01*
X709158Y958875D01*
X709075Y958500D01*
X710825D01*
G01X713550D02*
Y961000D01*
X712008Y959208D01*
X714092D01*
G01X716650Y958500D02*
Y961000D01*
X715108Y959208D01*
X717192D01*
G01X715300Y976300D02*
Y980300D01*
X707900D01*
G01X706017Y962500D02*
Y965000D01*
X707058D01*
X707392Y964875D01*
X707600Y964708D01*
X707683Y964375D01*
X707600Y964042D01*
X707350Y963833D01*
X707058Y963708D01*
X706017D01*
G01X707058D02*
X707683Y962500D01*
G01X709158Y964583D02*
X709408Y964833D01*
X709700Y964958D01*
X710033Y965000D01*
X710450Y964917D01*
X710742Y964708D01*
X710825Y964458D01*
X710783Y964208D01*
X710617Y964000D01*
X709783Y963583D01*
X709408Y963292D01*
X709158Y962875D01*
X709075Y962500D01*
X710825D01*
G01X713550D02*
Y965000D01*
X712008Y963208D01*
X714092D01*
G01X716067Y962500D02*
X716150Y963042D01*
X716275Y963500D01*
X716442Y963917D01*
X716650Y964375D01*
X716983Y965000D01*
X715317D01*
G01X707800Y984500D02*
Y980500D01*
X715200D01*
G01X683300Y998500D02*
Y994500D01*
X690700D01*
G01X757917Y1035161D02*
Y1037661D01*
X758958D01*
X759292Y1037536D01*
X759500Y1037369D01*
X759583Y1037036D01*
X759500Y1036703D01*
X759250Y1036494D01*
X758958Y1036369D01*
X757917D01*
G01X758958D02*
X759583Y1035161D01*
G01X761058Y1037244D02*
X761308Y1037494D01*
X761600Y1037619D01*
X761933Y1037661D01*
X762350Y1037578D01*
X762642Y1037369D01*
X762725Y1037119D01*
X762683Y1036869D01*
X762517Y1036661D01*
X761683Y1036244D01*
X761308Y1035953D01*
X761058Y1035536D01*
X760975Y1035161D01*
X762725D01*
G01X764033Y1035661D02*
X764283Y1035369D01*
X764617Y1035203D01*
X764992Y1035161D01*
X765325Y1035203D01*
X765658Y1035411D01*
X765867Y1035661D01*
X765908Y1035911D01*
X765825Y1036203D01*
X765533Y1036411D01*
X765242Y1036494D01*
X764867D01*
G01X765242D02*
X765492Y1036619D01*
X765700Y1036828D01*
X765783Y1037078D01*
X765700Y1037328D01*
X765492Y1037536D01*
X765117Y1037661D01*
X764742Y1037619D01*
X764367Y1037453D01*
G01X767342Y1035453D02*
X767633Y1035244D01*
X767967Y1035161D01*
X768300Y1035244D01*
X768592Y1035494D01*
X768800Y1035869D01*
X768883Y1036244D01*
Y1036703D01*
X768800Y1037078D01*
X768592Y1037411D01*
X768342Y1037578D01*
X768050Y1037661D01*
X767717Y1037578D01*
X767467Y1037411D01*
X767300Y1037161D01*
X767217Y1036828D01*
X767300Y1036536D01*
X767508Y1036244D01*
X767758Y1036078D01*
X768050Y1036036D01*
X768383Y1036119D01*
X768633Y1036328D01*
X768883Y1036703D01*
G01X755100Y1034000D02*
Y1038000D01*
X747700D01*
G01X699900Y1024000D02*
X699567Y1024042D01*
X699275Y1024208D01*
X699025Y1024458D01*
X698858Y1024750D01*
X698775Y1025083D01*
Y1025417D01*
X698858Y1025750D01*
X699025Y1026042D01*
X699275Y1026292D01*
X699567Y1026458D01*
X699900Y1026500D01*
X700233Y1026458D01*
X700525Y1026292D01*
X700775Y1026042D01*
X700942Y1025750D01*
X701025Y1025417D01*
Y1025083D01*
X700942Y1024750D01*
X700775Y1024458D01*
X700525Y1024208D01*
X700233Y1024042D01*
X699900Y1024000D01*
G01X700233Y1024667D02*
X700733Y1024000D01*
G01X703000D02*
Y1026500D01*
X702500Y1026000D01*
G01Y1024000D02*
X703500D01*
G01X706100D02*
X706392Y1024042D01*
X706725Y1024167D01*
X706933Y1024375D01*
X707017Y1024667D01*
X706933Y1024958D01*
X706683Y1025208D01*
X706308Y1025333D01*
X705892D01*
X705642Y1025417D01*
X705433Y1025625D01*
X705350Y1025917D01*
X705475Y1026208D01*
X705767Y1026417D01*
X706100Y1026500D01*
X706433Y1026417D01*
X706725Y1026208D01*
X706850Y1025917D01*
X706767Y1025625D01*
X706558Y1025417D01*
X706308Y1025333D01*
X705892D01*
X705517Y1025208D01*
X705267Y1024958D01*
X705183Y1024667D01*
X705267Y1024375D01*
X705475Y1024167D01*
X705808Y1024042D01*
X706100Y1024000D01*
G01X713200Y1007000D02*
X711100Y1008800D01*
X713200Y1011000D01*
G01X713300Y1014600D02*
X694100D01*
Y1003400D01*
X713300D01*
Y1014600D01*
X712900D01*
G01X749000Y1046017D02*
X746500D01*
Y1047058D01*
X746625Y1047392D01*
X746792Y1047600D01*
X747125Y1047683D01*
X747458Y1047600D01*
X747667Y1047350D01*
X747792Y1047058D01*
Y1046017D01*
G01Y1047058D02*
X749000Y1047683D01*
G01X746917Y1049158D02*
X746667Y1049408D01*
X746542Y1049700D01*
X746500Y1050033D01*
X746583Y1050450D01*
X746792Y1050742D01*
X747042Y1050825D01*
X747292Y1050783D01*
X747500Y1050617D01*
X747917Y1049783D01*
X748208Y1049408D01*
X748625Y1049158D01*
X749000Y1049075D01*
Y1050825D01*
G01Y1053550D02*
X746500D01*
X748292Y1052008D01*
Y1054092D01*
G01X749000Y1056150D02*
X746500D01*
X747000Y1055650D01*
G01X749000D02*
Y1056650D01*
G01X708800Y1027500D02*
X703300D01*
G01X708800Y1035500D02*
Y1027500D01*
G01X703300Y1035500D02*
X708800D01*
G01X691200D02*
X696700D01*
G01X691200Y1027500D02*
Y1035500D01*
G01X696700Y1027500D02*
X691200D01*
G01X688500Y961033D02*
X686000D01*
Y961867D01*
X686125Y962200D01*
X686292Y962450D01*
X686542Y962658D01*
X686833Y962825D01*
X687250Y962867D01*
X687667Y962825D01*
X687958Y962658D01*
X688208Y962450D01*
X688375Y962200D01*
X688500Y961867D01*
Y961033D01*
G01X688125Y964133D02*
X688333Y964383D01*
X688458Y964675D01*
X688500Y965050D01*
X688417Y965425D01*
X688250Y965717D01*
X687958Y965925D01*
X687625Y965967D01*
X687292Y965883D01*
X687083Y965675D01*
X686917Y965383D01*
X686875Y965092D01*
X686917Y964800D01*
X687083Y964425D01*
X686000Y964550D01*
Y965675D01*
G01X691000Y983500D02*
Y967400D01*
G01X684000Y983500D02*
X691000D01*
G01X684000Y967400D02*
Y983500D01*
G01X691000Y967400D02*
X684000D01*
G01X695000Y981900D02*
X694958Y981567D01*
X694792Y981275D01*
X694542Y981025D01*
X694250Y980858D01*
X693917Y980775D01*
X693583D01*
X693250Y980858D01*
X692958Y981025D01*
X692708Y981275D01*
X692542Y981567D01*
X692500Y981900D01*
X692542Y982233D01*
X692708Y982525D01*
X692958Y982775D01*
X693250Y982942D01*
X693583Y983025D01*
X693917D01*
X694250Y982942D01*
X694542Y982775D01*
X694792Y982525D01*
X694958Y982233D01*
X695000Y981900D01*
G01X694333Y982233D02*
X695000Y982733D01*
G01Y985000D02*
X692500D01*
X693000Y984500D01*
G01X695000D02*
Y985500D01*
G01X694708Y987392D02*
X694917Y987683D01*
X695000Y988017D01*
X694917Y988350D01*
X694667Y988642D01*
X694292Y988850D01*
X693917Y988933D01*
X693458D01*
X693083Y988850D01*
X692750Y988642D01*
X692583Y988392D01*
X692500Y988100D01*
X692583Y987767D01*
X692750Y987517D01*
X693000Y987350D01*
X693333Y987267D01*
X693625Y987350D01*
X693917Y987558D01*
X694083Y987808D01*
X694125Y988100D01*
X694042Y988433D01*
X693833Y988683D01*
X693458Y988933D01*
G01X707200Y989200D02*
X695800D01*
G01X707200Y975800D02*
Y989200D01*
G01X695800Y975800D02*
X707200D01*
G01X695800Y989200D02*
Y975800D01*
G01X715500Y1046517D02*
X713000D01*
Y1047558D01*
X713125Y1047892D01*
X713292Y1048100D01*
X713625Y1048183D01*
X713958Y1048100D01*
X714167Y1047850D01*
X714292Y1047558D01*
Y1046517D01*
G01Y1047558D02*
X715500Y1048183D01*
G01X713417Y1049658D02*
X713167Y1049908D01*
X713042Y1050200D01*
X713000Y1050533D01*
X713083Y1050950D01*
X713292Y1051242D01*
X713542Y1051325D01*
X713792Y1051283D01*
X714000Y1051117D01*
X714417Y1050283D01*
X714708Y1049908D01*
X715125Y1049658D01*
X715500Y1049575D01*
Y1051325D01*
G01X715000Y1052633D02*
X715292Y1052883D01*
X715458Y1053217D01*
X715500Y1053592D01*
X715458Y1053925D01*
X715250Y1054258D01*
X715000Y1054467D01*
X714750Y1054508D01*
X714458Y1054425D01*
X714250Y1054133D01*
X714167Y1053842D01*
Y1053467D01*
G01Y1053842D02*
X714042Y1054092D01*
X713833Y1054300D01*
X713583Y1054383D01*
X713333Y1054300D01*
X713125Y1054092D01*
X713000Y1053717D01*
X713042Y1053342D01*
X713208Y1052967D01*
G01X715500Y1056650D02*
X715458Y1056942D01*
X715333Y1057275D01*
X715125Y1057483D01*
X714833Y1057567D01*
X714542Y1057483D01*
X714292Y1057233D01*
X714167Y1056858D01*
Y1056442D01*
X714083Y1056192D01*
X713875Y1055983D01*
X713583Y1055900D01*
X713292Y1056025D01*
X713083Y1056317D01*
X713000Y1056650D01*
X713083Y1056983D01*
X713292Y1057275D01*
X713583Y1057400D01*
X713875Y1057317D01*
X714083Y1057108D01*
X714167Y1056858D01*
Y1056442D01*
X714292Y1056067D01*
X714542Y1055817D01*
X714833Y1055733D01*
X715125Y1055817D01*
X715333Y1056025D01*
X715458Y1056358D01*
X715500Y1056650D01*
G01X710500Y1045300D02*
X718500D01*
Y1027700D01*
X710500D01*
Y1045300D01*
G01X686700Y1042000D02*
Y1050000D01*
X704300D01*
Y1042000D01*
X686700D01*
G01X721325Y1113500D02*
Y1116000D01*
G01X723075D02*
Y1113500D01*
G01Y1114750D02*
X721325D01*
G01X724383Y1113500D02*
Y1116000D01*
X725217D01*
X725550Y1115875D01*
X725800Y1115708D01*
X726008Y1115458D01*
X726175Y1115167D01*
X726217Y1114750D01*
X726175Y1114333D01*
X726008Y1114042D01*
X725800Y1113792D01*
X725550Y1113625D01*
X725217Y1113500D01*
X724383D01*
G01X727483D02*
Y1116000D01*
X728317D01*
X728650Y1115875D01*
X728900Y1115708D01*
X729108Y1115458D01*
X729275Y1115167D01*
X729317Y1114750D01*
X729275Y1114333D01*
X729108Y1114042D01*
X728900Y1113792D01*
X728650Y1113625D01*
X728317Y1113500D01*
X727483D01*
G01X730625Y1113833D02*
X730958Y1113625D01*
X731333Y1113500D01*
X731667D01*
X732000Y1113625D01*
X732250Y1113833D01*
X732375Y1114125D01*
X732292Y1114417D01*
X732083Y1114667D01*
X731708Y1114833D01*
X731208Y1114917D01*
X730917Y1115083D01*
X730792Y1115375D01*
X730875Y1115667D01*
X731083Y1115875D01*
X731375Y1116000D01*
X731667D01*
X731958Y1115917D01*
X732208Y1115708D01*
G01X733558Y1113500D02*
X734600Y1116000D01*
X735642Y1113500D01*
G01X735267Y1114375D02*
X733933D01*
G01X736825Y1113833D02*
X737158Y1113625D01*
X737533Y1113500D01*
X737867D01*
X738200Y1113625D01*
X738450Y1113833D01*
X738575Y1114125D01*
X738492Y1114417D01*
X738283Y1114667D01*
X737908Y1114833D01*
X737408Y1114917D01*
X737117Y1115083D01*
X736992Y1115375D01*
X737075Y1115667D01*
X737283Y1115875D01*
X737575Y1116000D01*
X737867D01*
X738158Y1115917D01*
X738408Y1115708D01*
G01X739883Y1113875D02*
X740133Y1113667D01*
X740425Y1113542D01*
X740800Y1113500D01*
X741175Y1113583D01*
X741467Y1113750D01*
X741675Y1114042D01*
X741717Y1114375D01*
X741633Y1114708D01*
X741425Y1114917D01*
X741133Y1115083D01*
X740842Y1115125D01*
X740550Y1115083D01*
X740175Y1114917D01*
X740300Y1116000D01*
X741425D01*
G01X695317Y1057792D02*
X695067Y1057917D01*
X694775Y1058000D01*
X694442D01*
X694067Y1057875D01*
X693775Y1057667D01*
X693567Y1057417D01*
X693400Y1057000D01*
X693358Y1056625D01*
X693442Y1056250D01*
X693567Y1056000D01*
X693817Y1055750D01*
X694108Y1055583D01*
X694400Y1055500D01*
X694692D01*
X694983Y1055583D01*
X695233Y1055708D01*
X695442Y1055875D01*
G01X696792Y1055792D02*
X697083Y1055583D01*
X697417Y1055500D01*
X697750Y1055583D01*
X698042Y1055833D01*
X698250Y1056208D01*
X698333Y1056583D01*
Y1057042D01*
X698250Y1057417D01*
X698042Y1057750D01*
X697792Y1057917D01*
X697500Y1058000D01*
X697167Y1057917D01*
X696917Y1057750D01*
X696750Y1057500D01*
X696667Y1057167D01*
X696750Y1056875D01*
X696958Y1056583D01*
X697208Y1056417D01*
X697500Y1056375D01*
X697833Y1056458D01*
X698083Y1056667D01*
X698333Y1057042D01*
G01X699683Y1055875D02*
X699933Y1055667D01*
X700225Y1055542D01*
X700600Y1055500D01*
X700975Y1055583D01*
X701267Y1055750D01*
X701475Y1056042D01*
X701517Y1056375D01*
X701433Y1056708D01*
X701225Y1056917D01*
X700933Y1057083D01*
X700642Y1057125D01*
X700350Y1057083D01*
X699975Y1056917D01*
X700100Y1058000D01*
X701225D01*
G01X708208Y1087267D02*
X708083Y1087017D01*
X708000Y1086725D01*
Y1086392D01*
X708125Y1086017D01*
X708333Y1085725D01*
X708583Y1085517D01*
X709000Y1085350D01*
X709375Y1085308D01*
X709750Y1085392D01*
X710000Y1085517D01*
X710250Y1085767D01*
X710417Y1086058D01*
X710500Y1086350D01*
Y1086642D01*
X710417Y1086933D01*
X710292Y1087183D01*
X710125Y1087392D01*
G01X710500Y1089450D02*
X708000D01*
X708500Y1088950D01*
G01X710500D02*
Y1089950D01*
G01X708000Y1092550D02*
X708083Y1092217D01*
X708292Y1091967D01*
X708542Y1091800D01*
X708875Y1091675D01*
X709250Y1091633D01*
X709625Y1091675D01*
X709958Y1091800D01*
X710208Y1091967D01*
X710417Y1092217D01*
X710500Y1092550D01*
X710417Y1092883D01*
X710208Y1093133D01*
X709958Y1093300D01*
X709625Y1093425D01*
X709250Y1093467D01*
X708875Y1093425D01*
X708542Y1093300D01*
X708292Y1093133D01*
X708083Y1092883D01*
X708000Y1092550D01*
G01X710500Y1095650D02*
X708000D01*
X708500Y1095150D01*
G01X710500D02*
Y1096150D01*
G01X753350Y1068000D02*
Y1065500D01*
G01X752392Y1068000D02*
X754308D01*
G01X755617Y1065500D02*
Y1068000D01*
X756617D01*
X756950Y1067875D01*
X757200Y1067583D01*
X757283Y1067250D01*
X757200Y1066917D01*
X756992Y1066667D01*
X756617Y1066542D01*
X755617D01*
G01X760050Y1065500D02*
Y1068000D01*
X758508Y1066208D01*
X760592D01*
G01X761858Y1066542D02*
X762150Y1066833D01*
X762400Y1067000D01*
X762733Y1067083D01*
X763025Y1067000D01*
X763233Y1066833D01*
X763400Y1066583D01*
X763442Y1066292D01*
X763400Y1066042D01*
X763233Y1065792D01*
X762983Y1065583D01*
X762692Y1065500D01*
X762358Y1065583D01*
X762067Y1065833D01*
X761900Y1066208D01*
X761858Y1066625D01*
X761942Y1067167D01*
X762067Y1067458D01*
X762275Y1067750D01*
X762567Y1067958D01*
X762858Y1068000D01*
X763150Y1067917D01*
X763358Y1067708D01*
G01X695317Y1053792D02*
X695067Y1053917D01*
X694775Y1054000D01*
X694442D01*
X694067Y1053875D01*
X693775Y1053667D01*
X693567Y1053417D01*
X693400Y1053000D01*
X693358Y1052625D01*
X693442Y1052250D01*
X693567Y1052000D01*
X693817Y1051750D01*
X694108Y1051583D01*
X694400Y1051500D01*
X694692D01*
X694983Y1051583D01*
X695233Y1051708D01*
X695442Y1051875D01*
G01X696792Y1051792D02*
X697083Y1051583D01*
X697417Y1051500D01*
X697750Y1051583D01*
X698042Y1051833D01*
X698250Y1052208D01*
X698333Y1052583D01*
Y1053042D01*
X698250Y1053417D01*
X698042Y1053750D01*
X697792Y1053917D01*
X697500Y1054000D01*
X697167Y1053917D01*
X696917Y1053750D01*
X696750Y1053500D01*
X696667Y1053167D01*
X696750Y1052875D01*
X696958Y1052583D01*
X697208Y1052417D01*
X697500Y1052375D01*
X697833Y1052458D01*
X698083Y1052667D01*
X698333Y1053042D01*
G01X699808Y1052542D02*
X700100Y1052833D01*
X700350Y1053000D01*
X700683Y1053083D01*
X700975Y1053000D01*
X701183Y1052833D01*
X701350Y1052583D01*
X701392Y1052292D01*
X701350Y1052042D01*
X701183Y1051792D01*
X700933Y1051583D01*
X700642Y1051500D01*
X700308Y1051583D01*
X700017Y1051833D01*
X699850Y1052208D01*
X699808Y1052625D01*
X699892Y1053167D01*
X700017Y1053458D01*
X700225Y1053750D01*
X700517Y1053958D01*
X700808Y1054000D01*
X701100Y1053917D01*
X701308Y1053708D01*
G01X693517Y1059500D02*
Y1062000D01*
X694558D01*
X694892Y1061875D01*
X695100Y1061708D01*
X695183Y1061375D01*
X695100Y1061042D01*
X694850Y1060833D01*
X694558Y1060708D01*
X693517D01*
G01X694558D02*
X695183Y1059500D01*
G01X696658Y1061583D02*
X696908Y1061833D01*
X697200Y1061958D01*
X697533Y1062000D01*
X697950Y1061917D01*
X698242Y1061708D01*
X698325Y1061458D01*
X698283Y1061208D01*
X698117Y1061000D01*
X697283Y1060583D01*
X696908Y1060292D01*
X696658Y1059875D01*
X696575Y1059500D01*
X698325D01*
G01X701050D02*
Y1062000D01*
X699508Y1060208D01*
X701592D01*
G01X703650Y1062000D02*
X703317Y1061917D01*
X703067Y1061708D01*
X702900Y1061458D01*
X702775Y1061125D01*
X702733Y1060750D01*
X702775Y1060375D01*
X702900Y1060042D01*
X703067Y1059792D01*
X703317Y1059583D01*
X703650Y1059500D01*
X703983Y1059583D01*
X704233Y1059792D01*
X704400Y1060042D01*
X704525Y1060375D01*
X704567Y1060750D01*
X704525Y1061125D01*
X704400Y1061458D01*
X704233Y1061708D01*
X703983Y1061917D01*
X703650Y1062000D01*
G01X708347Y1072767D02*
X708222Y1072517D01*
X708139Y1072225D01*
Y1071892D01*
X708264Y1071517D01*
X708472Y1071225D01*
X708722Y1071017D01*
X709139Y1070850D01*
X709514Y1070808D01*
X709889Y1070892D01*
X710139Y1071017D01*
X710389Y1071267D01*
X710556Y1071558D01*
X710639Y1071850D01*
Y1072142D01*
X710556Y1072433D01*
X710431Y1072683D01*
X710264Y1072892D01*
G01X710639Y1074950D02*
X708139D01*
X708639Y1074450D01*
G01X710639D02*
Y1075450D01*
G01X708139Y1078050D02*
X708222Y1077717D01*
X708431Y1077467D01*
X708681Y1077300D01*
X709014Y1077175D01*
X709389Y1077133D01*
X709764Y1077175D01*
X710097Y1077300D01*
X710347Y1077467D01*
X710556Y1077717D01*
X710639Y1078050D01*
X710556Y1078383D01*
X710347Y1078633D01*
X710097Y1078800D01*
X709764Y1078925D01*
X709389Y1078967D01*
X709014Y1078925D01*
X708681Y1078800D01*
X708431Y1078633D01*
X708222Y1078383D01*
X708139Y1078050D01*
G01Y1081150D02*
X708222Y1080817D01*
X708431Y1080567D01*
X708681Y1080400D01*
X709014Y1080275D01*
X709389Y1080233D01*
X709764Y1080275D01*
X710097Y1080400D01*
X710347Y1080567D01*
X710556Y1080817D01*
X710639Y1081150D01*
X710556Y1081483D01*
X710347Y1081733D01*
X710097Y1081900D01*
X709764Y1082025D01*
X709389Y1082067D01*
X709014Y1082025D01*
X708681Y1081900D01*
X708431Y1081733D01*
X708222Y1081483D01*
X708139Y1081150D01*
G01X731383Y1398109D02*
X731258Y1397859D01*
X731175Y1397567D01*
Y1397234D01*
X731300Y1396859D01*
X731508Y1396567D01*
X731758Y1396359D01*
X732175Y1396192D01*
X732550Y1396150D01*
X732925Y1396234D01*
X733175Y1396359D01*
X733425Y1396609D01*
X733592Y1396900D01*
X733675Y1397192D01*
Y1397484D01*
X733592Y1397775D01*
X733467Y1398025D01*
X733300Y1398234D01*
G01Y1399375D02*
X733508Y1399625D01*
X733633Y1399917D01*
X733675Y1400292D01*
X733592Y1400667D01*
X733425Y1400959D01*
X733133Y1401167D01*
X732800Y1401209D01*
X732467Y1401125D01*
X732258Y1400917D01*
X732092Y1400625D01*
X732050Y1400334D01*
X732092Y1400042D01*
X732258Y1399667D01*
X731175Y1399792D01*
Y1400917D01*
G01X733675Y1403892D02*
X731175D01*
X732967Y1402350D01*
Y1404434D01*
G01X731175Y1406492D02*
X731258Y1406159D01*
X731467Y1405909D01*
X731717Y1405742D01*
X732050Y1405617D01*
X732425Y1405575D01*
X732800Y1405617D01*
X733133Y1405742D01*
X733383Y1405909D01*
X733592Y1406159D01*
X733675Y1406492D01*
X733592Y1406825D01*
X733383Y1407075D01*
X733133Y1407242D01*
X732800Y1407367D01*
X732425Y1407409D01*
X732050Y1407367D01*
X731717Y1407242D01*
X731467Y1407075D01*
X731258Y1406825D01*
X731175Y1406492D01*
G01X703597Y1398120D02*
X703472Y1397870D01*
X703389Y1397578D01*
Y1397245D01*
X703514Y1396870D01*
X703722Y1396578D01*
X703972Y1396370D01*
X704389Y1396203D01*
X704764Y1396161D01*
X705139Y1396245D01*
X705389Y1396370D01*
X705639Y1396620D01*
X705806Y1396911D01*
X705889Y1397203D01*
Y1397495D01*
X705806Y1397786D01*
X705681Y1398036D01*
X705514Y1398245D01*
G01Y1399386D02*
X705722Y1399636D01*
X705847Y1399928D01*
X705889Y1400303D01*
X705806Y1400678D01*
X705639Y1400970D01*
X705347Y1401178D01*
X705014Y1401220D01*
X704681Y1401136D01*
X704472Y1400928D01*
X704306Y1400636D01*
X704264Y1400345D01*
X704306Y1400053D01*
X704472Y1399678D01*
X703389Y1399803D01*
Y1400928D01*
G01X705889Y1403903D02*
X703389D01*
X705181Y1402361D01*
Y1404445D01*
G01X705514Y1405586D02*
X705722Y1405836D01*
X705847Y1406128D01*
X705889Y1406503D01*
X705806Y1406878D01*
X705639Y1407170D01*
X705347Y1407378D01*
X705014Y1407420D01*
X704681Y1407336D01*
X704472Y1407128D01*
X704306Y1406836D01*
X704264Y1406545D01*
X704306Y1406253D01*
X704472Y1405878D01*
X703389Y1406003D01*
Y1407128D01*
G01X719383Y1398109D02*
X719258Y1397859D01*
X719175Y1397567D01*
Y1397234D01*
X719300Y1396859D01*
X719508Y1396567D01*
X719758Y1396359D01*
X720175Y1396192D01*
X720550Y1396150D01*
X720925Y1396234D01*
X721175Y1396359D01*
X721425Y1396609D01*
X721592Y1396900D01*
X721675Y1397192D01*
Y1397484D01*
X721592Y1397775D01*
X721467Y1398025D01*
X721300Y1398234D01*
G01Y1399375D02*
X721508Y1399625D01*
X721633Y1399917D01*
X721675Y1400292D01*
X721592Y1400667D01*
X721425Y1400959D01*
X721133Y1401167D01*
X720800Y1401209D01*
X720467Y1401125D01*
X720258Y1400917D01*
X720092Y1400625D01*
X720050Y1400334D01*
X720092Y1400042D01*
X720258Y1399667D01*
X719175Y1399792D01*
Y1400917D01*
G01X721675Y1403892D02*
X719175D01*
X720967Y1402350D01*
Y1404434D01*
G01X720633Y1405700D02*
X720342Y1405992D01*
X720175Y1406242D01*
X720092Y1406575D01*
X720175Y1406867D01*
X720342Y1407075D01*
X720592Y1407242D01*
X720883Y1407284D01*
X721133Y1407242D01*
X721383Y1407075D01*
X721592Y1406825D01*
X721675Y1406534D01*
X721592Y1406200D01*
X721342Y1405909D01*
X720967Y1405742D01*
X720550Y1405700D01*
X720008Y1405784D01*
X719717Y1405909D01*
X719425Y1406117D01*
X719217Y1406409D01*
X719175Y1406700D01*
X719258Y1406992D01*
X719467Y1407200D01*
G01X727383Y1398109D02*
X727258Y1397859D01*
X727175Y1397567D01*
Y1397234D01*
X727300Y1396859D01*
X727508Y1396567D01*
X727758Y1396359D01*
X728175Y1396192D01*
X728550Y1396150D01*
X728925Y1396234D01*
X729175Y1396359D01*
X729425Y1396609D01*
X729592Y1396900D01*
X729675Y1397192D01*
Y1397484D01*
X729592Y1397775D01*
X729467Y1398025D01*
X729300Y1398234D01*
G01Y1399375D02*
X729508Y1399625D01*
X729633Y1399917D01*
X729675Y1400292D01*
X729592Y1400667D01*
X729425Y1400959D01*
X729133Y1401167D01*
X728800Y1401209D01*
X728467Y1401125D01*
X728258Y1400917D01*
X728092Y1400625D01*
X728050Y1400334D01*
X728092Y1400042D01*
X728258Y1399667D01*
X727175Y1399792D01*
Y1400917D01*
G01X729675Y1403892D02*
X727175D01*
X728967Y1402350D01*
Y1404434D01*
G01X729675Y1406492D02*
X729633Y1406784D01*
X729508Y1407117D01*
X729300Y1407325D01*
X729008Y1407409D01*
X728717Y1407325D01*
X728467Y1407075D01*
X728342Y1406700D01*
Y1406284D01*
X728258Y1406034D01*
X728050Y1405825D01*
X727758Y1405742D01*
X727467Y1405867D01*
X727258Y1406159D01*
X727175Y1406492D01*
X727258Y1406825D01*
X727467Y1407117D01*
X727758Y1407242D01*
X728050Y1407159D01*
X728258Y1406950D01*
X728342Y1406700D01*
Y1406284D01*
X728467Y1405909D01*
X728717Y1405659D01*
X729008Y1405575D01*
X729300Y1405659D01*
X729508Y1405867D01*
X729633Y1406200D01*
X729675Y1406492D01*
G01X716367Y1429292D02*
X716117Y1429417D01*
X715825Y1429500D01*
X715492D01*
X715117Y1429375D01*
X714825Y1429167D01*
X714617Y1428917D01*
X714450Y1428500D01*
X714408Y1428125D01*
X714492Y1427750D01*
X714617Y1427500D01*
X714867Y1427250D01*
X715158Y1427083D01*
X715450Y1427000D01*
X715742D01*
X716033Y1427083D01*
X716283Y1427208D01*
X716492Y1427375D01*
G01X718550Y1427000D02*
Y1429500D01*
X718050Y1429000D01*
G01Y1427000D02*
X719050D01*
G01X711517Y1423000D02*
Y1425500D01*
X712558D01*
X712892Y1425375D01*
X713100Y1425208D01*
X713183Y1424875D01*
X713100Y1424542D01*
X712850Y1424333D01*
X712558Y1424208D01*
X711517D01*
G01X712558D02*
X713183Y1423000D01*
G01X714742Y1423292D02*
X715033Y1423083D01*
X715367Y1423000D01*
X715700Y1423083D01*
X715992Y1423333D01*
X716200Y1423708D01*
X716283Y1424083D01*
Y1424542D01*
X716200Y1424917D01*
X715992Y1425250D01*
X715742Y1425417D01*
X715450Y1425500D01*
X715117Y1425417D01*
X714867Y1425250D01*
X714700Y1425000D01*
X714617Y1424667D01*
X714700Y1424375D01*
X714908Y1424083D01*
X715158Y1423917D01*
X715450Y1423875D01*
X715783Y1423958D01*
X716033Y1424167D01*
X716283Y1424542D01*
G01X717842Y1423292D02*
X718133Y1423083D01*
X718467Y1423000D01*
X718800Y1423083D01*
X719092Y1423333D01*
X719300Y1423708D01*
X719383Y1424083D01*
Y1424542D01*
X719300Y1424917D01*
X719092Y1425250D01*
X718842Y1425417D01*
X718550Y1425500D01*
X718217Y1425417D01*
X717967Y1425250D01*
X717800Y1425000D01*
X717717Y1424667D01*
X717800Y1424375D01*
X718008Y1424083D01*
X718258Y1423917D01*
X718550Y1423875D01*
X718883Y1423958D01*
X719133Y1424167D01*
X719383Y1424542D01*
G01X720733Y1423500D02*
X720983Y1423208D01*
X721317Y1423042D01*
X721692Y1423000D01*
X722025Y1423042D01*
X722358Y1423250D01*
X722567Y1423500D01*
X722608Y1423750D01*
X722525Y1424042D01*
X722233Y1424250D01*
X721942Y1424333D01*
X721567D01*
G01X721942D02*
X722192Y1424458D01*
X722400Y1424667D01*
X722483Y1424917D01*
X722400Y1425167D01*
X722192Y1425375D01*
X721817Y1425500D01*
X721442Y1425458D01*
X721067Y1425292D01*
G01X724517Y1427000D02*
Y1429500D01*
X725558D01*
X725892Y1429375D01*
X726100Y1429208D01*
X726183Y1428875D01*
X726100Y1428542D01*
X725850Y1428333D01*
X725558Y1428208D01*
X724517D01*
G01X725558D02*
X726183Y1427000D01*
G01X727742Y1427292D02*
X728033Y1427083D01*
X728367Y1427000D01*
X728700Y1427083D01*
X728992Y1427333D01*
X729200Y1427708D01*
X729283Y1428083D01*
Y1428542D01*
X729200Y1428917D01*
X728992Y1429250D01*
X728742Y1429417D01*
X728450Y1429500D01*
X728117Y1429417D01*
X727867Y1429250D01*
X727700Y1429000D01*
X727617Y1428667D01*
X727700Y1428375D01*
X727908Y1428083D01*
X728158Y1427917D01*
X728450Y1427875D01*
X728783Y1427958D01*
X729033Y1428167D01*
X729283Y1428542D01*
G01X731550Y1427000D02*
X731842Y1427042D01*
X732175Y1427167D01*
X732383Y1427375D01*
X732467Y1427667D01*
X732383Y1427958D01*
X732133Y1428208D01*
X731758Y1428333D01*
X731342D01*
X731092Y1428417D01*
X730883Y1428625D01*
X730800Y1428917D01*
X730925Y1429208D01*
X731217Y1429417D01*
X731550Y1429500D01*
X731883Y1429417D01*
X732175Y1429208D01*
X732300Y1428917D01*
X732217Y1428625D01*
X732008Y1428417D01*
X731758Y1428333D01*
X731342D01*
X730967Y1428208D01*
X730717Y1427958D01*
X730633Y1427667D01*
X730717Y1427375D01*
X730925Y1427167D01*
X731258Y1427042D01*
X731550Y1427000D01*
G01X733942Y1427292D02*
X734233Y1427083D01*
X734567Y1427000D01*
X734900Y1427083D01*
X735192Y1427333D01*
X735400Y1427708D01*
X735483Y1428083D01*
Y1428542D01*
X735400Y1428917D01*
X735192Y1429250D01*
X734942Y1429417D01*
X734650Y1429500D01*
X734317Y1429417D01*
X734067Y1429250D01*
X733900Y1429000D01*
X733817Y1428667D01*
X733900Y1428375D01*
X734108Y1428083D01*
X734358Y1427917D01*
X734650Y1427875D01*
X734983Y1427958D01*
X735233Y1428167D01*
X735483Y1428542D01*
G01X704653Y1412889D02*
Y1415389D01*
X705694D01*
X706028Y1415264D01*
X706236Y1415097D01*
X706319Y1414764D01*
X706236Y1414431D01*
X705986Y1414222D01*
X705694Y1414097D01*
X704653D01*
G01X705694D02*
X706319Y1412889D01*
G01X708586D02*
Y1415389D01*
X708086Y1414889D01*
G01Y1412889D02*
X709086D01*
G01X711686Y1415389D02*
X711353Y1415306D01*
X711103Y1415097D01*
X710936Y1414847D01*
X710811Y1414514D01*
X710769Y1414139D01*
X710811Y1413764D01*
X710936Y1413431D01*
X711103Y1413181D01*
X711353Y1412972D01*
X711686Y1412889D01*
X712019Y1412972D01*
X712269Y1413181D01*
X712436Y1413431D01*
X712561Y1413764D01*
X712603Y1414139D01*
X712561Y1414514D01*
X712436Y1414847D01*
X712269Y1415097D01*
X712019Y1415306D01*
X711686Y1415389D01*
G01X714786D02*
X714453Y1415306D01*
X714203Y1415097D01*
X714036Y1414847D01*
X713911Y1414514D01*
X713869Y1414139D01*
X713911Y1413764D01*
X714036Y1413431D01*
X714203Y1413181D01*
X714453Y1412972D01*
X714786Y1412889D01*
X715119Y1412972D01*
X715369Y1413181D01*
X715536Y1413431D01*
X715661Y1413764D01*
X715703Y1414139D01*
X715661Y1414514D01*
X715536Y1414847D01*
X715369Y1415097D01*
X715119Y1415306D01*
X714786Y1415389D01*
G01X716969Y1413264D02*
X717219Y1413056D01*
X717511Y1412931D01*
X717886Y1412889D01*
X718261Y1412972D01*
X718553Y1413139D01*
X718761Y1413431D01*
X718803Y1413764D01*
X718719Y1414097D01*
X718511Y1414306D01*
X718219Y1414472D01*
X717928Y1414514D01*
X717636Y1414472D01*
X717261Y1414306D01*
X717386Y1415389D01*
X718511D01*
G01X679300Y1432000D02*
Y1428000D01*
X686700D01*
G01X725675Y1396359D02*
X723175D01*
Y1397400D01*
X723300Y1397734D01*
X723467Y1397942D01*
X723800Y1398025D01*
X724133Y1397942D01*
X724342Y1397692D01*
X724467Y1397400D01*
Y1396359D01*
G01Y1397400D02*
X725675Y1398025D01*
G01Y1400292D02*
X723175D01*
X723675Y1399792D01*
G01X725675D02*
Y1400792D01*
G01X723175Y1403392D02*
X723258Y1403059D01*
X723467Y1402809D01*
X723717Y1402642D01*
X724050Y1402517D01*
X724425Y1402475D01*
X724800Y1402517D01*
X725133Y1402642D01*
X725383Y1402809D01*
X725592Y1403059D01*
X725675Y1403392D01*
X725592Y1403725D01*
X725383Y1403975D01*
X725133Y1404142D01*
X724800Y1404267D01*
X724425Y1404309D01*
X724050Y1404267D01*
X723717Y1404142D01*
X723467Y1403975D01*
X723258Y1403725D01*
X723175Y1403392D01*
G01Y1406492D02*
X723258Y1406159D01*
X723467Y1405909D01*
X723717Y1405742D01*
X724050Y1405617D01*
X724425Y1405575D01*
X724800Y1405617D01*
X725133Y1405742D01*
X725383Y1405909D01*
X725592Y1406159D01*
X725675Y1406492D01*
X725592Y1406825D01*
X725383Y1407075D01*
X725133Y1407242D01*
X724800Y1407367D01*
X724425Y1407409D01*
X724050Y1407367D01*
X723717Y1407242D01*
X723467Y1407075D01*
X723258Y1406825D01*
X723175Y1406492D01*
G01X725675Y1409592D02*
X725633Y1409884D01*
X725508Y1410217D01*
X725300Y1410425D01*
X725008Y1410509D01*
X724717Y1410425D01*
X724467Y1410175D01*
X724342Y1409800D01*
Y1409384D01*
X724258Y1409134D01*
X724050Y1408925D01*
X723758Y1408842D01*
X723467Y1408967D01*
X723258Y1409259D01*
X723175Y1409592D01*
X723258Y1409925D01*
X723467Y1410217D01*
X723758Y1410342D01*
X724050Y1410259D01*
X724258Y1410050D01*
X724342Y1409800D01*
Y1409384D01*
X724467Y1409009D01*
X724717Y1408759D01*
X725008Y1408675D01*
X725300Y1408759D01*
X725508Y1408967D01*
X725633Y1409300D01*
X725675Y1409592D01*
G01X691000Y1427700D02*
X687000D01*
Y1420300D01*
G01X717675Y1396359D02*
X715175D01*
Y1397400D01*
X715300Y1397734D01*
X715467Y1397942D01*
X715800Y1398025D01*
X716133Y1397942D01*
X716342Y1397692D01*
X716467Y1397400D01*
Y1396359D01*
G01Y1397400D02*
X717675Y1398025D01*
G01Y1400292D02*
X715175D01*
X715675Y1399792D01*
G01X717675D02*
Y1400792D01*
G01X715175Y1403392D02*
X715258Y1403059D01*
X715467Y1402809D01*
X715717Y1402642D01*
X716050Y1402517D01*
X716425Y1402475D01*
X716800Y1402517D01*
X717133Y1402642D01*
X717383Y1402809D01*
X717592Y1403059D01*
X717675Y1403392D01*
X717592Y1403725D01*
X717383Y1403975D01*
X717133Y1404142D01*
X716800Y1404267D01*
X716425Y1404309D01*
X716050Y1404267D01*
X715717Y1404142D01*
X715467Y1403975D01*
X715258Y1403725D01*
X715175Y1403392D01*
G01Y1406492D02*
X715258Y1406159D01*
X715467Y1405909D01*
X715717Y1405742D01*
X716050Y1405617D01*
X716425Y1405575D01*
X716800Y1405617D01*
X717133Y1405742D01*
X717383Y1405909D01*
X717592Y1406159D01*
X717675Y1406492D01*
X717592Y1406825D01*
X717383Y1407075D01*
X717133Y1407242D01*
X716800Y1407367D01*
X716425Y1407409D01*
X716050Y1407367D01*
X715717Y1407242D01*
X715467Y1407075D01*
X715258Y1406825D01*
X715175Y1406492D01*
G01X716633Y1408800D02*
X716342Y1409092D01*
X716175Y1409342D01*
X716092Y1409675D01*
X716175Y1409967D01*
X716342Y1410175D01*
X716592Y1410342D01*
X716883Y1410384D01*
X717133Y1410342D01*
X717383Y1410175D01*
X717592Y1409925D01*
X717675Y1409634D01*
X717592Y1409300D01*
X717342Y1409009D01*
X716967Y1408842D01*
X716550Y1408800D01*
X716008Y1408884D01*
X715717Y1409009D01*
X715425Y1409217D01*
X715217Y1409509D01*
X715175Y1409800D01*
X715258Y1410092D01*
X715467Y1410300D01*
G01X683000Y1427700D02*
X679000D01*
Y1420300D01*
G01X687653Y1412889D02*
Y1415389D01*
X688694D01*
X689028Y1415264D01*
X689236Y1415097D01*
X689319Y1414764D01*
X689236Y1414431D01*
X688986Y1414222D01*
X688694Y1414097D01*
X687653D01*
G01X688694D02*
X689319Y1412889D01*
G01X691586D02*
Y1415389D01*
X691086Y1414889D01*
G01Y1412889D02*
X692086D01*
G01X694686Y1415389D02*
X694353Y1415306D01*
X694103Y1415097D01*
X693936Y1414847D01*
X693811Y1414514D01*
X693769Y1414139D01*
X693811Y1413764D01*
X693936Y1413431D01*
X694103Y1413181D01*
X694353Y1412972D01*
X694686Y1412889D01*
X695019Y1412972D01*
X695269Y1413181D01*
X695436Y1413431D01*
X695561Y1413764D01*
X695603Y1414139D01*
X695561Y1414514D01*
X695436Y1414847D01*
X695269Y1415097D01*
X695019Y1415306D01*
X694686Y1415389D01*
G01X697786D02*
X697453Y1415306D01*
X697203Y1415097D01*
X697036Y1414847D01*
X696911Y1414514D01*
X696869Y1414139D01*
X696911Y1413764D01*
X697036Y1413431D01*
X697203Y1413181D01*
X697453Y1412972D01*
X697786Y1412889D01*
X698119Y1412972D01*
X698369Y1413181D01*
X698536Y1413431D01*
X698661Y1413764D01*
X698703Y1414139D01*
X698661Y1414514D01*
X698536Y1414847D01*
X698369Y1415097D01*
X698119Y1415306D01*
X697786Y1415389D01*
G01X699969Y1413389D02*
X700219Y1413097D01*
X700553Y1412931D01*
X700928Y1412889D01*
X701261Y1412931D01*
X701594Y1413139D01*
X701803Y1413389D01*
X701844Y1413639D01*
X701761Y1413931D01*
X701469Y1414139D01*
X701178Y1414222D01*
X700803D01*
G01X701178D02*
X701428Y1414347D01*
X701636Y1414556D01*
X701719Y1414806D01*
X701636Y1415056D01*
X701428Y1415264D01*
X701053Y1415389D01*
X700678Y1415347D01*
X700303Y1415181D01*
G01X721653Y1412989D02*
Y1415489D01*
X722694D01*
X723028Y1415364D01*
X723236Y1415197D01*
X723319Y1414864D01*
X723236Y1414531D01*
X722986Y1414322D01*
X722694Y1414197D01*
X721653D01*
G01X722694D02*
X723319Y1412989D01*
G01X725586D02*
Y1415489D01*
X725086Y1414989D01*
G01Y1412989D02*
X726086D01*
G01X728686Y1415489D02*
X728353Y1415406D01*
X728103Y1415197D01*
X727936Y1414947D01*
X727811Y1414614D01*
X727769Y1414239D01*
X727811Y1413864D01*
X727936Y1413531D01*
X728103Y1413281D01*
X728353Y1413072D01*
X728686Y1412989D01*
X729019Y1413072D01*
X729269Y1413281D01*
X729436Y1413531D01*
X729561Y1413864D01*
X729603Y1414239D01*
X729561Y1414614D01*
X729436Y1414947D01*
X729269Y1415197D01*
X729019Y1415406D01*
X728686Y1415489D01*
G01X731786D02*
X731453Y1415406D01*
X731203Y1415197D01*
X731036Y1414947D01*
X730911Y1414614D01*
X730869Y1414239D01*
X730911Y1413864D01*
X731036Y1413531D01*
X731203Y1413281D01*
X731453Y1413072D01*
X731786Y1412989D01*
X732119Y1413072D01*
X732369Y1413281D01*
X732536Y1413531D01*
X732661Y1413864D01*
X732703Y1414239D01*
X732661Y1414614D01*
X732536Y1414947D01*
X732369Y1415197D01*
X732119Y1415406D01*
X731786Y1415489D01*
G01X734803Y1412989D02*
X734886Y1413531D01*
X735011Y1413989D01*
X735178Y1414406D01*
X735386Y1414864D01*
X735719Y1415489D01*
X734053D01*
G01X687300Y1432000D02*
Y1428000D01*
X694700D01*
G01X716017Y1418500D02*
Y1421000D01*
X717058D01*
X717392Y1420875D01*
X717600Y1420708D01*
X717683Y1420375D01*
X717600Y1420042D01*
X717350Y1419833D01*
X717058Y1419708D01*
X716017D01*
G01X717058D02*
X717683Y1418500D01*
G01X719242Y1418792D02*
X719533Y1418583D01*
X719867Y1418500D01*
X720200Y1418583D01*
X720492Y1418833D01*
X720700Y1419208D01*
X720783Y1419583D01*
Y1420042D01*
X720700Y1420417D01*
X720492Y1420750D01*
X720242Y1420917D01*
X719950Y1421000D01*
X719617Y1420917D01*
X719367Y1420750D01*
X719200Y1420500D01*
X719117Y1420167D01*
X719200Y1419875D01*
X719408Y1419583D01*
X719658Y1419417D01*
X719950Y1419375D01*
X720283Y1419458D01*
X720533Y1419667D01*
X720783Y1420042D01*
G01X723050Y1418500D02*
X723342Y1418542D01*
X723675Y1418667D01*
X723883Y1418875D01*
X723967Y1419167D01*
X723883Y1419458D01*
X723633Y1419708D01*
X723258Y1419833D01*
X722842D01*
X722592Y1419917D01*
X722383Y1420125D01*
X722300Y1420417D01*
X722425Y1420708D01*
X722717Y1420917D01*
X723050Y1421000D01*
X723383Y1420917D01*
X723675Y1420708D01*
X723800Y1420417D01*
X723717Y1420125D01*
X723508Y1419917D01*
X723258Y1419833D01*
X722842D01*
X722467Y1419708D01*
X722217Y1419458D01*
X722133Y1419167D01*
X722217Y1418875D01*
X722425Y1418667D01*
X722758Y1418542D01*
X723050Y1418500D01*
G01X725358Y1419542D02*
X725650Y1419833D01*
X725900Y1420000D01*
X726233Y1420083D01*
X726525Y1420000D01*
X726733Y1419833D01*
X726900Y1419583D01*
X726942Y1419292D01*
X726900Y1419042D01*
X726733Y1418792D01*
X726483Y1418583D01*
X726192Y1418500D01*
X725858Y1418583D01*
X725567Y1418833D01*
X725400Y1419208D01*
X725358Y1419625D01*
X725442Y1420167D01*
X725567Y1420458D01*
X725775Y1420750D01*
X726067Y1420958D01*
X726358Y1421000D01*
X726650Y1420917D01*
X726858Y1420708D01*
G01X709342Y1420566D02*
X706842D01*
Y1421607D01*
X706967Y1421941D01*
X707134Y1422149D01*
X707467Y1422232D01*
X707800Y1422149D01*
X708009Y1421899D01*
X708134Y1421607D01*
Y1420566D01*
G01Y1421607D02*
X709342Y1422232D01*
G01Y1423666D02*
X706842D01*
Y1424707D01*
X706967Y1425041D01*
X707134Y1425249D01*
X707467Y1425332D01*
X707800Y1425249D01*
X708009Y1424999D01*
X708134Y1424707D01*
Y1423666D01*
G01Y1424707D02*
X709342Y1425332D01*
G01X709050Y1426891D02*
X709259Y1427182D01*
X709342Y1427516D01*
X709259Y1427849D01*
X709009Y1428141D01*
X708634Y1428349D01*
X708259Y1428432D01*
X707800D01*
X707425Y1428349D01*
X707092Y1428141D01*
X706925Y1427891D01*
X706842Y1427599D01*
X706925Y1427266D01*
X707092Y1427016D01*
X707342Y1426849D01*
X707675Y1426766D01*
X707967Y1426849D01*
X708259Y1427057D01*
X708425Y1427307D01*
X708467Y1427599D01*
X708384Y1427932D01*
X708175Y1428182D01*
X707800Y1428432D01*
G01X709342Y1430699D02*
X709300Y1430991D01*
X709175Y1431324D01*
X708967Y1431532D01*
X708675Y1431616D01*
X708384Y1431532D01*
X708134Y1431282D01*
X708009Y1430907D01*
Y1430491D01*
X707925Y1430241D01*
X707717Y1430032D01*
X707425Y1429949D01*
X707134Y1430074D01*
X706925Y1430366D01*
X706842Y1430699D01*
X706925Y1431032D01*
X707134Y1431324D01*
X707425Y1431449D01*
X707717Y1431366D01*
X707925Y1431157D01*
X708009Y1430907D01*
Y1430491D01*
X708134Y1430116D01*
X708384Y1429866D01*
X708675Y1429782D01*
X708967Y1429866D01*
X709175Y1430074D01*
X709300Y1430407D01*
X709342Y1430699D01*
G01X708967Y1432882D02*
X709175Y1433132D01*
X709300Y1433424D01*
X709342Y1433799D01*
X709259Y1434174D01*
X709092Y1434466D01*
X708800Y1434674D01*
X708467Y1434716D01*
X708134Y1434632D01*
X707925Y1434424D01*
X707759Y1434132D01*
X707717Y1433841D01*
X707759Y1433549D01*
X707925Y1433174D01*
X706842Y1433299D01*
Y1434424D01*
G01X705500Y1434700D02*
X701500D01*
Y1427300D01*
G01X711383Y1398109D02*
X711258Y1397859D01*
X711175Y1397567D01*
Y1397234D01*
X711300Y1396859D01*
X711508Y1396567D01*
X711758Y1396359D01*
X712175Y1396192D01*
X712550Y1396150D01*
X712925Y1396234D01*
X713175Y1396359D01*
X713425Y1396609D01*
X713592Y1396900D01*
X713675Y1397192D01*
Y1397484D01*
X713592Y1397775D01*
X713467Y1398025D01*
X713300Y1398234D01*
G01Y1399375D02*
X713508Y1399625D01*
X713633Y1399917D01*
X713675Y1400292D01*
X713592Y1400667D01*
X713425Y1400959D01*
X713133Y1401167D01*
X712800Y1401209D01*
X712467Y1401125D01*
X712258Y1400917D01*
X712092Y1400625D01*
X712050Y1400334D01*
X712092Y1400042D01*
X712258Y1399667D01*
X711175Y1399792D01*
Y1400917D01*
G01X713675Y1403892D02*
X711175D01*
X712967Y1402350D01*
Y1404434D01*
G01X713675Y1406409D02*
X713133Y1406492D01*
X712675Y1406617D01*
X712258Y1406784D01*
X711800Y1406992D01*
X711175Y1407325D01*
Y1405659D01*
G01X709675Y1396359D02*
X707175D01*
Y1397400D01*
X707300Y1397734D01*
X707467Y1397942D01*
X707800Y1398025D01*
X708133Y1397942D01*
X708342Y1397692D01*
X708467Y1397400D01*
Y1396359D01*
G01Y1397400D02*
X709675Y1398025D01*
G01Y1400292D02*
X707175D01*
X707675Y1399792D01*
G01X709675D02*
Y1400792D01*
G01X707175Y1403392D02*
X707258Y1403059D01*
X707467Y1402809D01*
X707717Y1402642D01*
X708050Y1402517D01*
X708425Y1402475D01*
X708800Y1402517D01*
X709133Y1402642D01*
X709383Y1402809D01*
X709592Y1403059D01*
X709675Y1403392D01*
X709592Y1403725D01*
X709383Y1403975D01*
X709133Y1404142D01*
X708800Y1404267D01*
X708425Y1404309D01*
X708050Y1404267D01*
X707717Y1404142D01*
X707467Y1403975D01*
X707258Y1403725D01*
X707175Y1403392D01*
G01Y1406492D02*
X707258Y1406159D01*
X707467Y1405909D01*
X707717Y1405742D01*
X708050Y1405617D01*
X708425Y1405575D01*
X708800Y1405617D01*
X709133Y1405742D01*
X709383Y1405909D01*
X709592Y1406159D01*
X709675Y1406492D01*
X709592Y1406825D01*
X709383Y1407075D01*
X709133Y1407242D01*
X708800Y1407367D01*
X708425Y1407409D01*
X708050Y1407367D01*
X707717Y1407242D01*
X707467Y1407075D01*
X707258Y1406825D01*
X707175Y1406492D01*
G01X709675Y1410092D02*
X707175D01*
X708967Y1408550D01*
Y1410634D01*
G01X724517Y1422500D02*
Y1425000D01*
X725558D01*
X725892Y1424875D01*
X726100Y1424708D01*
X726183Y1424375D01*
X726100Y1424042D01*
X725850Y1423833D01*
X725558Y1423708D01*
X724517D01*
G01X725558D02*
X726183Y1422500D01*
G01X727742Y1422792D02*
X728033Y1422583D01*
X728367Y1422500D01*
X728700Y1422583D01*
X728992Y1422833D01*
X729200Y1423208D01*
X729283Y1423583D01*
Y1424042D01*
X729200Y1424417D01*
X728992Y1424750D01*
X728742Y1424917D01*
X728450Y1425000D01*
X728117Y1424917D01*
X727867Y1424750D01*
X727700Y1424500D01*
X727617Y1424167D01*
X727700Y1423875D01*
X727908Y1423583D01*
X728158Y1423417D01*
X728450Y1423375D01*
X728783Y1423458D01*
X729033Y1423667D01*
X729283Y1424042D01*
G01X730842Y1422792D02*
X731133Y1422583D01*
X731467Y1422500D01*
X731800Y1422583D01*
X732092Y1422833D01*
X732300Y1423208D01*
X732383Y1423583D01*
Y1424042D01*
X732300Y1424417D01*
X732092Y1424750D01*
X731842Y1424917D01*
X731550Y1425000D01*
X731217Y1424917D01*
X730967Y1424750D01*
X730800Y1424500D01*
X730717Y1424167D01*
X730800Y1423875D01*
X731008Y1423583D01*
X731258Y1423417D01*
X731550Y1423375D01*
X731883Y1423458D01*
X732133Y1423667D01*
X732383Y1424042D01*
G01X734650Y1422500D02*
Y1425000D01*
X734150Y1424500D01*
G01Y1422500D02*
X735150D01*
G01X700267Y1477292D02*
X700017Y1477417D01*
X699725Y1477500D01*
X699392D01*
X699017Y1477375D01*
X698725Y1477167D01*
X698517Y1476917D01*
X698350Y1476500D01*
X698308Y1476125D01*
X698392Y1475750D01*
X698517Y1475500D01*
X698767Y1475250D01*
X699058Y1475083D01*
X699350Y1475000D01*
X699642D01*
X699933Y1475083D01*
X700183Y1475208D01*
X700392Y1475375D01*
G01X701533D02*
X701783Y1475167D01*
X702075Y1475042D01*
X702450Y1475000D01*
X702825Y1475083D01*
X703117Y1475250D01*
X703325Y1475542D01*
X703367Y1475875D01*
X703283Y1476208D01*
X703075Y1476417D01*
X702783Y1476583D01*
X702492Y1476625D01*
X702200Y1476583D01*
X701825Y1476417D01*
X701950Y1477500D01*
X703075D01*
G01X706050Y1475000D02*
Y1477500D01*
X704508Y1475708D01*
X706592D01*
G01X707858Y1477083D02*
X708108Y1477333D01*
X708400Y1477458D01*
X708733Y1477500D01*
X709150Y1477417D01*
X709442Y1477208D01*
X709525Y1476958D01*
X709483Y1476708D01*
X709317Y1476500D01*
X708483Y1476083D01*
X708108Y1475792D01*
X707858Y1475375D01*
X707775Y1475000D01*
X709525D01*
G01X751708Y1437267D02*
X751583Y1437017D01*
X751500Y1436725D01*
Y1436392D01*
X751625Y1436017D01*
X751833Y1435725D01*
X752083Y1435517D01*
X752500Y1435350D01*
X752875Y1435308D01*
X753250Y1435392D01*
X753500Y1435517D01*
X753750Y1435767D01*
X753917Y1436058D01*
X754000Y1436350D01*
Y1436642D01*
X753917Y1436933D01*
X753792Y1437183D01*
X753625Y1437392D01*
G01X754000Y1439367D02*
X753458Y1439450D01*
X753000Y1439575D01*
X752583Y1439742D01*
X752125Y1439950D01*
X751500Y1440283D01*
Y1438617D01*
G01X754000Y1442550D02*
X751500D01*
X752000Y1442050D01*
G01X754000D02*
Y1443050D01*
G01Y1445650D02*
X751500D01*
X752000Y1445150D01*
G01X754000D02*
Y1446150D01*
G01X681000Y1490017D02*
X678500D01*
Y1491058D01*
X678625Y1491392D01*
X678792Y1491600D01*
X679125Y1491683D01*
X679458Y1491600D01*
X679667Y1491350D01*
X679792Y1491058D01*
Y1490017D01*
G01Y1491058D02*
X681000Y1491683D01*
G01X680708Y1493242D02*
X680917Y1493533D01*
X681000Y1493867D01*
X680917Y1494200D01*
X680667Y1494492D01*
X680292Y1494700D01*
X679917Y1494783D01*
X679458D01*
X679083Y1494700D01*
X678750Y1494492D01*
X678583Y1494242D01*
X678500Y1493950D01*
X678583Y1493617D01*
X678750Y1493367D01*
X679000Y1493200D01*
X679333Y1493117D01*
X679625Y1493200D01*
X679917Y1493408D01*
X680083Y1493658D01*
X680125Y1493950D01*
X680042Y1494283D01*
X679833Y1494533D01*
X679458Y1494783D01*
G01X680708Y1496342D02*
X680917Y1496633D01*
X681000Y1496967D01*
X680917Y1497300D01*
X680667Y1497592D01*
X680292Y1497800D01*
X679917Y1497883D01*
X679458D01*
X679083Y1497800D01*
X678750Y1497592D01*
X678583Y1497342D01*
X678500Y1497050D01*
X678583Y1496717D01*
X678750Y1496467D01*
X679000Y1496300D01*
X679333Y1496217D01*
X679625Y1496300D01*
X679917Y1496508D01*
X680083Y1496758D01*
X680125Y1497050D01*
X680042Y1497383D01*
X679833Y1497633D01*
X679458Y1497883D01*
G01X680625Y1499233D02*
X680833Y1499483D01*
X680958Y1499775D01*
X681000Y1500150D01*
X680917Y1500525D01*
X680750Y1500817D01*
X680458Y1501025D01*
X680125Y1501067D01*
X679792Y1500983D01*
X679583Y1500775D01*
X679417Y1500483D01*
X679375Y1500192D01*
X679417Y1499900D01*
X679583Y1499525D01*
X678500Y1499650D01*
Y1500775D01*
G01X682500Y1481700D02*
X678500D01*
Y1474300D01*
G01X724417Y1431000D02*
Y1433500D01*
X725458D01*
X725792Y1433375D01*
X726000Y1433208D01*
X726083Y1432875D01*
X726000Y1432542D01*
X725750Y1432333D01*
X725458Y1432208D01*
X724417D01*
G01X725458D02*
X726083Y1431000D01*
G01X727642Y1431292D02*
X727933Y1431083D01*
X728267Y1431000D01*
X728600Y1431083D01*
X728892Y1431333D01*
X729100Y1431708D01*
X729183Y1432083D01*
Y1432542D01*
X729100Y1432917D01*
X728892Y1433250D01*
X728642Y1433417D01*
X728350Y1433500D01*
X728017Y1433417D01*
X727767Y1433250D01*
X727600Y1433000D01*
X727517Y1432667D01*
X727600Y1432375D01*
X727808Y1432083D01*
X728058Y1431917D01*
X728350Y1431875D01*
X728683Y1431958D01*
X728933Y1432167D01*
X729183Y1432542D01*
G01X730742Y1431292D02*
X731033Y1431083D01*
X731367Y1431000D01*
X731700Y1431083D01*
X731992Y1431333D01*
X732200Y1431708D01*
X732283Y1432083D01*
Y1432542D01*
X732200Y1432917D01*
X731992Y1433250D01*
X731742Y1433417D01*
X731450Y1433500D01*
X731117Y1433417D01*
X730867Y1433250D01*
X730700Y1433000D01*
X730617Y1432667D01*
X730700Y1432375D01*
X730908Y1432083D01*
X731158Y1431917D01*
X731450Y1431875D01*
X731783Y1431958D01*
X732033Y1432167D01*
X732283Y1432542D01*
G01X735050Y1431000D02*
Y1433500D01*
X733508Y1431708D01*
X735592D01*
G01X721800Y1455500D02*
Y1451500D01*
X729200D01*
G01X708300Y1445500D02*
Y1441500D01*
X715700D01*
G01X711717Y1430900D02*
Y1433400D01*
X712758D01*
X713092Y1433275D01*
X713300Y1433108D01*
X713383Y1432775D01*
X713300Y1432442D01*
X713050Y1432233D01*
X712758Y1432108D01*
X711717D01*
G01X712758D02*
X713383Y1430900D01*
G01X714942Y1431192D02*
X715233Y1430983D01*
X715567Y1430900D01*
X715900Y1430983D01*
X716192Y1431233D01*
X716400Y1431608D01*
X716483Y1431983D01*
Y1432442D01*
X716400Y1432817D01*
X716192Y1433150D01*
X715942Y1433317D01*
X715650Y1433400D01*
X715317Y1433317D01*
X715067Y1433150D01*
X714900Y1432900D01*
X714817Y1432567D01*
X714900Y1432275D01*
X715108Y1431983D01*
X715358Y1431817D01*
X715650Y1431775D01*
X715983Y1431858D01*
X716233Y1432067D01*
X716483Y1432442D01*
G01X718042Y1431192D02*
X718333Y1430983D01*
X718667Y1430900D01*
X719000Y1430983D01*
X719292Y1431233D01*
X719500Y1431608D01*
X719583Y1431983D01*
Y1432442D01*
X719500Y1432817D01*
X719292Y1433150D01*
X719042Y1433317D01*
X718750Y1433400D01*
X718417Y1433317D01*
X718167Y1433150D01*
X718000Y1432900D01*
X717917Y1432567D01*
X718000Y1432275D01*
X718208Y1431983D01*
X718458Y1431817D01*
X718750Y1431775D01*
X719083Y1431858D01*
X719333Y1432067D01*
X719583Y1432442D01*
G01X721058Y1432983D02*
X721308Y1433233D01*
X721600Y1433358D01*
X721933Y1433400D01*
X722350Y1433317D01*
X722642Y1433108D01*
X722725Y1432858D01*
X722683Y1432608D01*
X722517Y1432400D01*
X721683Y1431983D01*
X721308Y1431692D01*
X721058Y1431275D01*
X720975Y1430900D01*
X722725D01*
G01X716200Y1451500D02*
Y1455500D01*
X708800D01*
G01X719017Y1468000D02*
Y1470500D01*
X720058D01*
X720392Y1470375D01*
X720600Y1470208D01*
X720683Y1469875D01*
X720600Y1469542D01*
X720350Y1469333D01*
X720058Y1469208D01*
X719017D01*
G01X720058D02*
X720683Y1468000D01*
G01X722242Y1468292D02*
X722533Y1468083D01*
X722867Y1468000D01*
X723200Y1468083D01*
X723492Y1468333D01*
X723700Y1468708D01*
X723783Y1469083D01*
Y1469542D01*
X723700Y1469917D01*
X723492Y1470250D01*
X723242Y1470417D01*
X722950Y1470500D01*
X722617Y1470417D01*
X722367Y1470250D01*
X722200Y1470000D01*
X722117Y1469667D01*
X722200Y1469375D01*
X722408Y1469083D01*
X722658Y1468917D01*
X722950Y1468875D01*
X723283Y1468958D01*
X723533Y1469167D01*
X723783Y1469542D01*
G01X725342Y1468292D02*
X725633Y1468083D01*
X725967Y1468000D01*
X726300Y1468083D01*
X726592Y1468333D01*
X726800Y1468708D01*
X726883Y1469083D01*
Y1469542D01*
X726800Y1469917D01*
X726592Y1470250D01*
X726342Y1470417D01*
X726050Y1470500D01*
X725717Y1470417D01*
X725467Y1470250D01*
X725300Y1470000D01*
X725217Y1469667D01*
X725300Y1469375D01*
X725508Y1469083D01*
X725758Y1468917D01*
X726050Y1468875D01*
X726383Y1468958D01*
X726633Y1469167D01*
X726883Y1469542D01*
G01X729150Y1470500D02*
X728817Y1470417D01*
X728567Y1470208D01*
X728400Y1469958D01*
X728275Y1469625D01*
X728233Y1469250D01*
X728275Y1468875D01*
X728400Y1468542D01*
X728567Y1468292D01*
X728817Y1468083D01*
X729150Y1468000D01*
X729483Y1468083D01*
X729733Y1468292D01*
X729900Y1468542D01*
X730025Y1468875D01*
X730067Y1469250D01*
X730025Y1469625D01*
X729900Y1469958D01*
X729733Y1470208D01*
X729483Y1470417D01*
X729150Y1470500D01*
G01X717500Y1465300D02*
Y1469300D01*
X710100D01*
G01X729200Y1447000D02*
Y1451000D01*
X721800D01*
G01X756117Y1454400D02*
Y1456900D01*
X757158D01*
X757492Y1456775D01*
X757700Y1456608D01*
X757783Y1456275D01*
X757700Y1455942D01*
X757450Y1455733D01*
X757158Y1455608D01*
X756117D01*
G01X757158D02*
X757783Y1454400D01*
G01X759342Y1454692D02*
X759633Y1454483D01*
X759967Y1454400D01*
X760300Y1454483D01*
X760592Y1454733D01*
X760800Y1455108D01*
X760883Y1455483D01*
Y1455942D01*
X760800Y1456317D01*
X760592Y1456650D01*
X760342Y1456817D01*
X760050Y1456900D01*
X759717Y1456817D01*
X759467Y1456650D01*
X759300Y1456400D01*
X759217Y1456067D01*
X759300Y1455775D01*
X759508Y1455483D01*
X759758Y1455317D01*
X760050Y1455275D01*
X760383Y1455358D01*
X760633Y1455567D01*
X760883Y1455942D01*
G01X763150Y1454400D02*
X763442Y1454442D01*
X763775Y1454567D01*
X763983Y1454775D01*
X764067Y1455067D01*
X763983Y1455358D01*
X763733Y1455608D01*
X763358Y1455733D01*
X762942D01*
X762692Y1455817D01*
X762483Y1456025D01*
X762400Y1456317D01*
X762525Y1456608D01*
X762817Y1456817D01*
X763150Y1456900D01*
X763483Y1456817D01*
X763775Y1456608D01*
X763900Y1456317D01*
X763817Y1456025D01*
X763608Y1455817D01*
X763358Y1455733D01*
X762942D01*
X762567Y1455608D01*
X762317Y1455358D01*
X762233Y1455067D01*
X762317Y1454775D01*
X762525Y1454567D01*
X762858Y1454442D01*
X763150Y1454400D01*
G01X766250D02*
X766542Y1454442D01*
X766875Y1454567D01*
X767083Y1454775D01*
X767167Y1455067D01*
X767083Y1455358D01*
X766833Y1455608D01*
X766458Y1455733D01*
X766042D01*
X765792Y1455817D01*
X765583Y1456025D01*
X765500Y1456317D01*
X765625Y1456608D01*
X765917Y1456817D01*
X766250Y1456900D01*
X766583Y1456817D01*
X766875Y1456608D01*
X767000Y1456317D01*
X766917Y1456025D01*
X766708Y1455817D01*
X766458Y1455733D01*
X766042D01*
X765667Y1455608D01*
X765417Y1455358D01*
X765333Y1455067D01*
X765417Y1454775D01*
X765625Y1454567D01*
X765958Y1454442D01*
X766250Y1454400D01*
G01X714300Y1460500D02*
Y1456500D01*
X721700D01*
G01X755917Y1458300D02*
Y1460800D01*
X756958D01*
X757292Y1460675D01*
X757500Y1460508D01*
X757583Y1460175D01*
X757500Y1459842D01*
X757250Y1459633D01*
X756958Y1459508D01*
X755917D01*
G01X756958D02*
X757583Y1458300D01*
G01X759142Y1458592D02*
X759433Y1458383D01*
X759767Y1458300D01*
X760100Y1458383D01*
X760392Y1458633D01*
X760600Y1459008D01*
X760683Y1459383D01*
Y1459842D01*
X760600Y1460217D01*
X760392Y1460550D01*
X760142Y1460717D01*
X759850Y1460800D01*
X759517Y1460717D01*
X759267Y1460550D01*
X759100Y1460300D01*
X759017Y1459967D01*
X759100Y1459675D01*
X759308Y1459383D01*
X759558Y1459217D01*
X759850Y1459175D01*
X760183Y1459258D01*
X760433Y1459467D01*
X760683Y1459842D01*
G01X762950Y1458300D02*
X763242Y1458342D01*
X763575Y1458467D01*
X763783Y1458675D01*
X763867Y1458967D01*
X763783Y1459258D01*
X763533Y1459508D01*
X763158Y1459633D01*
X762742D01*
X762492Y1459717D01*
X762283Y1459925D01*
X762200Y1460217D01*
X762325Y1460508D01*
X762617Y1460717D01*
X762950Y1460800D01*
X763283Y1460717D01*
X763575Y1460508D01*
X763700Y1460217D01*
X763617Y1459925D01*
X763408Y1459717D01*
X763158Y1459633D01*
X762742D01*
X762367Y1459508D01*
X762117Y1459258D01*
X762033Y1458967D01*
X762117Y1458675D01*
X762325Y1458467D01*
X762658Y1458342D01*
X762950Y1458300D01*
G01X765967D02*
X766050Y1458842D01*
X766175Y1459300D01*
X766342Y1459717D01*
X766550Y1460175D01*
X766883Y1460800D01*
X765217D01*
G01X714300Y1465000D02*
Y1461000D01*
X721700D01*
G01X719017Y1472000D02*
Y1474500D01*
X720058D01*
X720392Y1474375D01*
X720600Y1474208D01*
X720683Y1473875D01*
X720600Y1473542D01*
X720350Y1473333D01*
X720058Y1473208D01*
X719017D01*
G01X720058D02*
X720683Y1472000D01*
G01X722242Y1472292D02*
X722533Y1472083D01*
X722867Y1472000D01*
X723200Y1472083D01*
X723492Y1472333D01*
X723700Y1472708D01*
X723783Y1473083D01*
Y1473542D01*
X723700Y1473917D01*
X723492Y1474250D01*
X723242Y1474417D01*
X722950Y1474500D01*
X722617Y1474417D01*
X722367Y1474250D01*
X722200Y1474000D01*
X722117Y1473667D01*
X722200Y1473375D01*
X722408Y1473083D01*
X722658Y1472917D01*
X722950Y1472875D01*
X723283Y1472958D01*
X723533Y1473167D01*
X723783Y1473542D01*
G01X725342Y1472292D02*
X725633Y1472083D01*
X725967Y1472000D01*
X726300Y1472083D01*
X726592Y1472333D01*
X726800Y1472708D01*
X726883Y1473083D01*
Y1473542D01*
X726800Y1473917D01*
X726592Y1474250D01*
X726342Y1474417D01*
X726050Y1474500D01*
X725717Y1474417D01*
X725467Y1474250D01*
X725300Y1474000D01*
X725217Y1473667D01*
X725300Y1473375D01*
X725508Y1473083D01*
X725758Y1472917D01*
X726050Y1472875D01*
X726383Y1472958D01*
X726633Y1473167D01*
X726883Y1473542D01*
G01X729067Y1472000D02*
X729150Y1472542D01*
X729275Y1473000D01*
X729442Y1473417D01*
X729650Y1473875D01*
X729983Y1474500D01*
X728317D01*
G01X717600Y1469600D02*
Y1473600D01*
X710200D01*
G01X711300Y1440500D02*
Y1436500D01*
X718700D01*
G01X718967Y1476000D02*
Y1478500D01*
X720008D01*
X720342Y1478375D01*
X720550Y1478208D01*
X720633Y1477875D01*
X720550Y1477542D01*
X720300Y1477333D01*
X720008Y1477208D01*
X718967D01*
G01X720008D02*
X720633Y1476000D01*
G01X722900D02*
Y1478500D01*
X722400Y1478000D01*
G01Y1476000D02*
X723400D01*
G01X726000Y1478500D02*
X725667Y1478417D01*
X725417Y1478208D01*
X725250Y1477958D01*
X725125Y1477625D01*
X725083Y1477250D01*
X725125Y1476875D01*
X725250Y1476542D01*
X725417Y1476292D01*
X725667Y1476083D01*
X726000Y1476000D01*
X726333Y1476083D01*
X726583Y1476292D01*
X726750Y1476542D01*
X726875Y1476875D01*
X726917Y1477250D01*
X726875Y1477625D01*
X726750Y1477958D01*
X726583Y1478208D01*
X726333Y1478417D01*
X726000Y1478500D01*
G01X729100D02*
X728767Y1478417D01*
X728517Y1478208D01*
X728350Y1477958D01*
X728225Y1477625D01*
X728183Y1477250D01*
X728225Y1476875D01*
X728350Y1476542D01*
X728517Y1476292D01*
X728767Y1476083D01*
X729100Y1476000D01*
X729433Y1476083D01*
X729683Y1476292D01*
X729850Y1476542D01*
X729975Y1476875D01*
X730017Y1477250D01*
X729975Y1477625D01*
X729850Y1477958D01*
X729683Y1478208D01*
X729433Y1478417D01*
X729100Y1478500D01*
G01X731408Y1478083D02*
X731658Y1478333D01*
X731950Y1478458D01*
X732283Y1478500D01*
X732700Y1478417D01*
X732992Y1478208D01*
X733075Y1477958D01*
X733033Y1477708D01*
X732867Y1477500D01*
X732033Y1477083D01*
X731658Y1476792D01*
X731408Y1476375D01*
X731325Y1476000D01*
X733075D01*
G01X710400Y1477800D02*
Y1473800D01*
X717800D01*
G01X685000Y1489967D02*
X682500D01*
Y1491008D01*
X682625Y1491342D01*
X682792Y1491550D01*
X683125Y1491633D01*
X683458Y1491550D01*
X683667Y1491300D01*
X683792Y1491008D01*
Y1489967D01*
G01Y1491008D02*
X685000Y1491633D01*
G01Y1493900D02*
X682500D01*
X683000Y1493400D01*
G01X685000D02*
Y1494400D01*
G01X682500Y1497000D02*
X682583Y1496667D01*
X682792Y1496417D01*
X683042Y1496250D01*
X683375Y1496125D01*
X683750Y1496083D01*
X684125Y1496125D01*
X684458Y1496250D01*
X684708Y1496417D01*
X684917Y1496667D01*
X685000Y1497000D01*
X684917Y1497333D01*
X684708Y1497583D01*
X684458Y1497750D01*
X684125Y1497875D01*
X683750Y1497917D01*
X683375Y1497875D01*
X683042Y1497750D01*
X682792Y1497583D01*
X682583Y1497333D01*
X682500Y1497000D01*
G01Y1500100D02*
X682583Y1499767D01*
X682792Y1499517D01*
X683042Y1499350D01*
X683375Y1499225D01*
X683750Y1499183D01*
X684125Y1499225D01*
X684458Y1499350D01*
X684708Y1499517D01*
X684917Y1499767D01*
X685000Y1500100D01*
X684917Y1500433D01*
X684708Y1500683D01*
X684458Y1500850D01*
X684125Y1500975D01*
X683750Y1501017D01*
X683375Y1500975D01*
X683042Y1500850D01*
X682792Y1500683D01*
X682583Y1500433D01*
X682500Y1500100D01*
G01X685000Y1503200D02*
X682500D01*
X683000Y1502700D01*
G01X685000D02*
Y1503700D01*
G01X682800Y1478000D02*
Y1474000D01*
X690200D01*
G01X736032Y1468234D02*
Y1464234D01*
X743432D01*
G01X747532Y1467934D02*
Y1463934D01*
X754932D01*
G01X732232Y1466719D02*
X728232D01*
Y1459319D01*
G01X754832Y1463719D02*
X750832D01*
Y1456319D01*
G01X732932Y1462934D02*
Y1451534D01*
G01X746332Y1462934D02*
X732932D01*
G01X746332Y1451534D02*
Y1462934D01*
G01X732932Y1451534D02*
X746332D01*
G01X677000Y1490017D02*
X674500D01*
Y1491058D01*
X674625Y1491392D01*
X674792Y1491600D01*
X675125Y1491683D01*
X675458Y1491600D01*
X675667Y1491350D01*
X675792Y1491058D01*
Y1490017D01*
G01Y1491058D02*
X677000Y1491683D01*
G01X676708Y1493242D02*
X676917Y1493533D01*
X677000Y1493867D01*
X676917Y1494200D01*
X676667Y1494492D01*
X676292Y1494700D01*
X675917Y1494783D01*
X675458D01*
X675083Y1494700D01*
X674750Y1494492D01*
X674583Y1494242D01*
X674500Y1493950D01*
X674583Y1493617D01*
X674750Y1493367D01*
X675000Y1493200D01*
X675333Y1493117D01*
X675625Y1493200D01*
X675917Y1493408D01*
X676083Y1493658D01*
X676125Y1493950D01*
X676042Y1494283D01*
X675833Y1494533D01*
X675458Y1494783D01*
G01X677000Y1497050D02*
X676958Y1497342D01*
X676833Y1497675D01*
X676625Y1497883D01*
X676333Y1497967D01*
X676042Y1497883D01*
X675792Y1497633D01*
X675667Y1497258D01*
Y1496842D01*
X675583Y1496592D01*
X675375Y1496383D01*
X675083Y1496300D01*
X674792Y1496425D01*
X674583Y1496717D01*
X674500Y1497050D01*
X674583Y1497383D01*
X674792Y1497675D01*
X675083Y1497800D01*
X675375Y1497717D01*
X675583Y1497508D01*
X675667Y1497258D01*
Y1496842D01*
X675792Y1496467D01*
X676042Y1496217D01*
X676333Y1496133D01*
X676625Y1496217D01*
X676833Y1496425D01*
X676958Y1496758D01*
X677000Y1497050D01*
G01X674917Y1499358D02*
X674667Y1499608D01*
X674542Y1499900D01*
X674500Y1500233D01*
X674583Y1500650D01*
X674792Y1500942D01*
X675042Y1501025D01*
X675292Y1500983D01*
X675500Y1500817D01*
X675917Y1499983D01*
X676208Y1499608D01*
X676625Y1499358D01*
X677000Y1499275D01*
Y1501025D01*
G01X674500Y1474300D02*
X678500D01*
Y1481700D01*
G01X693983Y1472000D02*
Y1470208D01*
X694150Y1469833D01*
X694483Y1469583D01*
X694900Y1469500D01*
X695317Y1469583D01*
X695650Y1469833D01*
X695817Y1470208D01*
Y1472000D01*
G01X697208Y1471583D02*
X697458Y1471833D01*
X697750Y1471958D01*
X698083Y1472000D01*
X698500Y1471917D01*
X698792Y1471708D01*
X698875Y1471458D01*
X698833Y1471208D01*
X698667Y1471000D01*
X697833Y1470583D01*
X697458Y1470292D01*
X697208Y1469875D01*
X697125Y1469500D01*
X698875D01*
G01X701100D02*
Y1472000D01*
X700600Y1471500D01*
G01Y1469500D02*
X701600D01*
G01X690987Y1469450D02*
Y1466450D01*
G01Y1438550D02*
Y1440550D01*
G01X705950Y1448580D02*
X702950D01*
G01X674050Y1450548D02*
X677050D01*
G01X675050Y1460388D02*
X677050D01*
G01X704950Y1458420D02*
X702950D01*
G01X676150Y1462350D02*
Y1467350D01*
X681150D01*
G01X703850Y1444650D02*
Y1439650D01*
X698850D01*
G01X703850Y1462350D02*
Y1467350D01*
X698850D01*
G01X756000Y1436983D02*
X757792D01*
X758167Y1437150D01*
X758417Y1437483D01*
X758500Y1437900D01*
X758417Y1438317D01*
X758167Y1438650D01*
X757792Y1438817D01*
X756000D01*
G01X758125Y1440083D02*
X758333Y1440333D01*
X758458Y1440625D01*
X758500Y1441000D01*
X758417Y1441375D01*
X758250Y1441667D01*
X757958Y1441875D01*
X757625Y1441917D01*
X757292Y1441833D01*
X757083Y1441625D01*
X756917Y1441333D01*
X756875Y1441042D01*
X756917Y1440750D01*
X757083Y1440375D01*
X756000Y1440500D01*
Y1441625D01*
G01Y1444100D02*
X756083Y1443767D01*
X756292Y1443517D01*
X756542Y1443350D01*
X756875Y1443225D01*
X757250Y1443183D01*
X757625Y1443225D01*
X757958Y1443350D01*
X758208Y1443517D01*
X758417Y1443767D01*
X758500Y1444100D01*
X758417Y1444433D01*
X758208Y1444683D01*
X757958Y1444850D01*
X757625Y1444975D01*
X757250Y1445017D01*
X756875Y1444975D01*
X756542Y1444850D01*
X756292Y1444683D01*
X756083Y1444433D01*
X756000Y1444100D01*
G01X749132Y1448134D02*
Y1434734D01*
G01X739132Y1448134D02*
X749132D01*
G01X739132Y1434734D02*
Y1448134D01*
G01X749132Y1434734D02*
X739132D01*
G01X729667Y1499217D02*
Y1501717D01*
X730708D01*
X731042Y1501592D01*
X731250Y1501425D01*
X731333Y1501092D01*
X731250Y1500759D01*
X731000Y1500550D01*
X730708Y1500425D01*
X729667D01*
G01X730708D02*
X731333Y1499217D01*
G01X732892Y1499509D02*
X733183Y1499300D01*
X733517Y1499217D01*
X733850Y1499300D01*
X734142Y1499550D01*
X734350Y1499925D01*
X734433Y1500300D01*
Y1500759D01*
X734350Y1501134D01*
X734142Y1501467D01*
X733892Y1501634D01*
X733600Y1501717D01*
X733267Y1501634D01*
X733017Y1501467D01*
X732850Y1501217D01*
X732767Y1500884D01*
X732850Y1500592D01*
X733058Y1500300D01*
X733308Y1500134D01*
X733600Y1500092D01*
X733933Y1500175D01*
X734183Y1500384D01*
X734433Y1500759D01*
G01X735908Y1500259D02*
X736200Y1500550D01*
X736450Y1500717D01*
X736783Y1500800D01*
X737075Y1500717D01*
X737283Y1500550D01*
X737450Y1500300D01*
X737492Y1500009D01*
X737450Y1499759D01*
X737283Y1499509D01*
X737033Y1499300D01*
X736742Y1499217D01*
X736408Y1499300D01*
X736117Y1499550D01*
X735950Y1499925D01*
X735908Y1500342D01*
X735992Y1500884D01*
X736117Y1501175D01*
X736325Y1501467D01*
X736617Y1501675D01*
X736908Y1501717D01*
X737200Y1501634D01*
X737408Y1501425D01*
G01X739717Y1499217D02*
X739800Y1499759D01*
X739925Y1500217D01*
X740092Y1500634D01*
X740300Y1501092D01*
X740633Y1501717D01*
X738967D01*
G01X741850Y1482950D02*
X736650D01*
G01X741850Y1489950D02*
X734050D01*
G01X741850Y1482950D02*
Y1489950D01*
G01X728450Y1482950D02*
X737150D01*
G01X728450Y1489950D02*
Y1482950D01*
G01X734850Y1489950D02*
X728450D01*
G01X729467Y1503750D02*
Y1506250D01*
X730508D01*
X730842Y1506125D01*
X731050Y1505958D01*
X731133Y1505625D01*
X731050Y1505292D01*
X730800Y1505083D01*
X730508Y1504958D01*
X729467D01*
G01X730508D02*
X731133Y1503750D01*
G01X732692Y1504042D02*
X732983Y1503833D01*
X733317Y1503750D01*
X733650Y1503833D01*
X733942Y1504083D01*
X734150Y1504458D01*
X734233Y1504833D01*
Y1505292D01*
X734150Y1505667D01*
X733942Y1506000D01*
X733692Y1506167D01*
X733400Y1506250D01*
X733067Y1506167D01*
X732817Y1506000D01*
X732650Y1505750D01*
X732567Y1505417D01*
X732650Y1505125D01*
X732858Y1504833D01*
X733108Y1504667D01*
X733400Y1504625D01*
X733733Y1504708D01*
X733983Y1504917D01*
X734233Y1505292D01*
G01X736417Y1503750D02*
X736500Y1504292D01*
X736625Y1504750D01*
X736792Y1505167D01*
X737000Y1505625D01*
X737333Y1506250D01*
X735667D01*
G01X739600D02*
X739267Y1506167D01*
X739017Y1505958D01*
X738850Y1505708D01*
X738725Y1505375D01*
X738683Y1505000D01*
X738725Y1504625D01*
X738850Y1504292D01*
X739017Y1504042D01*
X739267Y1503833D01*
X739600Y1503750D01*
X739933Y1503833D01*
X740183Y1504042D01*
X740350Y1504292D01*
X740475Y1504625D01*
X740517Y1505000D01*
X740475Y1505375D01*
X740350Y1505708D01*
X740183Y1505958D01*
X739933Y1506167D01*
X739600Y1506250D01*
G01X728450Y1497750D02*
X733650D01*
G01X728450Y1490750D02*
X736250D01*
G01X728450Y1497750D02*
Y1490750D01*
G01X741850Y1497750D02*
X733150D01*
G01X741850Y1490750D02*
Y1497750D01*
G01X735450Y1490750D02*
X741850D01*
G01X715981Y1479118D02*
X686381D01*
Y1516718D01*
X715981D01*
Y1479118D01*
G01X708086Y1494328D02*
X714786D01*
G01X702986D02*
X698886D01*
G01X708086Y1499428D02*
X702986Y1494328D01*
G01X708086Y1489228D02*
Y1499428D01*
G01X702986Y1494328D02*
X708086Y1489228D01*
G01X693786Y1499428D02*
X698886Y1494328D01*
G01X693786Y1489228D02*
Y1499428D01*
G01X698886Y1494328D02*
X693786Y1489228D01*
G01Y1494328D02*
X690086D01*
G01X702986Y1497128D02*
Y1490728D01*
G01X698886Y1497128D02*
Y1490728D01*
G01X756373Y1471380D02*
X756331Y1471047D01*
X756165Y1470755D01*
X755915Y1470505D01*
X755623Y1470338D01*
X755290Y1470255D01*
X754956D01*
X754623Y1470338D01*
X754331Y1470505D01*
X754081Y1470755D01*
X753915Y1471047D01*
X753873Y1471380D01*
X753915Y1471713D01*
X754081Y1472005D01*
X754331Y1472255D01*
X754623Y1472422D01*
X754956Y1472505D01*
X755290D01*
X755623Y1472422D01*
X755915Y1472255D01*
X756165Y1472005D01*
X756331Y1471713D01*
X756373Y1471380D01*
G01X755706Y1471713D02*
X756373Y1472213D01*
G01X754290Y1473688D02*
X754040Y1473938D01*
X753915Y1474230D01*
X753873Y1474563D01*
X753956Y1474980D01*
X754165Y1475272D01*
X754415Y1475355D01*
X754665Y1475313D01*
X754873Y1475147D01*
X755290Y1474313D01*
X755581Y1473938D01*
X755998Y1473688D01*
X756373Y1473605D01*
Y1475355D01*
G01X753873Y1477580D02*
X753956Y1477247D01*
X754165Y1476997D01*
X754415Y1476830D01*
X754748Y1476705D01*
X755123Y1476663D01*
X755498Y1476705D01*
X755831Y1476830D01*
X756081Y1476997D01*
X756290Y1477247D01*
X756373Y1477580D01*
X756290Y1477913D01*
X756081Y1478163D01*
X755831Y1478330D01*
X755498Y1478455D01*
X755123Y1478497D01*
X754748Y1478455D01*
X754415Y1478330D01*
X754165Y1478163D01*
X753956Y1477913D01*
X753873Y1477580D01*
G01X755998Y1479763D02*
X756206Y1480013D01*
X756331Y1480305D01*
X756373Y1480680D01*
X756290Y1481055D01*
X756123Y1481347D01*
X755831Y1481555D01*
X755498Y1481597D01*
X755165Y1481513D01*
X754956Y1481305D01*
X754790Y1481013D01*
X754748Y1480722D01*
X754790Y1480430D01*
X754956Y1480055D01*
X753873Y1480180D01*
Y1481305D01*
G01X742067Y1468534D02*
Y1468794D01*
X740632Y1470229D01*
X739197Y1468794D01*
G01X742067Y1468534D02*
X739197D01*
Y1479534D01*
G01X742067D02*
Y1468534D01*
G01Y1479534D02*
X739197D01*
G01X857401Y238493D02*
X857934Y238160D01*
X858534Y237960D01*
X859068D01*
X859601Y238160D01*
X860001Y238493D01*
X860201Y238960D01*
X860068Y239427D01*
X859734Y239827D01*
X859134Y240093D01*
X858334Y240227D01*
X857868Y240493D01*
X857668Y240960D01*
X857801Y241427D01*
X858134Y241760D01*
X858601Y241960D01*
X859068D01*
X859534Y241827D01*
X859934Y241493D01*
G01X863401Y237960D02*
Y241960D01*
G01X868001Y240627D02*
Y237960D01*
G01Y241693D02*
X867868Y241760D01*
Y241893D01*
X868001Y241960D01*
X868134Y241893D01*
Y241760D01*
X868001Y241693D01*
G01X872601Y241960D02*
Y237960D01*
G01X871668Y240627D02*
X873534D01*
G01X823072Y248031D02*
Y324992D01*
X917172D01*
Y248031D01*
X823072D01*
G01X849639Y318492D02*
Y322492D01*
X851239D01*
X851772Y322292D01*
X852172Y321825D01*
X852305Y321292D01*
X852172Y320759D01*
X851839Y320359D01*
X851239Y320159D01*
X849639D01*
G01X854639Y318492D02*
Y321159D01*
G01Y320625D02*
X854972Y320892D01*
X855305Y321092D01*
X855772Y321159D01*
X856105Y321092D01*
X856505Y320892D01*
G01X859172Y320292D02*
X861305D01*
X861105Y320759D01*
X860772Y321025D01*
X860305Y321159D01*
X859839Y321092D01*
X859439Y320892D01*
X859172Y320425D01*
X859039Y320025D01*
Y319625D01*
X859172Y319225D01*
X859505Y318825D01*
X859905Y318559D01*
X860372Y318492D01*
X860839Y318625D01*
X861305Y319025D01*
G01X863772Y318959D02*
X864105Y318692D01*
X864572Y318492D01*
X864972D01*
X865372Y318625D01*
X865639Y318825D01*
X865772Y319092D01*
X865705Y319492D01*
X865439Y319692D01*
X864239Y320092D01*
X863972Y320559D01*
X864105Y320892D01*
X864372Y321092D01*
X864772Y321159D01*
X865172Y321092D01*
X865572Y320892D01*
G01X868372Y318959D02*
X868705Y318692D01*
X869172Y318492D01*
X869572D01*
X869972Y318625D01*
X870239Y318825D01*
X870372Y319092D01*
X870305Y319492D01*
X870039Y319692D01*
X868839Y320092D01*
X868572Y320559D01*
X868705Y320892D01*
X868972Y321092D01*
X869372Y321159D01*
X869772Y321092D01*
X870172Y320892D01*
G01X877305Y318492D02*
Y322492D01*
X879839D01*
G01X878905Y320559D02*
X877305D01*
G01X883172Y321159D02*
Y318492D01*
G01Y322225D02*
X883039Y322292D01*
Y322425D01*
X883172Y322492D01*
X883305Y322425D01*
Y322292D01*
X883172Y322225D01*
G01X887772Y322492D02*
Y318492D01*
G01X886839Y321159D02*
X888705D01*
G01X808933Y365000D02*
Y367500D01*
X809767D01*
X810100Y367375D01*
X810350Y367208D01*
X810558Y366958D01*
X810725Y366667D01*
X810767Y366250D01*
X810725Y365833D01*
X810558Y365542D01*
X810350Y365292D01*
X810100Y365125D01*
X809767Y365000D01*
X808933D01*
G01X812117D02*
Y367500D01*
X813117D01*
X813450Y367375D01*
X813700Y367083D01*
X813783Y366750D01*
X813700Y366417D01*
X813492Y366167D01*
X813117Y366042D01*
X812117D01*
G01X816383Y366333D02*
X816550Y366458D01*
X816675Y366667D01*
X816758Y366958D01*
X816675Y367208D01*
X816508Y367375D01*
X816217Y367500D01*
X815092D01*
Y365000D01*
X816467D01*
X816758Y365167D01*
X816925Y365417D01*
X817008Y365708D01*
X816925Y366000D01*
X816675Y366250D01*
X816383Y366333D01*
X815092D01*
G01X819150Y365000D02*
Y367500D01*
X818650Y367000D01*
G01Y365000D02*
X819650D01*
G01X843778Y394632D02*
X841278D01*
Y395673D01*
X841403Y396007D01*
X841570Y396215D01*
X841903Y396298D01*
X842236Y396215D01*
X842445Y395965D01*
X842570Y395673D01*
Y394632D01*
G01Y395673D02*
X843778Y396298D01*
G01X843278Y397648D02*
X843570Y397898D01*
X843736Y398232D01*
X843778Y398607D01*
X843736Y398940D01*
X843528Y399273D01*
X843278Y399482D01*
X843028Y399523D01*
X842736Y399440D01*
X842528Y399148D01*
X842445Y398857D01*
Y398482D01*
G01Y398857D02*
X842320Y399107D01*
X842111Y399315D01*
X841861Y399398D01*
X841611Y399315D01*
X841403Y399107D01*
X841278Y398732D01*
X841320Y398357D01*
X841486Y397982D01*
G01X843403Y400748D02*
X843611Y400998D01*
X843736Y401290D01*
X843778Y401665D01*
X843695Y402040D01*
X843528Y402332D01*
X843236Y402540D01*
X842903Y402582D01*
X842570Y402498D01*
X842361Y402290D01*
X842195Y401998D01*
X842153Y401707D01*
X842195Y401415D01*
X842361Y401040D01*
X841278Y401165D01*
Y402290D01*
G01X843778Y405265D02*
X841278D01*
X843070Y403723D01*
Y405807D01*
G01X839939Y384415D02*
X843939D01*
Y391815D01*
G01X847824Y394632D02*
X845324D01*
Y395673D01*
X845449Y396007D01*
X845616Y396215D01*
X845949Y396298D01*
X846282Y396215D01*
X846491Y395965D01*
X846616Y395673D01*
Y394632D01*
G01Y395673D02*
X847824Y396298D01*
G01X847324Y397648D02*
X847616Y397898D01*
X847782Y398232D01*
X847824Y398607D01*
X847782Y398940D01*
X847574Y399273D01*
X847324Y399482D01*
X847074Y399523D01*
X846782Y399440D01*
X846574Y399148D01*
X846491Y398857D01*
Y398482D01*
G01Y398857D02*
X846366Y399107D01*
X846157Y399315D01*
X845907Y399398D01*
X845657Y399315D01*
X845449Y399107D01*
X845324Y398732D01*
X845366Y398357D01*
X845532Y397982D01*
G01X847449Y400748D02*
X847657Y400998D01*
X847782Y401290D01*
X847824Y401665D01*
X847741Y402040D01*
X847574Y402332D01*
X847282Y402540D01*
X846949Y402582D01*
X846616Y402498D01*
X846407Y402290D01*
X846241Y401998D01*
X846199Y401707D01*
X846241Y401415D01*
X846407Y401040D01*
X845324Y401165D01*
Y402290D01*
G01X847824Y404682D02*
X847282Y404765D01*
X846824Y404890D01*
X846407Y405057D01*
X845949Y405265D01*
X845324Y405598D01*
Y403932D01*
G01X844939Y384415D02*
X848939D01*
Y391815D01*
G01X858473Y420151D02*
X855973D01*
Y421192D01*
X856098Y421526D01*
X856265Y421734D01*
X856598Y421817D01*
X856931Y421734D01*
X857140Y421484D01*
X857265Y421192D01*
Y420151D01*
G01Y421192D02*
X858473Y421817D01*
G01Y424084D02*
X855973D01*
X856473Y423584D01*
G01X858473D02*
Y424584D01*
G01X858098Y426267D02*
X858306Y426517D01*
X858431Y426809D01*
X858473Y427184D01*
X858390Y427559D01*
X858223Y427851D01*
X857931Y428059D01*
X857598Y428101D01*
X857265Y428017D01*
X857056Y427809D01*
X856890Y427517D01*
X856848Y427226D01*
X856890Y426934D01*
X857056Y426559D01*
X855973Y426684D01*
Y427809D01*
G01X862298Y415792D02*
X858298D01*
Y408392D01*
G01X864266Y430909D02*
X861766D01*
Y431950D01*
X861891Y432284D01*
X862058Y432492D01*
X862391Y432575D01*
X862724Y432492D01*
X862933Y432242D01*
X863058Y431950D01*
Y430909D01*
G01Y431950D02*
X864266Y432575D01*
G01Y434842D02*
X861766D01*
X862266Y434342D01*
G01X864266D02*
Y435342D01*
G01Y438442D02*
X861766D01*
X863558Y436900D01*
Y438984D01*
G01X862183Y440250D02*
X861933Y440500D01*
X861808Y440792D01*
X861766Y441125D01*
X861849Y441542D01*
X862058Y441834D01*
X862308Y441917D01*
X862558Y441875D01*
X862766Y441709D01*
X863183Y440875D01*
X863474Y440500D01*
X863891Y440250D01*
X864266Y440167D01*
Y441917D01*
G01X864766Y426592D02*
X860766D01*
Y419192D01*
G01X852447Y420659D02*
X849947D01*
Y421700D01*
X850072Y422034D01*
X850239Y422242D01*
X850572Y422325D01*
X850905Y422242D01*
X851114Y421992D01*
X851239Y421700D01*
Y420659D01*
G01Y421700D02*
X852447Y422325D01*
G01Y424592D02*
X849947D01*
X850447Y424092D01*
G01X852447D02*
Y425092D01*
G01Y428192D02*
X849947D01*
X851739Y426650D01*
Y428734D01*
G01X852947Y415792D02*
X848947D01*
Y408392D01*
G01X812400Y436500D02*
Y434000D01*
G01X811442Y436500D02*
X813358D01*
G01X816417Y436292D02*
X816167Y436417D01*
X815875Y436500D01*
X815542D01*
X815167Y436375D01*
X814875Y436167D01*
X814667Y435917D01*
X814500Y435500D01*
X814458Y435125D01*
X814542Y434750D01*
X814667Y434500D01*
X814917Y434250D01*
X815208Y434083D01*
X815500Y434000D01*
X815792D01*
X816083Y434083D01*
X816333Y434208D01*
X816542Y434375D01*
G01X819100Y434000D02*
Y436500D01*
X817558Y434708D01*
X819642D01*
G01X800843Y395846D02*
Y427446D01*
X805543Y432146D01*
X824143D01*
X828843Y427446D01*
Y395846D01*
X800843D01*
G01X796400Y553850D02*
Y585450D01*
X801100Y590150D01*
X819700D01*
X824400Y585450D01*
Y553850D01*
X796400D01*
G01X837307Y634643D02*
X837057Y634768D01*
X836765Y634851D01*
X836432D01*
X836057Y634726D01*
X835765Y634518D01*
X835557Y634268D01*
X835390Y633851D01*
X835348Y633476D01*
X835432Y633101D01*
X835557Y632851D01*
X835807Y632601D01*
X836098Y632434D01*
X836390Y632351D01*
X836682D01*
X836973Y632434D01*
X837223Y632559D01*
X837432Y632726D01*
G01X839490Y632351D02*
Y634851D01*
X838990Y634351D01*
G01Y632351D02*
X839990D01*
G01X841798Y634434D02*
X842048Y634684D01*
X842340Y634809D01*
X842673Y634851D01*
X843090Y634768D01*
X843382Y634559D01*
X843465Y634309D01*
X843423Y634059D01*
X843257Y633851D01*
X842423Y633434D01*
X842048Y633143D01*
X841798Y632726D01*
X841715Y632351D01*
X843465D01*
G01X808067Y658500D02*
Y661000D01*
X809108D01*
X809442Y660875D01*
X809650Y660708D01*
X809733Y660375D01*
X809650Y660042D01*
X809400Y659833D01*
X809108Y659708D01*
X808067D01*
G01X809108D02*
X809733Y658500D01*
G01X811083Y658875D02*
X811333Y658667D01*
X811625Y658542D01*
X812000Y658500D01*
X812375Y658583D01*
X812667Y658750D01*
X812875Y659042D01*
X812917Y659375D01*
X812833Y659708D01*
X812625Y659917D01*
X812333Y660083D01*
X812042Y660125D01*
X811750Y660083D01*
X811375Y659917D01*
X811500Y661000D01*
X812625D01*
G01X814183Y659000D02*
X814433Y658708D01*
X814767Y658542D01*
X815142Y658500D01*
X815475Y658542D01*
X815808Y658750D01*
X816017Y659000D01*
X816058Y659250D01*
X815975Y659542D01*
X815683Y659750D01*
X815392Y659833D01*
X815017D01*
G01X815392D02*
X815642Y659958D01*
X815850Y660167D01*
X815933Y660417D01*
X815850Y660667D01*
X815642Y660875D01*
X815267Y661000D01*
X814892Y660958D01*
X814517Y660792D01*
G01X826690Y657190D02*
Y661190D01*
X819290D01*
G01X809067Y654000D02*
Y656500D01*
X810108D01*
X810442Y656375D01*
X810650Y656208D01*
X810733Y655875D01*
X810650Y655542D01*
X810400Y655333D01*
X810108Y655208D01*
X809067D01*
G01X810108D02*
X810733Y654000D01*
G01X812083Y654375D02*
X812333Y654167D01*
X812625Y654042D01*
X813000Y654000D01*
X813375Y654083D01*
X813667Y654250D01*
X813875Y654542D01*
X813917Y654875D01*
X813833Y655208D01*
X813625Y655417D01*
X813333Y655583D01*
X813042Y655625D01*
X812750Y655583D01*
X812375Y655417D01*
X812500Y656500D01*
X813625D01*
G01X816017Y654000D02*
X816100Y654542D01*
X816225Y655000D01*
X816392Y655417D01*
X816600Y655875D01*
X816933Y656500D01*
X815267D01*
G01X819290Y657190D02*
Y653190D01*
X826690D01*
G01X820067Y641000D02*
Y643500D01*
X821108D01*
X821442Y643375D01*
X821650Y643208D01*
X821733Y642875D01*
X821650Y642542D01*
X821400Y642333D01*
X821108Y642208D01*
X820067D01*
G01X821108D02*
X821733Y641000D01*
G01X823208Y642042D02*
X823500Y642333D01*
X823750Y642500D01*
X824083Y642583D01*
X824375Y642500D01*
X824583Y642333D01*
X824750Y642083D01*
X824792Y641792D01*
X824750Y641542D01*
X824583Y641292D01*
X824333Y641083D01*
X824042Y641000D01*
X823708Y641083D01*
X823417Y641333D01*
X823250Y641708D01*
X823208Y642125D01*
X823292Y642667D01*
X823417Y642958D01*
X823625Y643250D01*
X823917Y643458D01*
X824208Y643500D01*
X824500Y643417D01*
X824708Y643208D01*
G01X827100Y643500D02*
X826767Y643417D01*
X826517Y643208D01*
X826350Y642958D01*
X826225Y642625D01*
X826183Y642250D01*
X826225Y641875D01*
X826350Y641542D01*
X826517Y641292D01*
X826767Y641083D01*
X827100Y641000D01*
X827433Y641083D01*
X827683Y641292D01*
X827850Y641542D01*
X827975Y641875D01*
X828017Y642250D01*
X827975Y642625D01*
X827850Y642958D01*
X827683Y643208D01*
X827433Y643417D01*
X827100Y643500D01*
G01X826690Y645190D02*
Y649190D01*
X819290D01*
G01X808567Y650000D02*
Y652500D01*
X809608D01*
X809942Y652375D01*
X810150Y652208D01*
X810233Y651875D01*
X810150Y651542D01*
X809900Y651333D01*
X809608Y651208D01*
X808567D01*
G01X809608D02*
X810233Y650000D01*
G01X811708Y651042D02*
X812000Y651333D01*
X812250Y651500D01*
X812583Y651583D01*
X812875Y651500D01*
X813083Y651333D01*
X813250Y651083D01*
X813292Y650792D01*
X813250Y650542D01*
X813083Y650292D01*
X812833Y650083D01*
X812542Y650000D01*
X812208Y650083D01*
X811917Y650333D01*
X811750Y650708D01*
X811708Y651125D01*
X811792Y651667D01*
X811917Y651958D01*
X812125Y652250D01*
X812417Y652458D01*
X812708Y652500D01*
X813000Y652417D01*
X813208Y652208D01*
G01X815600Y650000D02*
Y652500D01*
X815100Y652000D01*
G01Y650000D02*
X816100D01*
G01X826690Y649190D02*
Y653190D01*
X819290D01*
G01X837807Y630643D02*
X837557Y630768D01*
X837265Y630851D01*
X836932D01*
X836557Y630726D01*
X836265Y630518D01*
X836057Y630268D01*
X835890Y629851D01*
X835848Y629476D01*
X835932Y629101D01*
X836057Y628851D01*
X836307Y628601D01*
X836598Y628434D01*
X836890Y628351D01*
X837182D01*
X837473Y628434D01*
X837723Y628559D01*
X837932Y628726D01*
G01X839990Y628351D02*
Y630851D01*
X839490Y630351D01*
G01Y628351D02*
X840490D01*
G01X843090D02*
Y630851D01*
X842590Y630351D01*
G01Y628351D02*
X843590D01*
G01X863990Y647540D02*
X842990D01*
Y679190D01*
X853990D01*
Y647540D01*
G01X845340D02*
X848490Y650690D01*
X851640Y647540D01*
G01X805800Y596500D02*
Y594000D01*
G01X804842Y596500D02*
X806758D01*
G01X809817Y596292D02*
X809567Y596417D01*
X809275Y596500D01*
X808942D01*
X808567Y596375D01*
X808275Y596167D01*
X808067Y595917D01*
X807900Y595500D01*
X807858Y595125D01*
X807942Y594750D01*
X808067Y594500D01*
X808317Y594250D01*
X808608Y594083D01*
X808900Y594000D01*
X809192D01*
X809483Y594083D01*
X809733Y594208D01*
X809942Y594375D01*
G01X812000Y594000D02*
Y596500D01*
X811500Y596000D01*
G01Y594000D02*
X812500D01*
G01X828800Y775650D02*
X849800D01*
Y744000D01*
X838800D01*
Y775650D01*
G01X847033Y684500D02*
Y682708D01*
X847200Y682333D01*
X847533Y682083D01*
X847950Y682000D01*
X848367Y682083D01*
X848700Y682333D01*
X848867Y682708D01*
Y684500D01*
G01X850967Y682000D02*
X851050Y682542D01*
X851175Y683000D01*
X851342Y683417D01*
X851550Y683875D01*
X851883Y684500D01*
X850217D01*
G01X835017Y793953D02*
X834767Y794078D01*
X834475Y794161D01*
X834142D01*
X833767Y794036D01*
X833475Y793828D01*
X833267Y793578D01*
X833100Y793161D01*
X833058Y792786D01*
X833142Y792411D01*
X833267Y792161D01*
X833517Y791911D01*
X833808Y791744D01*
X834100Y791661D01*
X834392D01*
X834683Y791744D01*
X834933Y791869D01*
X835142Y792036D01*
G01X837200Y791661D02*
Y794161D01*
X836700Y793661D01*
G01Y791661D02*
X837700D01*
G01X840300Y794161D02*
X839967Y794078D01*
X839717Y793869D01*
X839550Y793619D01*
X839425Y793286D01*
X839383Y792911D01*
X839425Y792536D01*
X839550Y792203D01*
X839717Y791953D01*
X839967Y791744D01*
X840300Y791661D01*
X840633Y791744D01*
X840883Y791953D01*
X841050Y792203D01*
X841175Y792536D01*
X841217Y792911D01*
X841175Y793286D01*
X841050Y793619D01*
X840883Y793869D01*
X840633Y794078D01*
X840300Y794161D01*
G01X799867Y772661D02*
Y775161D01*
X800908D01*
X801242Y775036D01*
X801450Y774869D01*
X801533Y774536D01*
X801450Y774203D01*
X801200Y773994D01*
X800908Y773869D01*
X799867D01*
G01X800908D02*
X801533Y772661D01*
G01X803008Y774744D02*
X803258Y774994D01*
X803550Y775119D01*
X803883Y775161D01*
X804300Y775078D01*
X804592Y774869D01*
X804675Y774619D01*
X804633Y774369D01*
X804467Y774161D01*
X803633Y773744D01*
X803258Y773453D01*
X803008Y773036D01*
X802925Y772661D01*
X804675D01*
G01X806817D02*
X806900Y773203D01*
X807025Y773661D01*
X807192Y774078D01*
X807400Y774536D01*
X807733Y775161D01*
X806067D01*
G01X812600Y774000D02*
Y770000D01*
X820000D01*
G01X799867Y777161D02*
Y779661D01*
X800908D01*
X801242Y779536D01*
X801450Y779369D01*
X801533Y779036D01*
X801450Y778703D01*
X801200Y778494D01*
X800908Y778369D01*
X799867D01*
G01X800908D02*
X801533Y777161D01*
G01X803008Y779244D02*
X803258Y779494D01*
X803550Y779619D01*
X803883Y779661D01*
X804300Y779578D01*
X804592Y779369D01*
X804675Y779119D01*
X804633Y778869D01*
X804467Y778661D01*
X803633Y778244D01*
X803258Y777953D01*
X803008Y777536D01*
X802925Y777161D01*
X804675D01*
G01X806900D02*
X807192Y777203D01*
X807525Y777328D01*
X807733Y777536D01*
X807817Y777828D01*
X807733Y778119D01*
X807483Y778369D01*
X807108Y778494D01*
X806692D01*
X806442Y778578D01*
X806233Y778786D01*
X806150Y779078D01*
X806275Y779369D01*
X806567Y779578D01*
X806900Y779661D01*
X807233Y779578D01*
X807525Y779369D01*
X807650Y779078D01*
X807567Y778786D01*
X807358Y778578D01*
X807108Y778494D01*
X806692D01*
X806317Y778369D01*
X806067Y778119D01*
X805983Y777828D01*
X806067Y777536D01*
X806275Y777328D01*
X806608Y777203D01*
X806900Y777161D01*
G01X820000Y774500D02*
Y778500D01*
X812600D01*
G01X800067Y786000D02*
Y788500D01*
X801108D01*
X801442Y788375D01*
X801650Y788208D01*
X801733Y787875D01*
X801650Y787542D01*
X801400Y787333D01*
X801108Y787208D01*
X800067D01*
G01X801108D02*
X801733Y786000D01*
G01X803208Y788083D02*
X803458Y788333D01*
X803750Y788458D01*
X804083Y788500D01*
X804500Y788417D01*
X804792Y788208D01*
X804875Y787958D01*
X804833Y787708D01*
X804667Y787500D01*
X803833Y787083D01*
X803458Y786792D01*
X803208Y786375D01*
X803125Y786000D01*
X804875D01*
G01X806392Y786292D02*
X806683Y786083D01*
X807017Y786000D01*
X807350Y786083D01*
X807642Y786333D01*
X807850Y786708D01*
X807933Y787083D01*
Y787542D01*
X807850Y787917D01*
X807642Y788250D01*
X807392Y788417D01*
X807100Y788500D01*
X806767Y788417D01*
X806517Y788250D01*
X806350Y788000D01*
X806267Y787667D01*
X806350Y787375D01*
X806558Y787083D01*
X806808Y786917D01*
X807100Y786875D01*
X807433Y786958D01*
X807683Y787167D01*
X807933Y787542D01*
G01X819900Y783500D02*
Y787500D01*
X812500D01*
G01X799867Y781661D02*
Y784161D01*
X800908D01*
X801242Y784036D01*
X801450Y783869D01*
X801533Y783536D01*
X801450Y783203D01*
X801200Y782994D01*
X800908Y782869D01*
X799867D01*
G01X800908D02*
X801533Y781661D01*
G01X802883Y782161D02*
X803133Y781869D01*
X803467Y781703D01*
X803842Y781661D01*
X804175Y781703D01*
X804508Y781911D01*
X804717Y782161D01*
X804758Y782411D01*
X804675Y782703D01*
X804383Y782911D01*
X804092Y782994D01*
X803717D01*
G01X804092D02*
X804342Y783119D01*
X804550Y783328D01*
X804633Y783578D01*
X804550Y783828D01*
X804342Y784036D01*
X803967Y784161D01*
X803592Y784119D01*
X803217Y783953D01*
G01X806900Y781661D02*
Y784161D01*
X806400Y783661D01*
G01Y781661D02*
X807400D01*
G01X812600Y783000D02*
Y779000D01*
X820000D01*
G01X799867Y768161D02*
Y770661D01*
X800908D01*
X801242Y770536D01*
X801450Y770369D01*
X801533Y770036D01*
X801450Y769703D01*
X801200Y769494D01*
X800908Y769369D01*
X799867D01*
G01X800908D02*
X801533Y768161D01*
G01X802883Y768661D02*
X803133Y768369D01*
X803467Y768203D01*
X803842Y768161D01*
X804175Y768203D01*
X804508Y768411D01*
X804717Y768661D01*
X804758Y768911D01*
X804675Y769203D01*
X804383Y769411D01*
X804092Y769494D01*
X803717D01*
G01X804092D02*
X804342Y769619D01*
X804550Y769828D01*
X804633Y770078D01*
X804550Y770328D01*
X804342Y770536D01*
X803967Y770661D01*
X803592Y770619D01*
X803217Y770453D01*
G01X806108Y770244D02*
X806358Y770494D01*
X806650Y770619D01*
X806983Y770661D01*
X807400Y770578D01*
X807692Y770369D01*
X807775Y770119D01*
X807733Y769869D01*
X807567Y769661D01*
X806733Y769244D01*
X806358Y768953D01*
X806108Y768536D01*
X806025Y768161D01*
X807775D01*
G01X820000Y765500D02*
Y769500D01*
X812600D01*
G01X864500Y794067D02*
X862000D01*
Y795108D01*
X862125Y795442D01*
X862292Y795650D01*
X862625Y795733D01*
X862958Y795650D01*
X863167Y795400D01*
X863292Y795108D01*
Y794067D01*
G01Y795108D02*
X864500Y795733D01*
G01Y798500D02*
X862000D01*
X863792Y796958D01*
Y799042D01*
G01X864500Y801600D02*
X862000D01*
X863792Y800058D01*
Y802142D01*
G01X820067Y835361D02*
Y837861D01*
X821108D01*
X821442Y837736D01*
X821650Y837569D01*
X821733Y837236D01*
X821650Y836903D01*
X821400Y836694D01*
X821108Y836569D01*
X820067D01*
G01X821108D02*
X821733Y835361D01*
G01X824500D02*
Y837861D01*
X822958Y836069D01*
X825042D01*
G01X826183Y835736D02*
X826433Y835528D01*
X826725Y835403D01*
X827100Y835361D01*
X827475Y835444D01*
X827767Y835611D01*
X827975Y835903D01*
X828017Y836236D01*
X827933Y836569D01*
X827725Y836778D01*
X827433Y836944D01*
X827142Y836986D01*
X826850Y836944D01*
X826475Y836778D01*
X826600Y837861D01*
X827725D01*
G01X828200Y817000D02*
Y821000D01*
X820800D01*
G01X820067Y823361D02*
Y825861D01*
X821108D01*
X821442Y825736D01*
X821650Y825569D01*
X821733Y825236D01*
X821650Y824903D01*
X821400Y824694D01*
X821108Y824569D01*
X820067D01*
G01X821108D02*
X821733Y823361D01*
G01X824500D02*
Y825861D01*
X822958Y824069D01*
X825042D01*
G01X827100Y823361D02*
X827392Y823403D01*
X827725Y823528D01*
X827933Y823736D01*
X828017Y824028D01*
X827933Y824319D01*
X827683Y824569D01*
X827308Y824694D01*
X826892D01*
X826642Y824778D01*
X826433Y824986D01*
X826350Y825278D01*
X826475Y825569D01*
X826767Y825778D01*
X827100Y825861D01*
X827433Y825778D01*
X827725Y825569D01*
X827850Y825278D01*
X827767Y824986D01*
X827558Y824778D01*
X827308Y824694D01*
X826892D01*
X826517Y824569D01*
X826267Y824319D01*
X826183Y824028D01*
X826267Y823736D01*
X826475Y823528D01*
X826808Y823403D01*
X827100Y823361D01*
G01X828200Y805000D02*
Y809000D01*
X820800D01*
G01X820067Y827361D02*
Y829861D01*
X821108D01*
X821442Y829736D01*
X821650Y829569D01*
X821733Y829236D01*
X821650Y828903D01*
X821400Y828694D01*
X821108Y828569D01*
X820067D01*
G01X821108D02*
X821733Y827361D01*
G01X824500D02*
Y829861D01*
X822958Y828069D01*
X825042D01*
G01X826392Y827653D02*
X826683Y827444D01*
X827017Y827361D01*
X827350Y827444D01*
X827642Y827694D01*
X827850Y828069D01*
X827933Y828444D01*
Y828903D01*
X827850Y829278D01*
X827642Y829611D01*
X827392Y829778D01*
X827100Y829861D01*
X826767Y829778D01*
X826517Y829611D01*
X826350Y829361D01*
X826267Y829028D01*
X826350Y828736D01*
X826558Y828444D01*
X826808Y828278D01*
X827100Y828236D01*
X827433Y828319D01*
X827683Y828528D01*
X827933Y828903D01*
G01X828200Y809000D02*
Y813000D01*
X820800D01*
G01X820067Y831361D02*
Y833861D01*
X821108D01*
X821442Y833736D01*
X821650Y833569D01*
X821733Y833236D01*
X821650Y832903D01*
X821400Y832694D01*
X821108Y832569D01*
X820067D01*
G01X821108D02*
X821733Y831361D01*
G01X823083Y831736D02*
X823333Y831528D01*
X823625Y831403D01*
X824000Y831361D01*
X824375Y831444D01*
X824667Y831611D01*
X824875Y831903D01*
X824917Y832236D01*
X824833Y832569D01*
X824625Y832778D01*
X824333Y832944D01*
X824042Y832986D01*
X823750Y832944D01*
X823375Y832778D01*
X823500Y833861D01*
X824625D01*
G01X827100D02*
X826767Y833778D01*
X826517Y833569D01*
X826350Y833319D01*
X826225Y832986D01*
X826183Y832611D01*
X826225Y832236D01*
X826350Y831903D01*
X826517Y831653D01*
X826767Y831444D01*
X827100Y831361D01*
X827433Y831444D01*
X827683Y831653D01*
X827850Y831903D01*
X827975Y832236D01*
X828017Y832611D01*
X827975Y832986D01*
X827850Y833319D01*
X827683Y833569D01*
X827433Y833778D01*
X827100Y833861D01*
G01X820800Y817000D02*
Y813000D01*
X828200D01*
G01X837067Y789953D02*
X836817Y790078D01*
X836525Y790161D01*
X836192D01*
X835817Y790036D01*
X835525Y789828D01*
X835317Y789578D01*
X835150Y789161D01*
X835108Y788786D01*
X835192Y788411D01*
X835317Y788161D01*
X835567Y787911D01*
X835858Y787744D01*
X836150Y787661D01*
X836442D01*
X836733Y787744D01*
X836983Y787869D01*
X837192Y788036D01*
G01X838542Y787953D02*
X838833Y787744D01*
X839167Y787661D01*
X839500Y787744D01*
X839792Y787994D01*
X840000Y788369D01*
X840083Y788744D01*
Y789203D01*
X840000Y789578D01*
X839792Y789911D01*
X839542Y790078D01*
X839250Y790161D01*
X838917Y790078D01*
X838667Y789911D01*
X838500Y789661D01*
X838417Y789328D01*
X838500Y789036D01*
X838708Y788744D01*
X838958Y788578D01*
X839250Y788536D01*
X839583Y788619D01*
X839833Y788828D01*
X840083Y789203D01*
G01X834000Y887650D02*
X855000D01*
Y856000D01*
X844000D01*
Y887650D01*
G01X841033Y780500D02*
Y778708D01*
X841200Y778333D01*
X841533Y778083D01*
X841950Y778000D01*
X842367Y778083D01*
X842700Y778333D01*
X842867Y778708D01*
Y780500D01*
G01X845550Y778000D02*
Y780500D01*
X844008Y778708D01*
X846092D01*
G01X847450Y775650D02*
X844300Y772500D01*
X841150Y775650D01*
G01X847533Y844000D02*
Y842208D01*
X847700Y841833D01*
X848033Y841583D01*
X848450Y841500D01*
X848867Y841583D01*
X849200Y841833D01*
X849367Y842208D01*
Y844000D01*
G01X850758Y842542D02*
X851050Y842833D01*
X851300Y843000D01*
X851633Y843083D01*
X851925Y843000D01*
X852133Y842833D01*
X852300Y842583D01*
X852342Y842292D01*
X852300Y842042D01*
X852133Y841792D01*
X851883Y841583D01*
X851592Y841500D01*
X851258Y841583D01*
X850967Y841833D01*
X850800Y842208D01*
X850758Y842625D01*
X850842Y843167D01*
X850967Y843458D01*
X851175Y843750D01*
X851467Y843958D01*
X851758Y844000D01*
X852050Y843917D01*
X852258Y843708D01*
G01X865500Y807350D02*
X844500D01*
Y839000D01*
X855500D01*
Y807350D01*
G01X846850D02*
X850000Y810500D01*
X853150Y807350D01*
G01X846017Y938797D02*
X845892Y938547D01*
X845809Y938255D01*
Y937922D01*
X845934Y937547D01*
X846142Y937255D01*
X846392Y937047D01*
X846809Y936880D01*
X847184Y936838D01*
X847559Y936922D01*
X847809Y937047D01*
X848059Y937297D01*
X848226Y937588D01*
X848309Y937880D01*
Y938172D01*
X848226Y938463D01*
X848101Y938713D01*
X847934Y938922D01*
G01X848309Y940980D02*
X848267Y941272D01*
X848142Y941605D01*
X847934Y941813D01*
X847642Y941897D01*
X847351Y941813D01*
X847101Y941563D01*
X846976Y941188D01*
Y940772D01*
X846892Y940522D01*
X846684Y940313D01*
X846392Y940230D01*
X846101Y940355D01*
X845892Y940647D01*
X845809Y940980D01*
X845892Y941313D01*
X846101Y941605D01*
X846392Y941730D01*
X846684Y941647D01*
X846892Y941438D01*
X846976Y941188D01*
Y940772D01*
X847101Y940397D01*
X847351Y940147D01*
X847642Y940063D01*
X847934Y940147D01*
X848142Y940355D01*
X848267Y940688D01*
X848309Y940980D01*
G01X804567Y891500D02*
Y894000D01*
X805608D01*
X805942Y893875D01*
X806150Y893708D01*
X806233Y893375D01*
X806150Y893042D01*
X805900Y892833D01*
X805608Y892708D01*
X804567D01*
G01X805608D02*
X806233Y891500D01*
G01X808500D02*
Y894000D01*
X808000Y893500D01*
G01Y891500D02*
X809000D01*
G01X811600D02*
X811892Y891542D01*
X812225Y891667D01*
X812433Y891875D01*
X812517Y892167D01*
X812433Y892458D01*
X812183Y892708D01*
X811808Y892833D01*
X811392D01*
X811142Y892917D01*
X810933Y893125D01*
X810850Y893417D01*
X810975Y893708D01*
X811267Y893917D01*
X811600Y894000D01*
X811933Y893917D01*
X812225Y893708D01*
X812350Y893417D01*
X812267Y893125D01*
X812058Y892917D01*
X811808Y892833D01*
X811392D01*
X811017Y892708D01*
X810767Y892458D01*
X810683Y892167D01*
X810767Y891875D01*
X810975Y891667D01*
X811308Y891542D01*
X811600Y891500D01*
G01X822300Y895000D02*
Y891000D01*
X829700D01*
G01X804454Y883453D02*
Y885953D01*
X805495D01*
X805829Y885828D01*
X806037Y885661D01*
X806120Y885328D01*
X806037Y884995D01*
X805787Y884786D01*
X805495Y884661D01*
X804454D01*
G01X805495D02*
X806120Y883453D01*
G01X808387D02*
Y885953D01*
X807887Y885453D01*
G01Y883453D02*
X808887D01*
G01X810779Y883745D02*
X811070Y883536D01*
X811404Y883453D01*
X811737Y883536D01*
X812029Y883786D01*
X812237Y884161D01*
X812320Y884536D01*
Y884995D01*
X812237Y885370D01*
X812029Y885703D01*
X811779Y885870D01*
X811487Y885953D01*
X811154Y885870D01*
X810904Y885703D01*
X810737Y885453D01*
X810654Y885120D01*
X810737Y884828D01*
X810945Y884536D01*
X811195Y884370D01*
X811487Y884328D01*
X811820Y884411D01*
X812070Y884620D01*
X812320Y884995D01*
G01X822187Y886453D02*
Y882453D01*
X829587D01*
G01X804567Y895500D02*
Y898000D01*
X805608D01*
X805942Y897875D01*
X806150Y897708D01*
X806233Y897375D01*
X806150Y897042D01*
X805900Y896833D01*
X805608Y896708D01*
X804567D01*
G01X805608D02*
X806233Y895500D01*
G01X807708Y897583D02*
X807958Y897833D01*
X808250Y897958D01*
X808583Y898000D01*
X809000Y897917D01*
X809292Y897708D01*
X809375Y897458D01*
X809333Y897208D01*
X809167Y897000D01*
X808333Y896583D01*
X807958Y896292D01*
X807708Y895875D01*
X807625Y895500D01*
X809375D01*
G01X811600Y898000D02*
X811267Y897917D01*
X811017Y897708D01*
X810850Y897458D01*
X810725Y897125D01*
X810683Y896750D01*
X810725Y896375D01*
X810850Y896042D01*
X811017Y895792D01*
X811267Y895583D01*
X811600Y895500D01*
X811933Y895583D01*
X812183Y895792D01*
X812350Y896042D01*
X812475Y896375D01*
X812517Y896750D01*
X812475Y897125D01*
X812350Y897458D01*
X812183Y897708D01*
X811933Y897917D01*
X811600Y898000D01*
G01X829700Y895500D02*
Y899500D01*
X822300D01*
G01X804567Y887500D02*
Y890000D01*
X805608D01*
X805942Y889875D01*
X806150Y889708D01*
X806233Y889375D01*
X806150Y889042D01*
X805900Y888833D01*
X805608Y888708D01*
X804567D01*
G01X805608D02*
X806233Y887500D01*
G01X807708Y889583D02*
X807958Y889833D01*
X808250Y889958D01*
X808583Y890000D01*
X809000Y889917D01*
X809292Y889708D01*
X809375Y889458D01*
X809333Y889208D01*
X809167Y889000D01*
X808333Y888583D01*
X807958Y888292D01*
X807708Y887875D01*
X807625Y887500D01*
X809375D01*
G01X812100D02*
Y890000D01*
X810558Y888208D01*
X812642D01*
G01X829700Y886500D02*
Y890500D01*
X822300D01*
G01X804454Y879756D02*
Y882256D01*
X805495D01*
X805829Y882131D01*
X806037Y881964D01*
X806120Y881631D01*
X806037Y881298D01*
X805787Y881089D01*
X805495Y880964D01*
X804454D01*
G01X805495D02*
X806120Y879756D01*
G01X807595Y881839D02*
X807845Y882089D01*
X808137Y882214D01*
X808470Y882256D01*
X808887Y882173D01*
X809179Y881964D01*
X809262Y881714D01*
X809220Y881464D01*
X809054Y881256D01*
X808220Y880839D01*
X807845Y880548D01*
X807595Y880131D01*
X807512Y879756D01*
X809262D01*
G01X810570Y880131D02*
X810820Y879923D01*
X811112Y879798D01*
X811487Y879756D01*
X811862Y879839D01*
X812154Y880006D01*
X812362Y880298D01*
X812404Y880631D01*
X812320Y880964D01*
X812112Y881173D01*
X811820Y881339D01*
X811529Y881381D01*
X811237Y881339D01*
X810862Y881173D01*
X810987Y882256D01*
X812112D01*
G01X829587Y878256D02*
Y882256D01*
X822187D01*
G01X823809Y910497D02*
X821309D01*
Y911538D01*
X821434Y911872D01*
X821601Y912080D01*
X821934Y912163D01*
X822267Y912080D01*
X822476Y911830D01*
X822601Y911538D01*
Y910497D01*
G01Y911538D02*
X823809Y912163D01*
G01X823309Y913513D02*
X823601Y913763D01*
X823767Y914097D01*
X823809Y914472D01*
X823767Y914805D01*
X823559Y915138D01*
X823309Y915347D01*
X823059Y915388D01*
X822767Y915305D01*
X822559Y915013D01*
X822476Y914722D01*
Y914347D01*
G01Y914722D02*
X822351Y914972D01*
X822142Y915180D01*
X821892Y915263D01*
X821642Y915180D01*
X821434Y914972D01*
X821309Y914597D01*
X821351Y914222D01*
X821517Y913847D01*
G01X822767Y916738D02*
X822476Y917030D01*
X822309Y917280D01*
X822226Y917613D01*
X822309Y917905D01*
X822476Y918113D01*
X822726Y918280D01*
X823017Y918322D01*
X823267Y918280D01*
X823517Y918113D01*
X823726Y917863D01*
X823809Y917572D01*
X823726Y917238D01*
X823476Y916947D01*
X823101Y916780D01*
X822684Y916738D01*
X822142Y916822D01*
X821851Y916947D01*
X821559Y917155D01*
X821351Y917447D01*
X821309Y917738D01*
X821392Y918030D01*
X821601Y918238D01*
G01X820470Y922230D02*
X824470D01*
Y929630D01*
G01X832000Y910567D02*
X829500D01*
Y911608D01*
X829625Y911942D01*
X829792Y912150D01*
X830125Y912233D01*
X830458Y912150D01*
X830667Y911900D01*
X830792Y911608D01*
Y910567D01*
G01Y911608D02*
X832000Y912233D01*
G01X831500Y913583D02*
X831792Y913833D01*
X831958Y914167D01*
X832000Y914542D01*
X831958Y914875D01*
X831750Y915208D01*
X831500Y915417D01*
X831250Y915458D01*
X830958Y915375D01*
X830750Y915083D01*
X830667Y914792D01*
Y914417D01*
G01Y914792D02*
X830542Y915042D01*
X830333Y915250D01*
X830083Y915333D01*
X829833Y915250D01*
X829625Y915042D01*
X829500Y914667D01*
X829542Y914292D01*
X829708Y913917D01*
G01X831708Y916892D02*
X831917Y917183D01*
X832000Y917517D01*
X831917Y917850D01*
X831667Y918142D01*
X831292Y918350D01*
X830917Y918433D01*
X830458D01*
X830083Y918350D01*
X829750Y918142D01*
X829583Y917892D01*
X829500Y917600D01*
X829583Y917267D01*
X829750Y917017D01*
X830000Y916850D01*
X830333Y916767D01*
X830625Y916850D01*
X830917Y917058D01*
X831083Y917308D01*
X831125Y917600D01*
X831042Y917933D01*
X830833Y918183D01*
X830458Y918433D01*
G01X832470Y929630D02*
X828470D01*
Y922230D01*
G01X827809Y910497D02*
X825309D01*
Y911538D01*
X825434Y911872D01*
X825601Y912080D01*
X825934Y912163D01*
X826267Y912080D01*
X826476Y911830D01*
X826601Y911538D01*
Y910497D01*
G01Y911538D02*
X827809Y912163D01*
G01Y914930D02*
X825309D01*
X827101Y913388D01*
Y915472D01*
G01X825309Y917530D02*
X825392Y917197D01*
X825601Y916947D01*
X825851Y916780D01*
X826184Y916655D01*
X826559Y916613D01*
X826934Y916655D01*
X827267Y916780D01*
X827517Y916947D01*
X827726Y917197D01*
X827809Y917530D01*
X827726Y917863D01*
X827517Y918113D01*
X827267Y918280D01*
X826934Y918405D01*
X826559Y918447D01*
X826184Y918405D01*
X825851Y918280D01*
X825601Y918113D01*
X825392Y917863D01*
X825309Y917530D01*
G01X828470Y929630D02*
X824470D01*
Y922230D01*
G01X819809Y910497D02*
X817309D01*
Y911538D01*
X817434Y911872D01*
X817601Y912080D01*
X817934Y912163D01*
X818267Y912080D01*
X818476Y911830D01*
X818601Y911538D01*
Y910497D01*
G01Y911538D02*
X819809Y912163D01*
G01Y914930D02*
X817309D01*
X819101Y913388D01*
Y915472D01*
G01X819809Y917530D02*
X817309D01*
X817809Y917030D01*
G01X819809D02*
Y918030D01*
G01X820470Y929630D02*
X816470D01*
Y922230D01*
G01X850208Y938867D02*
X850083Y938617D01*
X850000Y938325D01*
Y937992D01*
X850125Y937617D01*
X850333Y937325D01*
X850583Y937117D01*
X851000Y936950D01*
X851375Y936908D01*
X851750Y936992D01*
X852000Y937117D01*
X852250Y937367D01*
X852417Y937658D01*
X852500Y937950D01*
Y938242D01*
X852417Y938533D01*
X852292Y938783D01*
X852125Y938992D01*
G01X852500Y940967D02*
X851958Y941050D01*
X851500Y941175D01*
X851083Y941342D01*
X850625Y941550D01*
X850000Y941883D01*
Y940217D01*
G01X847433Y892900D02*
Y891108D01*
X847600Y890733D01*
X847933Y890483D01*
X848350Y890400D01*
X848767Y890483D01*
X849100Y890733D01*
X849267Y891108D01*
Y892900D01*
G01X850533Y890900D02*
X850783Y890608D01*
X851117Y890442D01*
X851492Y890400D01*
X851825Y890442D01*
X852158Y890650D01*
X852367Y890900D01*
X852408Y891150D01*
X852325Y891442D01*
X852033Y891650D01*
X851742Y891733D01*
X851367D01*
G01X851742D02*
X851992Y891858D01*
X852200Y892067D01*
X852283Y892317D01*
X852200Y892567D01*
X851992Y892775D01*
X851617Y892900D01*
X851242Y892858D01*
X850867Y892692D01*
G01X852650Y887650D02*
X849500Y884500D01*
X846350Y887650D01*
G01X830120Y966930D02*
Y945930D01*
X798470D01*
Y956930D01*
X830120D01*
G01Y948280D02*
X826970Y951430D01*
X830120Y954580D01*
G01X828000Y986567D02*
X825500D01*
Y987608D01*
X825625Y987942D01*
X825792Y988150D01*
X826125Y988233D01*
X826458Y988150D01*
X826667Y987900D01*
X826792Y987608D01*
Y986567D01*
G01Y987608D02*
X828000Y988233D01*
G01Y991000D02*
X825500D01*
X827292Y989458D01*
Y991542D01*
G01X827500Y992683D02*
X827792Y992933D01*
X827958Y993267D01*
X828000Y993642D01*
X827958Y993975D01*
X827750Y994308D01*
X827500Y994517D01*
X827250Y994558D01*
X826958Y994475D01*
X826750Y994183D01*
X826667Y993892D01*
Y993517D01*
G01Y993892D02*
X826542Y994142D01*
X826333Y994350D01*
X826083Y994433D01*
X825833Y994350D01*
X825625Y994142D01*
X825500Y993767D01*
X825542Y993392D01*
X825708Y993017D01*
G01X828470Y979630D02*
X824470D01*
Y972230D01*
G01X823500Y986567D02*
X821000D01*
Y987608D01*
X821125Y987942D01*
X821292Y988150D01*
X821625Y988233D01*
X821958Y988150D01*
X822167Y987900D01*
X822292Y987608D01*
Y986567D01*
G01Y987608D02*
X823500Y988233D01*
G01X823000Y989583D02*
X823292Y989833D01*
X823458Y990167D01*
X823500Y990542D01*
X823458Y990875D01*
X823250Y991208D01*
X823000Y991417D01*
X822750Y991458D01*
X822458Y991375D01*
X822250Y991083D01*
X822167Y990792D01*
Y990417D01*
G01Y990792D02*
X822042Y991042D01*
X821833Y991250D01*
X821583Y991333D01*
X821333Y991250D01*
X821125Y991042D01*
X821000Y990667D01*
X821042Y990292D01*
X821208Y989917D01*
G01X823500Y993600D02*
X823458Y993892D01*
X823333Y994225D01*
X823125Y994433D01*
X822833Y994517D01*
X822542Y994433D01*
X822292Y994183D01*
X822167Y993808D01*
Y993392D01*
X822083Y993142D01*
X821875Y992933D01*
X821583Y992850D01*
X821292Y992975D01*
X821083Y993267D01*
X821000Y993600D01*
X821083Y993933D01*
X821292Y994225D01*
X821583Y994350D01*
X821875Y994267D01*
X822083Y994058D01*
X822167Y993808D01*
Y993392D01*
X822292Y993017D01*
X822542Y992767D01*
X822833Y992683D01*
X823125Y992767D01*
X823333Y992975D01*
X823458Y993308D01*
X823500Y993600D01*
G01X820470Y972230D02*
X824470D01*
Y979630D01*
G01X841000Y986567D02*
X838500D01*
Y987608D01*
X838625Y987942D01*
X838792Y988150D01*
X839125Y988233D01*
X839458Y988150D01*
X839667Y987900D01*
X839792Y987608D01*
Y986567D01*
G01Y987608D02*
X841000Y988233D01*
G01Y990500D02*
X838500D01*
X839000Y990000D01*
G01X841000D02*
Y991000D01*
G01Y993600D02*
X840958Y993892D01*
X840833Y994225D01*
X840625Y994433D01*
X840333Y994517D01*
X840042Y994433D01*
X839792Y994183D01*
X839667Y993808D01*
Y993392D01*
X839583Y993142D01*
X839375Y992933D01*
X839083Y992850D01*
X838792Y992975D01*
X838583Y993267D01*
X838500Y993600D01*
X838583Y993933D01*
X838792Y994225D01*
X839083Y994350D01*
X839375Y994267D01*
X839583Y994058D01*
X839667Y993808D01*
Y993392D01*
X839792Y993017D01*
X840042Y992767D01*
X840333Y992683D01*
X840625Y992767D01*
X840833Y992975D01*
X840958Y993308D01*
X841000Y993600D01*
G01X840708Y995992D02*
X840917Y996283D01*
X841000Y996617D01*
X840917Y996950D01*
X840667Y997242D01*
X840292Y997450D01*
X839917Y997533D01*
X839458D01*
X839083Y997450D01*
X838750Y997242D01*
X838583Y996992D01*
X838500Y996700D01*
X838583Y996367D01*
X838750Y996117D01*
X839000Y995950D01*
X839333Y995867D01*
X839625Y995950D01*
X839917Y996158D01*
X840083Y996408D01*
X840125Y996700D01*
X840042Y997033D01*
X839833Y997283D01*
X839458Y997533D01*
G01X841970Y979630D02*
X837970D01*
Y972230D01*
G01X836500Y986567D02*
X834000D01*
Y987608D01*
X834125Y987942D01*
X834292Y988150D01*
X834625Y988233D01*
X834958Y988150D01*
X835167Y987900D01*
X835292Y987608D01*
Y986567D01*
G01Y987608D02*
X836500Y988233D01*
G01Y991000D02*
X834000D01*
X835792Y989458D01*
Y991542D01*
G01X834417Y992808D02*
X834167Y993058D01*
X834042Y993350D01*
X834000Y993683D01*
X834083Y994100D01*
X834292Y994392D01*
X834542Y994475D01*
X834792Y994433D01*
X835000Y994267D01*
X835417Y993433D01*
X835708Y993058D01*
X836125Y992808D01*
X836500Y992725D01*
Y994475D01*
G01X836470Y979630D02*
X832470D01*
Y972230D01*
G01X832000Y986567D02*
X829500D01*
Y987608D01*
X829625Y987942D01*
X829792Y988150D01*
X830125Y988233D01*
X830458Y988150D01*
X830667Y987900D01*
X830792Y987608D01*
Y986567D01*
G01Y987608D02*
X832000Y988233D01*
G01X831500Y989583D02*
X831792Y989833D01*
X831958Y990167D01*
X832000Y990542D01*
X831958Y990875D01*
X831750Y991208D01*
X831500Y991417D01*
X831250Y991458D01*
X830958Y991375D01*
X830750Y991083D01*
X830667Y990792D01*
Y990417D01*
G01Y990792D02*
X830542Y991042D01*
X830333Y991250D01*
X830083Y991333D01*
X829833Y991250D01*
X829625Y991042D01*
X829500Y990667D01*
X829542Y990292D01*
X829708Y989917D01*
G01X832000Y993517D02*
X831458Y993600D01*
X831000Y993725D01*
X830583Y993892D01*
X830125Y994100D01*
X829500Y994433D01*
Y992767D01*
G01X828470Y972230D02*
X832470D01*
Y979630D01*
G01X846000Y963567D02*
X843500D01*
Y964608D01*
X843625Y964942D01*
X843792Y965150D01*
X844125Y965233D01*
X844458Y965150D01*
X844667Y964900D01*
X844792Y964608D01*
Y963567D01*
G01Y964608D02*
X846000Y965233D01*
G01X845500Y966583D02*
X845792Y966833D01*
X845958Y967167D01*
X846000Y967542D01*
X845958Y967875D01*
X845750Y968208D01*
X845500Y968417D01*
X845250Y968458D01*
X844958Y968375D01*
X844750Y968083D01*
X844667Y967792D01*
Y967417D01*
G01Y967792D02*
X844542Y968042D01*
X844333Y968250D01*
X844083Y968333D01*
X843833Y968250D01*
X843625Y968042D01*
X843500Y967667D01*
X843542Y967292D01*
X843708Y966917D01*
G01X845625Y969683D02*
X845833Y969933D01*
X845958Y970225D01*
X846000Y970600D01*
X845917Y970975D01*
X845750Y971267D01*
X845458Y971475D01*
X845125Y971517D01*
X844792Y971433D01*
X844583Y971225D01*
X844417Y970933D01*
X844375Y970642D01*
X844417Y970350D01*
X844583Y969975D01*
X843500Y970100D01*
Y971225D01*
G01X837970Y964470D02*
X841970D01*
Y971870D01*
G01X797533Y970000D02*
Y968208D01*
X797700Y967833D01*
X798033Y967583D01*
X798450Y967500D01*
X798867Y967583D01*
X799200Y967833D01*
X799367Y968208D01*
Y970000D01*
G01X800633Y967875D02*
X800883Y967667D01*
X801175Y967542D01*
X801550Y967500D01*
X801925Y967583D01*
X802217Y967750D01*
X802425Y968042D01*
X802467Y968375D01*
X802383Y968708D01*
X802175Y968917D01*
X801883Y969083D01*
X801592Y969125D01*
X801300Y969083D01*
X800925Y968917D01*
X801050Y970000D01*
X802175D01*
G01X798200Y1234900D02*
Y1232400D01*
G01X797242Y1234900D02*
X799158D01*
G01X802217Y1234692D02*
X801967Y1234817D01*
X801675Y1234900D01*
X801342D01*
X800967Y1234775D01*
X800675Y1234567D01*
X800467Y1234317D01*
X800300Y1233900D01*
X800258Y1233525D01*
X800342Y1233150D01*
X800467Y1232900D01*
X800717Y1232650D01*
X801008Y1232483D01*
X801300Y1232400D01*
X801592D01*
X801883Y1232483D01*
X802133Y1232608D01*
X802342Y1232775D01*
G01X803608Y1233442D02*
X803900Y1233733D01*
X804150Y1233900D01*
X804483Y1233983D01*
X804775Y1233900D01*
X804983Y1233733D01*
X805150Y1233483D01*
X805192Y1233192D01*
X805150Y1232942D01*
X804983Y1232692D01*
X804733Y1232483D01*
X804442Y1232400D01*
X804108Y1232483D01*
X803817Y1232733D01*
X803650Y1233108D01*
X803608Y1233525D01*
X803692Y1234067D01*
X803817Y1234358D01*
X804025Y1234650D01*
X804317Y1234858D01*
X804608Y1234900D01*
X804900Y1234817D01*
X805108Y1234608D01*
G01X787300Y1193750D02*
Y1225350D01*
X792000Y1230050D01*
X810600D01*
X815300Y1225350D01*
Y1193750D01*
X787300D01*
G01X857639Y1308418D02*
X857514Y1308168D01*
X857431Y1307876D01*
Y1307543D01*
X857556Y1307168D01*
X857764Y1306876D01*
X858014Y1306668D01*
X858431Y1306501D01*
X858806Y1306459D01*
X859181Y1306543D01*
X859431Y1306668D01*
X859681Y1306918D01*
X859848Y1307209D01*
X859931Y1307501D01*
Y1307793D01*
X859848Y1308084D01*
X859723Y1308334D01*
X859556Y1308543D01*
G01Y1309684D02*
X859764Y1309934D01*
X859889Y1310226D01*
X859931Y1310601D01*
X859848Y1310976D01*
X859681Y1311268D01*
X859389Y1311476D01*
X859056Y1311518D01*
X858723Y1311434D01*
X858514Y1311226D01*
X858348Y1310934D01*
X858306Y1310643D01*
X858348Y1310351D01*
X858514Y1309976D01*
X857431Y1310101D01*
Y1311226D01*
G01X859931Y1313701D02*
X857431D01*
X857931Y1313201D01*
G01X859931D02*
Y1314201D01*
G01X859431Y1315884D02*
X859723Y1316134D01*
X859889Y1316468D01*
X859931Y1316843D01*
X859889Y1317176D01*
X859681Y1317509D01*
X859431Y1317718D01*
X859181Y1317759D01*
X858889Y1317676D01*
X858681Y1317384D01*
X858598Y1317093D01*
Y1316718D01*
G01Y1317093D02*
X858473Y1317343D01*
X858264Y1317551D01*
X858014Y1317634D01*
X857764Y1317551D01*
X857556Y1317343D01*
X857431Y1316968D01*
X857473Y1316593D01*
X857639Y1316218D01*
G01X853963Y1286166D02*
Y1304866D01*
X864263D01*
Y1286166D01*
X853963D01*
G01X803050Y1295300D02*
X802717Y1295342D01*
X802425Y1295508D01*
X802175Y1295758D01*
X802008Y1296050D01*
X801925Y1296383D01*
Y1296717D01*
X802008Y1297050D01*
X802175Y1297342D01*
X802425Y1297592D01*
X802717Y1297758D01*
X803050Y1297800D01*
X803383Y1297758D01*
X803675Y1297592D01*
X803925Y1297342D01*
X804092Y1297050D01*
X804175Y1296717D01*
Y1296383D01*
X804092Y1296050D01*
X803925Y1295758D01*
X803675Y1295508D01*
X803383Y1295342D01*
X803050Y1295300D01*
G01X803383Y1295967D02*
X803883Y1295300D01*
G01X806150D02*
Y1297800D01*
X805650Y1297300D01*
G01Y1295300D02*
X806650D01*
G01X808542Y1295592D02*
X808833Y1295383D01*
X809167Y1295300D01*
X809500Y1295383D01*
X809792Y1295633D01*
X810000Y1296008D01*
X810083Y1296383D01*
Y1296842D01*
X810000Y1297217D01*
X809792Y1297550D01*
X809542Y1297717D01*
X809250Y1297800D01*
X808917Y1297717D01*
X808667Y1297550D01*
X808500Y1297300D01*
X808417Y1296967D01*
X808500Y1296675D01*
X808708Y1296383D01*
X808958Y1296217D01*
X809250Y1296175D01*
X809583Y1296258D01*
X809833Y1296467D01*
X810083Y1296842D01*
G01X811433Y1295675D02*
X811683Y1295467D01*
X811975Y1295342D01*
X812350Y1295300D01*
X812725Y1295383D01*
X813017Y1295550D01*
X813225Y1295842D01*
X813267Y1296175D01*
X813183Y1296508D01*
X812975Y1296717D01*
X812683Y1296883D01*
X812392Y1296925D01*
X812100Y1296883D01*
X811725Y1296717D01*
X811850Y1297800D01*
X812975D01*
G01X813631Y1301185D02*
X783631D01*
Y1323985D01*
X813631D01*
Y1301185D01*
G01X824157Y1331971D02*
Y1334471D01*
X825198D01*
X825532Y1334346D01*
X825740Y1334179D01*
X825823Y1333846D01*
X825740Y1333513D01*
X825490Y1333304D01*
X825198Y1333179D01*
X824157D01*
G01X825198D02*
X825823Y1331971D01*
G01X828090D02*
Y1334471D01*
X827590Y1333971D01*
G01Y1331971D02*
X828590D01*
G01X831190Y1334471D02*
X830857Y1334388D01*
X830607Y1334179D01*
X830440Y1333929D01*
X830315Y1333596D01*
X830273Y1333221D01*
X830315Y1332846D01*
X830440Y1332513D01*
X830607Y1332263D01*
X830857Y1332054D01*
X831190Y1331971D01*
X831523Y1332054D01*
X831773Y1332263D01*
X831940Y1332513D01*
X832065Y1332846D01*
X832107Y1333221D01*
X832065Y1333596D01*
X831940Y1333929D01*
X831773Y1334179D01*
X831523Y1334388D01*
X831190Y1334471D01*
G01X834290Y1331971D02*
Y1334471D01*
X833790Y1333971D01*
G01Y1331971D02*
X834790D01*
G01X836598Y1333013D02*
X836890Y1333304D01*
X837140Y1333471D01*
X837473Y1333554D01*
X837765Y1333471D01*
X837973Y1333304D01*
X838140Y1333054D01*
X838182Y1332763D01*
X838140Y1332513D01*
X837973Y1332263D01*
X837723Y1332054D01*
X837432Y1331971D01*
X837098Y1332054D01*
X836807Y1332304D01*
X836640Y1332679D01*
X836598Y1333096D01*
X836682Y1333638D01*
X836807Y1333929D01*
X837015Y1334221D01*
X837307Y1334429D01*
X837598Y1334471D01*
X837890Y1334388D01*
X838098Y1334179D01*
G01X807300Y1329500D02*
X815100D01*
G01X807300Y1336500D02*
Y1329500D01*
G01X820700D02*
Y1336500D01*
G01X814300Y1329500D02*
X820700D01*
G01X865207Y1374250D02*
X862707D01*
Y1375291D01*
X862832Y1375625D01*
X862999Y1375833D01*
X863332Y1375916D01*
X863665Y1375833D01*
X863874Y1375583D01*
X863999Y1375291D01*
Y1374250D01*
G01Y1375291D02*
X865207Y1375916D01*
G01Y1378183D02*
X862707D01*
X863207Y1377683D01*
G01X865207D02*
Y1378683D01*
G01X862707Y1381283D02*
X862790Y1380950D01*
X862999Y1380700D01*
X863249Y1380533D01*
X863582Y1380408D01*
X863957Y1380366D01*
X864332Y1380408D01*
X864665Y1380533D01*
X864915Y1380700D01*
X865124Y1380950D01*
X865207Y1381283D01*
X865124Y1381616D01*
X864915Y1381866D01*
X864665Y1382033D01*
X864332Y1382158D01*
X863957Y1382200D01*
X863582Y1382158D01*
X863249Y1382033D01*
X862999Y1381866D01*
X862790Y1381616D01*
X862707Y1381283D01*
G01X863124Y1383591D02*
X862874Y1383841D01*
X862749Y1384133D01*
X862707Y1384466D01*
X862790Y1384883D01*
X862999Y1385175D01*
X863249Y1385258D01*
X863499Y1385216D01*
X863707Y1385050D01*
X864124Y1384216D01*
X864415Y1383841D01*
X864832Y1383591D01*
X865207Y1383508D01*
Y1385258D01*
G01Y1387483D02*
X862707D01*
X863207Y1386983D01*
G01X865207D02*
Y1387983D01*
G01X856167Y1401380D02*
X855917Y1401505D01*
X855625Y1401588D01*
X855292D01*
X854917Y1401463D01*
X854625Y1401255D01*
X854417Y1401005D01*
X854250Y1400588D01*
X854208Y1400213D01*
X854292Y1399838D01*
X854417Y1399588D01*
X854667Y1399338D01*
X854958Y1399171D01*
X855250Y1399088D01*
X855542D01*
X855833Y1399171D01*
X856083Y1399296D01*
X856292Y1399463D01*
G01X857433D02*
X857683Y1399255D01*
X857975Y1399130D01*
X858350Y1399088D01*
X858725Y1399171D01*
X859017Y1399338D01*
X859225Y1399630D01*
X859267Y1399963D01*
X859183Y1400296D01*
X858975Y1400505D01*
X858683Y1400671D01*
X858392Y1400713D01*
X858100Y1400671D01*
X857725Y1400505D01*
X857850Y1401588D01*
X858975D01*
G01X860533Y1399463D02*
X860783Y1399255D01*
X861075Y1399130D01*
X861450Y1399088D01*
X861825Y1399171D01*
X862117Y1399338D01*
X862325Y1399630D01*
X862367Y1399963D01*
X862283Y1400296D01*
X862075Y1400505D01*
X861783Y1400671D01*
X861492Y1400713D01*
X861200Y1400671D01*
X860825Y1400505D01*
X860950Y1401588D01*
X862075D01*
G01X863758Y1401171D02*
X864008Y1401421D01*
X864300Y1401546D01*
X864633Y1401588D01*
X865050Y1401505D01*
X865342Y1401296D01*
X865425Y1401046D01*
X865383Y1400796D01*
X865217Y1400588D01*
X864383Y1400171D01*
X864008Y1399880D01*
X863758Y1399463D01*
X863675Y1399088D01*
X865425D01*
G01X803050Y1338200D02*
X802717Y1338242D01*
X802425Y1338408D01*
X802175Y1338658D01*
X802008Y1338950D01*
X801925Y1339283D01*
Y1339617D01*
X802008Y1339950D01*
X802175Y1340242D01*
X802425Y1340492D01*
X802717Y1340658D01*
X803050Y1340700D01*
X803383Y1340658D01*
X803675Y1340492D01*
X803925Y1340242D01*
X804092Y1339950D01*
X804175Y1339617D01*
Y1339283D01*
X804092Y1338950D01*
X803925Y1338658D01*
X803675Y1338408D01*
X803383Y1338242D01*
X803050Y1338200D01*
G01X803383Y1338867D02*
X803883Y1338200D01*
G01X806150D02*
Y1340700D01*
X805650Y1340200D01*
G01Y1338200D02*
X806650D01*
G01X808542Y1338492D02*
X808833Y1338283D01*
X809167Y1338200D01*
X809500Y1338283D01*
X809792Y1338533D01*
X810000Y1338908D01*
X810083Y1339283D01*
Y1339742D01*
X810000Y1340117D01*
X809792Y1340450D01*
X809542Y1340617D01*
X809250Y1340700D01*
X808917Y1340617D01*
X808667Y1340450D01*
X808500Y1340200D01*
X808417Y1339867D01*
X808500Y1339575D01*
X808708Y1339283D01*
X808958Y1339117D01*
X809250Y1339075D01*
X809583Y1339158D01*
X809833Y1339367D01*
X810083Y1339742D01*
G01X812267Y1338200D02*
X812350Y1338742D01*
X812475Y1339200D01*
X812642Y1339617D01*
X812850Y1340075D01*
X813183Y1340700D01*
X811517D01*
G01X814101Y1343691D02*
X784101D01*
Y1366491D01*
X814101D01*
Y1343691D01*
G01X800233Y1411211D02*
X799900Y1411253D01*
X799608Y1411419D01*
X799358Y1411669D01*
X799191Y1411961D01*
X799108Y1412294D01*
Y1412628D01*
X799191Y1412961D01*
X799358Y1413253D01*
X799608Y1413503D01*
X799900Y1413669D01*
X800233Y1413711D01*
X800566Y1413669D01*
X800858Y1413503D01*
X801108Y1413253D01*
X801275Y1412961D01*
X801358Y1412628D01*
Y1412294D01*
X801275Y1411961D01*
X801108Y1411669D01*
X800858Y1411419D01*
X800566Y1411253D01*
X800233Y1411211D01*
G01X800566Y1411878D02*
X801066Y1411211D01*
G01X803333D02*
Y1413711D01*
X802833Y1413211D01*
G01Y1411211D02*
X803833D01*
G01X805725Y1411503D02*
X806016Y1411294D01*
X806350Y1411211D01*
X806683Y1411294D01*
X806975Y1411544D01*
X807183Y1411919D01*
X807266Y1412294D01*
Y1412753D01*
X807183Y1413128D01*
X806975Y1413461D01*
X806725Y1413628D01*
X806433Y1413711D01*
X806100Y1413628D01*
X805850Y1413461D01*
X805683Y1413211D01*
X805600Y1412878D01*
X805683Y1412586D01*
X805891Y1412294D01*
X806141Y1412128D01*
X806433Y1412086D01*
X806766Y1412169D01*
X807016Y1412378D01*
X807266Y1412753D01*
G01X808825Y1411503D02*
X809116Y1411294D01*
X809450Y1411211D01*
X809783Y1411294D01*
X810075Y1411544D01*
X810283Y1411919D01*
X810366Y1412294D01*
Y1412753D01*
X810283Y1413128D01*
X810075Y1413461D01*
X809825Y1413628D01*
X809533Y1413711D01*
X809200Y1413628D01*
X808950Y1413461D01*
X808783Y1413211D01*
X808700Y1412878D01*
X808783Y1412586D01*
X808991Y1412294D01*
X809241Y1412128D01*
X809533Y1412086D01*
X809866Y1412169D01*
X810116Y1412378D01*
X810366Y1412753D01*
G01X813880Y1381359D02*
X783880D01*
Y1404159D01*
X813880D01*
Y1381359D01*
G01X838417Y1413000D02*
Y1415500D01*
X839458D01*
X839792Y1415375D01*
X840000Y1415208D01*
X840083Y1414875D01*
X840000Y1414542D01*
X839750Y1414333D01*
X839458Y1414208D01*
X838417D01*
G01X839458D02*
X840083Y1413000D01*
G01X842350D02*
Y1415500D01*
X841850Y1415000D01*
G01Y1413000D02*
X842850D01*
G01X844533Y1413375D02*
X844783Y1413167D01*
X845075Y1413042D01*
X845450Y1413000D01*
X845825Y1413083D01*
X846117Y1413250D01*
X846325Y1413542D01*
X846367Y1413875D01*
X846283Y1414208D01*
X846075Y1414417D01*
X845783Y1414583D01*
X845492Y1414625D01*
X845200Y1414583D01*
X844825Y1414417D01*
X844950Y1415500D01*
X846075D01*
G01X847758Y1415083D02*
X848008Y1415333D01*
X848300Y1415458D01*
X848633Y1415500D01*
X849050Y1415417D01*
X849342Y1415208D01*
X849425Y1414958D01*
X849383Y1414708D01*
X849217Y1414500D01*
X848383Y1414083D01*
X848008Y1413792D01*
X847758Y1413375D01*
X847675Y1413000D01*
X849425D01*
G01X836795Y1396384D02*
X841995D01*
G01X836795Y1389384D02*
X844595D01*
G01X836795Y1396384D02*
Y1389384D01*
G01X850195Y1396384D02*
X841495D01*
G01X850195Y1389384D02*
Y1396384D01*
G01X843795Y1389384D02*
X850195D01*
G01X836917Y1417500D02*
Y1420000D01*
X837958D01*
X838292Y1419875D01*
X838500Y1419708D01*
X838583Y1419375D01*
X838500Y1419042D01*
X838250Y1418833D01*
X837958Y1418708D01*
X836917D01*
G01X837958D02*
X838583Y1417500D01*
G01X840850D02*
Y1420000D01*
X840350Y1419500D01*
G01Y1417500D02*
X841350D01*
G01X843950Y1420000D02*
X843617Y1419917D01*
X843367Y1419708D01*
X843200Y1419458D01*
X843075Y1419125D01*
X843033Y1418750D01*
X843075Y1418375D01*
X843200Y1418042D01*
X843367Y1417792D01*
X843617Y1417583D01*
X843950Y1417500D01*
X844283Y1417583D01*
X844533Y1417792D01*
X844700Y1418042D01*
X844825Y1418375D01*
X844867Y1418750D01*
X844825Y1419125D01*
X844700Y1419458D01*
X844533Y1419708D01*
X844283Y1419917D01*
X843950Y1420000D01*
G01X846258Y1419583D02*
X846508Y1419833D01*
X846800Y1419958D01*
X847133Y1420000D01*
X847550Y1419917D01*
X847842Y1419708D01*
X847925Y1419458D01*
X847883Y1419208D01*
X847717Y1419000D01*
X846883Y1418583D01*
X846508Y1418292D01*
X846258Y1417875D01*
X846175Y1417500D01*
X847925D01*
G01X849358Y1419583D02*
X849608Y1419833D01*
X849900Y1419958D01*
X850233Y1420000D01*
X850650Y1419917D01*
X850942Y1419708D01*
X851025Y1419458D01*
X850983Y1419208D01*
X850817Y1419000D01*
X849983Y1418583D01*
X849608Y1418292D01*
X849358Y1417875D01*
X849275Y1417500D01*
X851025D01*
G01X850156Y1397036D02*
X844956D01*
G01X850156Y1404036D02*
X842356D01*
G01X850156Y1397036D02*
Y1404036D01*
G01X836756Y1397036D02*
X845456D01*
G01X836756Y1404036D02*
Y1397036D01*
G01X843156Y1404036D02*
X836756D01*
G01X814373Y1408150D02*
Y1410650D01*
X815414D01*
X815748Y1410525D01*
X815956Y1410358D01*
X816039Y1410025D01*
X815956Y1409692D01*
X815706Y1409483D01*
X815414Y1409358D01*
X814373D01*
G01X815414D02*
X816039Y1408150D01*
G01X818306D02*
Y1410650D01*
X817806Y1410150D01*
G01Y1408150D02*
X818806D01*
G01X821406Y1410650D02*
X821073Y1410567D01*
X820823Y1410358D01*
X820656Y1410108D01*
X820531Y1409775D01*
X820489Y1409400D01*
X820531Y1409025D01*
X820656Y1408692D01*
X820823Y1408442D01*
X821073Y1408233D01*
X821406Y1408150D01*
X821739Y1408233D01*
X821989Y1408442D01*
X822156Y1408692D01*
X822281Y1409025D01*
X822323Y1409400D01*
X822281Y1409775D01*
X822156Y1410108D01*
X821989Y1410358D01*
X821739Y1410567D01*
X821406Y1410650D01*
G01X823714Y1410233D02*
X823964Y1410483D01*
X824256Y1410608D01*
X824589Y1410650D01*
X825006Y1410567D01*
X825298Y1410358D01*
X825381Y1410108D01*
X825339Y1409858D01*
X825173Y1409650D01*
X824339Y1409233D01*
X823964Y1408942D01*
X823714Y1408525D01*
X823631Y1408150D01*
X825381D01*
G01X827606Y1410650D02*
X827273Y1410567D01*
X827023Y1410358D01*
X826856Y1410108D01*
X826731Y1409775D01*
X826689Y1409400D01*
X826731Y1409025D01*
X826856Y1408692D01*
X827023Y1408442D01*
X827273Y1408233D01*
X827606Y1408150D01*
X827939Y1408233D01*
X828189Y1408442D01*
X828356Y1408692D01*
X828481Y1409025D01*
X828523Y1409400D01*
X828481Y1409775D01*
X828356Y1410108D01*
X828189Y1410358D01*
X827939Y1410567D01*
X827606Y1410650D01*
G01X819842Y1406156D02*
X825042D01*
G01X819842Y1399156D02*
X827642D01*
G01X819842Y1406156D02*
Y1399156D01*
G01X833242Y1406156D02*
X824542D01*
G01X833242Y1399156D02*
Y1406156D01*
G01X826842Y1399156D02*
X833242D01*
G01X824250Y1370678D02*
Y1373178D01*
X825291D01*
X825625Y1373053D01*
X825833Y1372886D01*
X825916Y1372553D01*
X825833Y1372220D01*
X825583Y1372011D01*
X825291Y1371886D01*
X824250D01*
G01X825291D02*
X825916Y1370678D01*
G01X828183D02*
Y1373178D01*
X827683Y1372678D01*
G01Y1370678D02*
X828683D01*
G01X831283Y1373178D02*
X830950Y1373095D01*
X830700Y1372886D01*
X830533Y1372636D01*
X830408Y1372303D01*
X830366Y1371928D01*
X830408Y1371553D01*
X830533Y1371220D01*
X830700Y1370970D01*
X830950Y1370761D01*
X831283Y1370678D01*
X831616Y1370761D01*
X831866Y1370970D01*
X832033Y1371220D01*
X832158Y1371553D01*
X832200Y1371928D01*
X832158Y1372303D01*
X832033Y1372636D01*
X831866Y1372886D01*
X831616Y1373095D01*
X831283Y1373178D01*
G01X834383Y1370678D02*
Y1373178D01*
X833883Y1372678D01*
G01Y1370678D02*
X834883D01*
G01X837483D02*
X837775Y1370720D01*
X838108Y1370845D01*
X838316Y1371053D01*
X838400Y1371345D01*
X838316Y1371636D01*
X838066Y1371886D01*
X837691Y1372011D01*
X837275D01*
X837025Y1372095D01*
X836816Y1372303D01*
X836733Y1372595D01*
X836858Y1372886D01*
X837150Y1373095D01*
X837483Y1373178D01*
X837816Y1373095D01*
X838108Y1372886D01*
X838233Y1372595D01*
X838150Y1372303D01*
X837941Y1372095D01*
X837691Y1372011D01*
X837275D01*
X836900Y1371886D01*
X836650Y1371636D01*
X836566Y1371345D01*
X836650Y1371053D01*
X836858Y1370845D01*
X837191Y1370720D01*
X837483Y1370678D01*
G01X807300Y1375000D02*
X812500D01*
G01X807300Y1368000D02*
X815100D01*
G01X807300Y1375000D02*
Y1368000D01*
G01X820700Y1375000D02*
X812000D01*
G01X820700Y1368000D02*
Y1375000D01*
G01X814300Y1368000D02*
X820700D01*
G01X807300Y1336500D02*
X812500D01*
G01X820700D02*
X812000D01*
G01X773517Y1459000D02*
Y1461500D01*
X774558D01*
X774892Y1461375D01*
X775100Y1461208D01*
X775183Y1460875D01*
X775100Y1460542D01*
X774850Y1460333D01*
X774558Y1460208D01*
X773517D01*
G01X774558D02*
X775183Y1459000D01*
G01X777450D02*
Y1461500D01*
X776950Y1461000D01*
G01Y1459000D02*
X777950D01*
G01X780467D02*
X780550Y1459542D01*
X780675Y1460000D01*
X780842Y1460417D01*
X781050Y1460875D01*
X781383Y1461500D01*
X779717D01*
G01X783650Y1459000D02*
X783942Y1459042D01*
X784275Y1459167D01*
X784483Y1459375D01*
X784567Y1459667D01*
X784483Y1459958D01*
X784233Y1460208D01*
X783858Y1460333D01*
X783442D01*
X783192Y1460417D01*
X782983Y1460625D01*
X782900Y1460917D01*
X783025Y1461208D01*
X783317Y1461417D01*
X783650Y1461500D01*
X783983Y1461417D01*
X784275Y1461208D01*
X784400Y1460917D01*
X784317Y1460625D01*
X784108Y1460417D01*
X783858Y1460333D01*
X783442D01*
X783067Y1460208D01*
X782817Y1459958D01*
X782733Y1459667D01*
X782817Y1459375D01*
X783025Y1459167D01*
X783358Y1459042D01*
X783650Y1459000D01*
G01X786467D02*
Y1461500D01*
X787508D01*
X787842Y1461375D01*
X788050Y1461208D01*
X788133Y1460875D01*
X788050Y1460542D01*
X787800Y1460333D01*
X787508Y1460208D01*
X786467D01*
G01X787508D02*
X788133Y1459000D01*
G01X790400D02*
Y1461500D01*
X789900Y1461000D01*
G01Y1459000D02*
X790900D01*
G01X792708Y1461083D02*
X792958Y1461333D01*
X793250Y1461458D01*
X793583Y1461500D01*
X794000Y1461417D01*
X794292Y1461208D01*
X794375Y1460958D01*
X794333Y1460708D01*
X794167Y1460500D01*
X793333Y1460083D01*
X792958Y1459792D01*
X792708Y1459375D01*
X792625Y1459000D01*
X794375D01*
G01X795892Y1459292D02*
X796183Y1459083D01*
X796517Y1459000D01*
X796850Y1459083D01*
X797142Y1459333D01*
X797350Y1459708D01*
X797433Y1460083D01*
Y1460542D01*
X797350Y1460917D01*
X797142Y1461250D01*
X796892Y1461417D01*
X796600Y1461500D01*
X796267Y1461417D01*
X796017Y1461250D01*
X795850Y1461000D01*
X795767Y1460667D01*
X795850Y1460375D01*
X796058Y1460083D01*
X796308Y1459917D01*
X796600Y1459875D01*
X796933Y1459958D01*
X797183Y1460167D01*
X797433Y1460542D01*
G01X799700Y1459000D02*
X799992Y1459042D01*
X800325Y1459167D01*
X800533Y1459375D01*
X800617Y1459667D01*
X800533Y1459958D01*
X800283Y1460208D01*
X799908Y1460333D01*
X799492D01*
X799242Y1460417D01*
X799033Y1460625D01*
X798950Y1460917D01*
X799075Y1461208D01*
X799367Y1461417D01*
X799700Y1461500D01*
X800033Y1461417D01*
X800325Y1461208D01*
X800450Y1460917D01*
X800367Y1460625D01*
X800158Y1460417D01*
X799908Y1460333D01*
X799492D01*
X799117Y1460208D01*
X798867Y1459958D01*
X798783Y1459667D01*
X798867Y1459375D01*
X799075Y1459167D01*
X799408Y1459042D01*
X799700Y1459000D01*
G01X771500Y1454467D02*
X769000D01*
Y1455508D01*
X769125Y1455842D01*
X769292Y1456050D01*
X769625Y1456133D01*
X769958Y1456050D01*
X770167Y1455800D01*
X770292Y1455508D01*
Y1454467D01*
G01Y1455508D02*
X771500Y1456133D01*
G01Y1458400D02*
X769000D01*
X769500Y1457900D01*
G01X771500D02*
Y1458900D01*
G01X771000Y1460583D02*
X771292Y1460833D01*
X771458Y1461167D01*
X771500Y1461542D01*
X771458Y1461875D01*
X771250Y1462208D01*
X771000Y1462417D01*
X770750Y1462458D01*
X770458Y1462375D01*
X770250Y1462083D01*
X770167Y1461792D01*
Y1461417D01*
G01Y1461792D02*
X770042Y1462042D01*
X769833Y1462250D01*
X769583Y1462333D01*
X769333Y1462250D01*
X769125Y1462042D01*
X769000Y1461667D01*
X769042Y1461292D01*
X769208Y1460917D01*
G01X769000Y1464600D02*
X769083Y1464267D01*
X769292Y1464017D01*
X769542Y1463850D01*
X769875Y1463725D01*
X770250Y1463683D01*
X770625Y1463725D01*
X770958Y1463850D01*
X771208Y1464017D01*
X771417Y1464267D01*
X771500Y1464600D01*
X771417Y1464933D01*
X771208Y1465183D01*
X770958Y1465350D01*
X770625Y1465475D01*
X770250Y1465517D01*
X769875Y1465475D01*
X769542Y1465350D01*
X769292Y1465183D01*
X769083Y1464933D01*
X769000Y1464600D01*
G01X769417Y1466908D02*
X769167Y1467158D01*
X769042Y1467450D01*
X769000Y1467783D01*
X769083Y1468200D01*
X769292Y1468492D01*
X769542Y1468575D01*
X769792Y1468533D01*
X770000Y1468367D01*
X770417Y1467533D01*
X770708Y1467158D01*
X771125Y1466908D01*
X771500Y1466825D01*
Y1468575D01*
G01X786467Y1454500D02*
Y1457000D01*
X787508D01*
X787842Y1456875D01*
X788050Y1456708D01*
X788133Y1456375D01*
X788050Y1456042D01*
X787800Y1455833D01*
X787508Y1455708D01*
X786467D01*
G01X787508D02*
X788133Y1454500D01*
G01X790400D02*
Y1457000D01*
X789900Y1456500D01*
G01Y1454500D02*
X790900D01*
G01X792583Y1455000D02*
X792833Y1454708D01*
X793167Y1454542D01*
X793542Y1454500D01*
X793875Y1454542D01*
X794208Y1454750D01*
X794417Y1455000D01*
X794458Y1455250D01*
X794375Y1455542D01*
X794083Y1455750D01*
X793792Y1455833D01*
X793417D01*
G01X793792D02*
X794042Y1455958D01*
X794250Y1456167D01*
X794333Y1456417D01*
X794250Y1456667D01*
X794042Y1456875D01*
X793667Y1457000D01*
X793292Y1456958D01*
X792917Y1456792D01*
G01X796600Y1457000D02*
X796267Y1456917D01*
X796017Y1456708D01*
X795850Y1456458D01*
X795725Y1456125D01*
X795683Y1455750D01*
X795725Y1455375D01*
X795850Y1455042D01*
X796017Y1454792D01*
X796267Y1454583D01*
X796600Y1454500D01*
X796933Y1454583D01*
X797183Y1454792D01*
X797350Y1455042D01*
X797475Y1455375D01*
X797517Y1455750D01*
X797475Y1456125D01*
X797350Y1456458D01*
X797183Y1456708D01*
X796933Y1456917D01*
X796600Y1457000D01*
G01X798908Y1455542D02*
X799200Y1455833D01*
X799450Y1456000D01*
X799783Y1456083D01*
X800075Y1456000D01*
X800283Y1455833D01*
X800450Y1455583D01*
X800492Y1455292D01*
X800450Y1455042D01*
X800283Y1454792D01*
X800033Y1454583D01*
X799742Y1454500D01*
X799408Y1454583D01*
X799117Y1454833D01*
X798950Y1455208D01*
X798908Y1455625D01*
X798992Y1456167D01*
X799117Y1456458D01*
X799325Y1456750D01*
X799617Y1456958D01*
X799908Y1457000D01*
X800200Y1456917D01*
X800408Y1456708D01*
G01X774350Y1454500D02*
X774017Y1454542D01*
X773725Y1454708D01*
X773475Y1454958D01*
X773308Y1455250D01*
X773225Y1455583D01*
Y1455917D01*
X773308Y1456250D01*
X773475Y1456542D01*
X773725Y1456792D01*
X774017Y1456958D01*
X774350Y1457000D01*
X774683Y1456958D01*
X774975Y1456792D01*
X775225Y1456542D01*
X775392Y1456250D01*
X775475Y1455917D01*
Y1455583D01*
X775392Y1455250D01*
X775225Y1454958D01*
X774975Y1454708D01*
X774683Y1454542D01*
X774350Y1454500D01*
G01X774683Y1455167D02*
X775183Y1454500D01*
G01X776658Y1456583D02*
X776908Y1456833D01*
X777200Y1456958D01*
X777533Y1457000D01*
X777950Y1456917D01*
X778242Y1456708D01*
X778325Y1456458D01*
X778283Y1456208D01*
X778117Y1456000D01*
X777283Y1455583D01*
X776908Y1455292D01*
X776658Y1454875D01*
X776575Y1454500D01*
X778325D01*
G01X780550D02*
Y1457000D01*
X780050Y1456500D01*
G01Y1454500D02*
X781050D01*
G01X782858Y1455542D02*
X783150Y1455833D01*
X783400Y1456000D01*
X783733Y1456083D01*
X784025Y1456000D01*
X784233Y1455833D01*
X784400Y1455583D01*
X784442Y1455292D01*
X784400Y1455042D01*
X784233Y1454792D01*
X783983Y1454583D01*
X783692Y1454500D01*
X783358Y1454583D01*
X783067Y1454833D01*
X782900Y1455208D01*
X782858Y1455625D01*
X782942Y1456167D01*
X783067Y1456458D01*
X783275Y1456750D01*
X783567Y1456958D01*
X783858Y1457000D01*
X784150Y1456917D01*
X784358Y1456708D01*
G01X950246Y4490D02*
X950646Y4890D01*
X951113Y5090D01*
X951646Y5157D01*
X952313Y5024D01*
X952780Y4690D01*
X952913Y4290D01*
X952846Y3890D01*
X952580Y3557D01*
X951246Y2890D01*
X950646Y2424D01*
X950246Y1757D01*
X950113Y1157D01*
X952913D01*
G01X920018D02*
Y5157D01*
X919218Y4357D01*
G01Y1157D02*
X920818D01*
G01X873236Y433555D02*
X870736D01*
Y434596D01*
X870861Y434930D01*
X871028Y435138D01*
X871361Y435221D01*
X871694Y435138D01*
X871903Y434888D01*
X872028Y434596D01*
Y433555D01*
G01Y434596D02*
X873236Y435221D01*
G01Y437488D02*
X870736D01*
X871236Y436988D01*
G01X873236D02*
Y437988D01*
G01X872194Y439796D02*
X871903Y440088D01*
X871736Y440338D01*
X871653Y440671D01*
X871736Y440963D01*
X871903Y441171D01*
X872153Y441338D01*
X872444Y441380D01*
X872694Y441338D01*
X872944Y441171D01*
X873153Y440921D01*
X873236Y440630D01*
X873153Y440296D01*
X872903Y440005D01*
X872528Y439838D01*
X872111Y439796D01*
X871569Y439880D01*
X871278Y440005D01*
X870986Y440213D01*
X870778Y440505D01*
X870736Y440796D01*
X870819Y441088D01*
X871028Y441296D01*
G01X874137Y426592D02*
X870137D01*
Y419192D01*
G01X925390Y554761D02*
Y557261D01*
X926431D01*
X926765Y557136D01*
X926973Y556969D01*
X927056Y556636D01*
X926973Y556303D01*
X926723Y556094D01*
X926431Y555969D01*
X925390D01*
G01X926431D02*
X927056Y554761D01*
G01X929823D02*
Y557261D01*
X928281Y555469D01*
X930365D01*
G01X932923Y554761D02*
Y557261D01*
X931381Y555469D01*
X933465D01*
G01X935523Y557261D02*
X935190Y557178D01*
X934940Y556969D01*
X934773Y556719D01*
X934648Y556386D01*
X934606Y556011D01*
X934648Y555636D01*
X934773Y555303D01*
X934940Y555053D01*
X935190Y554844D01*
X935523Y554761D01*
X935856Y554844D01*
X936106Y555053D01*
X936273Y555303D01*
X936398Y555636D01*
X936440Y556011D01*
X936398Y556386D01*
X936273Y556719D01*
X936106Y556969D01*
X935856Y557178D01*
X935523Y557261D01*
G01X940673Y558600D02*
Y554600D01*
X948073D01*
G01X925917Y528100D02*
Y530600D01*
X926958D01*
X927292Y530475D01*
X927500Y530308D01*
X927583Y529975D01*
X927500Y529642D01*
X927250Y529433D01*
X926958Y529308D01*
X925917D01*
G01X926958D02*
X927583Y528100D01*
G01X928933Y528600D02*
X929183Y528308D01*
X929517Y528142D01*
X929892Y528100D01*
X930225Y528142D01*
X930558Y528350D01*
X930767Y528600D01*
X930808Y528850D01*
X930725Y529142D01*
X930433Y529350D01*
X930142Y529433D01*
X929767D01*
G01X930142D02*
X930392Y529558D01*
X930600Y529767D01*
X930683Y530017D01*
X930600Y530267D01*
X930392Y530475D01*
X930017Y530600D01*
X929642Y530558D01*
X929267Y530392D01*
G01X932867Y528100D02*
X932950Y528642D01*
X933075Y529100D01*
X933242Y529517D01*
X933450Y529975D01*
X933783Y530600D01*
X932117D01*
G01X936050Y528100D02*
Y530600D01*
X935550Y530100D01*
G01Y528100D02*
X936550D01*
G01X940388Y531107D02*
Y527107D01*
X947788D01*
G01X925346Y549540D02*
Y552040D01*
X926387D01*
X926721Y551915D01*
X926929Y551748D01*
X927012Y551415D01*
X926929Y551082D01*
X926679Y550873D01*
X926387Y550748D01*
X925346D01*
G01X926387D02*
X927012Y549540D01*
G01X929779D02*
Y552040D01*
X928237Y550248D01*
X930321D01*
G01X932879Y549540D02*
Y552040D01*
X931337Y550248D01*
X933421D01*
G01X935979Y549540D02*
Y552040D01*
X934437Y550248D01*
X936521D01*
G01X940629Y553379D02*
Y549379D01*
X948029D01*
G01X922744Y522684D02*
Y525184D01*
X923785D01*
X924119Y525059D01*
X924327Y524892D01*
X924410Y524559D01*
X924327Y524226D01*
X924077Y524017D01*
X923785Y523892D01*
X922744D01*
G01X923785D02*
X924410Y522684D01*
G01X927177D02*
Y525184D01*
X925635Y523392D01*
X927719D01*
G01X929777Y522684D02*
Y525184D01*
X929277Y524684D01*
G01Y522684D02*
X930277D01*
G01X932794D02*
X932877Y523226D01*
X933002Y523684D01*
X933169Y524101D01*
X933377Y524559D01*
X933710Y525184D01*
X932044D01*
G01X937527Y526023D02*
Y522023D01*
X944927D01*
G01X946500Y533717D02*
X944000D01*
Y534758D01*
X944125Y535092D01*
X944292Y535300D01*
X944625Y535383D01*
X944958Y535300D01*
X945167Y535050D01*
X945292Y534758D01*
Y533717D01*
G01Y534758D02*
X946500Y535383D01*
G01Y538150D02*
X944000D01*
X945792Y536608D01*
Y538692D01*
G01X945458Y539958D02*
X945167Y540250D01*
X945000Y540500D01*
X944917Y540833D01*
X945000Y541125D01*
X945167Y541333D01*
X945417Y541500D01*
X945708Y541542D01*
X945958Y541500D01*
X946208Y541333D01*
X946417Y541083D01*
X946500Y540792D01*
X946417Y540458D01*
X946167Y540167D01*
X945792Y540000D01*
X945375Y539958D01*
X944833Y540042D01*
X944542Y540167D01*
X944250Y540375D01*
X944042Y540667D01*
X944000Y540958D01*
X944083Y541250D01*
X944292Y541458D01*
G01X946000Y542933D02*
X946292Y543183D01*
X946458Y543517D01*
X946500Y543892D01*
X946458Y544225D01*
X946250Y544558D01*
X946000Y544767D01*
X945750Y544808D01*
X945458Y544725D01*
X945250Y544433D01*
X945167Y544142D01*
Y543767D01*
G01Y544142D02*
X945042Y544392D01*
X944833Y544600D01*
X944583Y544683D01*
X944333Y544600D01*
X944125Y544392D01*
X944000Y544017D01*
X944042Y543642D01*
X944208Y543267D01*
G01X952639Y552441D02*
X948639D01*
Y545041D01*
G01X947000Y503517D02*
X944500D01*
Y504558D01*
X944625Y504892D01*
X944792Y505100D01*
X945125Y505183D01*
X945458Y505100D01*
X945667Y504850D01*
X945792Y504558D01*
Y503517D01*
G01Y504558D02*
X947000Y505183D01*
G01Y507950D02*
X944500D01*
X946292Y506408D01*
Y508492D01*
G01X944917Y509758D02*
X944667Y510008D01*
X944542Y510300D01*
X944500Y510633D01*
X944583Y511050D01*
X944792Y511342D01*
X945042Y511425D01*
X945292Y511383D01*
X945500Y511217D01*
X945917Y510383D01*
X946208Y510008D01*
X946625Y509758D01*
X947000Y509675D01*
Y511425D01*
G01X944500Y513650D02*
X944583Y513317D01*
X944792Y513067D01*
X945042Y512900D01*
X945375Y512775D01*
X945750Y512733D01*
X946125Y512775D01*
X946458Y512900D01*
X946708Y513067D01*
X946917Y513317D01*
X947000Y513650D01*
X946917Y513983D01*
X946708Y514233D01*
X946458Y514400D01*
X946125Y514525D01*
X945750Y514567D01*
X945375Y514525D01*
X945042Y514400D01*
X944792Y514233D01*
X944583Y513983D01*
X944500Y513650D01*
G01X949587Y526082D02*
X945587D01*
Y518682D01*
G01X951500Y532617D02*
X949000D01*
Y533658D01*
X949125Y533992D01*
X949292Y534200D01*
X949625Y534283D01*
X949958Y534200D01*
X950167Y533950D01*
X950292Y533658D01*
Y532617D01*
G01Y533658D02*
X951500Y534283D01*
G01X950458Y535758D02*
X950167Y536050D01*
X950000Y536300D01*
X949917Y536633D01*
X950000Y536925D01*
X950167Y537133D01*
X950417Y537300D01*
X950708Y537342D01*
X950958Y537300D01*
X951208Y537133D01*
X951417Y536883D01*
X951500Y536592D01*
X951417Y536258D01*
X951167Y535967D01*
X950792Y535800D01*
X950375Y535758D01*
X949833Y535842D01*
X949542Y535967D01*
X949250Y536175D01*
X949042Y536467D01*
X949000Y536758D01*
X949083Y537050D01*
X949292Y537258D01*
G01X949000Y539650D02*
X949083Y539317D01*
X949292Y539067D01*
X949542Y538900D01*
X949875Y538775D01*
X950250Y538733D01*
X950625Y538775D01*
X950958Y538900D01*
X951208Y539067D01*
X951417Y539317D01*
X951500Y539650D01*
X951417Y539983D01*
X951208Y540233D01*
X950958Y540400D01*
X950625Y540525D01*
X950250Y540567D01*
X949875Y540525D01*
X949542Y540400D01*
X949292Y540233D01*
X949083Y539983D01*
X949000Y539650D01*
G01X951125Y541833D02*
X951333Y542083D01*
X951458Y542375D01*
X951500Y542750D01*
X951417Y543125D01*
X951250Y543417D01*
X950958Y543625D01*
X950625Y543667D01*
X950292Y543583D01*
X950083Y543375D01*
X949917Y543083D01*
X949875Y542792D01*
X949917Y542500D01*
X950083Y542125D01*
X949000Y542250D01*
Y543375D01*
G01X953000Y542400D02*
X957000D01*
Y549800D01*
G01X953600Y499917D02*
X951100D01*
Y500958D01*
X951225Y501292D01*
X951392Y501500D01*
X951725Y501583D01*
X952058Y501500D01*
X952267Y501250D01*
X952392Y500958D01*
Y499917D01*
G01Y500958D02*
X953600Y501583D01*
G01X952558Y503058D02*
X952267Y503350D01*
X952100Y503600D01*
X952017Y503933D01*
X952100Y504225D01*
X952267Y504433D01*
X952517Y504600D01*
X952808Y504642D01*
X953058Y504600D01*
X953308Y504433D01*
X953517Y504183D01*
X953600Y503892D01*
X953517Y503558D01*
X953267Y503267D01*
X952892Y503100D01*
X952475Y503058D01*
X951933Y503142D01*
X951642Y503267D01*
X951350Y503475D01*
X951142Y503767D01*
X951100Y504058D01*
X951183Y504350D01*
X951392Y504558D01*
G01X951100Y506950D02*
X951183Y506617D01*
X951392Y506367D01*
X951642Y506200D01*
X951975Y506075D01*
X952350Y506033D01*
X952725Y506075D01*
X953058Y506200D01*
X953308Y506367D01*
X953517Y506617D01*
X953600Y506950D01*
X953517Y507283D01*
X953308Y507533D01*
X953058Y507700D01*
X952725Y507825D01*
X952350Y507867D01*
X951975Y507825D01*
X951642Y507700D01*
X951392Y507533D01*
X951183Y507283D01*
X951100Y506950D01*
G01X953600Y510550D02*
X951100D01*
X952892Y509008D01*
Y511092D01*
G01X950100Y514600D02*
X954100D01*
Y522000D01*
G01X957983Y561500D02*
Y559708D01*
X958150Y559333D01*
X958483Y559083D01*
X958900Y559000D01*
X959317Y559083D01*
X959650Y559333D01*
X959817Y559708D01*
Y561500D01*
G01X961208Y561083D02*
X961458Y561333D01*
X961750Y561458D01*
X962083Y561500D01*
X962500Y561417D01*
X962792Y561208D01*
X962875Y560958D01*
X962833Y560708D01*
X962667Y560500D01*
X961833Y560083D01*
X961458Y559792D01*
X961208Y559375D01*
X961125Y559000D01*
X962875D01*
G01X965600D02*
Y561500D01*
X964058Y559708D01*
X966142D01*
G01X882067Y641500D02*
Y644000D01*
X883108D01*
X883442Y643875D01*
X883650Y643708D01*
X883733Y643375D01*
X883650Y643042D01*
X883400Y642833D01*
X883108Y642708D01*
X882067D01*
G01X883108D02*
X883733Y641500D01*
G01X885083Y641875D02*
X885333Y641667D01*
X885625Y641542D01*
X886000Y641500D01*
X886375Y641583D01*
X886667Y641750D01*
X886875Y642042D01*
X886917Y642375D01*
X886833Y642708D01*
X886625Y642917D01*
X886333Y643083D01*
X886042Y643125D01*
X885750Y643083D01*
X885375Y642917D01*
X885500Y644000D01*
X886625D01*
G01X889600Y641500D02*
Y644000D01*
X888058Y642208D01*
X890142D01*
G01X876690Y641190D02*
Y645190D01*
X869290D01*
G01X882067Y649500D02*
Y652000D01*
X883108D01*
X883442Y651875D01*
X883650Y651708D01*
X883733Y651375D01*
X883650Y651042D01*
X883400Y650833D01*
X883108Y650708D01*
X882067D01*
G01X883108D02*
X883733Y649500D01*
G01X885083Y649875D02*
X885333Y649667D01*
X885625Y649542D01*
X886000Y649500D01*
X886375Y649583D01*
X886667Y649750D01*
X886875Y650042D01*
X886917Y650375D01*
X886833Y650708D01*
X886625Y650917D01*
X886333Y651083D01*
X886042Y651125D01*
X885750Y651083D01*
X885375Y650917D01*
X885500Y652000D01*
X886625D01*
G01X888183Y649875D02*
X888433Y649667D01*
X888725Y649542D01*
X889100Y649500D01*
X889475Y649583D01*
X889767Y649750D01*
X889975Y650042D01*
X890017Y650375D01*
X889933Y650708D01*
X889725Y650917D01*
X889433Y651083D01*
X889142Y651125D01*
X888850Y651083D01*
X888475Y650917D01*
X888600Y652000D01*
X889725D01*
G01X876690Y649190D02*
Y653190D01*
X869290D01*
G01X878000Y631567D02*
X875500D01*
Y632608D01*
X875625Y632942D01*
X875792Y633150D01*
X876125Y633233D01*
X876458Y633150D01*
X876667Y632900D01*
X876792Y632608D01*
Y631567D01*
G01Y632608D02*
X878000Y633233D01*
G01X877625Y634583D02*
X877833Y634833D01*
X877958Y635125D01*
X878000Y635500D01*
X877917Y635875D01*
X877750Y636167D01*
X877458Y636375D01*
X877125Y636417D01*
X876792Y636333D01*
X876583Y636125D01*
X876417Y635833D01*
X876375Y635542D01*
X876417Y635250D01*
X876583Y634875D01*
X875500Y635000D01*
Y636125D01*
G01X876958Y637808D02*
X876667Y638100D01*
X876500Y638350D01*
X876417Y638683D01*
X876500Y638975D01*
X876667Y639183D01*
X876917Y639350D01*
X877208Y639392D01*
X877458Y639350D01*
X877708Y639183D01*
X877917Y638933D01*
X878000Y638642D01*
X877917Y638308D01*
X877667Y638017D01*
X877292Y637850D01*
X876875Y637808D01*
X876333Y637892D01*
X876042Y638017D01*
X875750Y638225D01*
X875542Y638517D01*
X875500Y638808D01*
X875583Y639100D01*
X875792Y639308D01*
G01X873240Y641140D02*
X869240D01*
Y633740D01*
G01X882067Y645500D02*
Y648000D01*
X883108D01*
X883442Y647875D01*
X883650Y647708D01*
X883733Y647375D01*
X883650Y647042D01*
X883400Y646833D01*
X883108Y646708D01*
X882067D01*
G01X883108D02*
X883733Y645500D01*
G01X885083Y645875D02*
X885333Y645667D01*
X885625Y645542D01*
X886000Y645500D01*
X886375Y645583D01*
X886667Y645750D01*
X886875Y646042D01*
X886917Y646375D01*
X886833Y646708D01*
X886625Y646917D01*
X886333Y647083D01*
X886042Y647125D01*
X885750Y647083D01*
X885375Y646917D01*
X885500Y648000D01*
X886625D01*
G01X889100Y645500D02*
X889392Y645542D01*
X889725Y645667D01*
X889933Y645875D01*
X890017Y646167D01*
X889933Y646458D01*
X889683Y646708D01*
X889308Y646833D01*
X888892D01*
X888642Y646917D01*
X888433Y647125D01*
X888350Y647417D01*
X888475Y647708D01*
X888767Y647917D01*
X889100Y648000D01*
X889433Y647917D01*
X889725Y647708D01*
X889850Y647417D01*
X889767Y647125D01*
X889558Y646917D01*
X889308Y646833D01*
X888892D01*
X888517Y646708D01*
X888267Y646458D01*
X888183Y646167D01*
X888267Y645875D01*
X888475Y645667D01*
X888808Y645542D01*
X889100Y645500D01*
G01X869290Y649190D02*
Y645190D01*
X876690D01*
G01X882067Y653500D02*
Y656000D01*
X883108D01*
X883442Y655875D01*
X883650Y655708D01*
X883733Y655375D01*
X883650Y655042D01*
X883400Y654833D01*
X883108Y654708D01*
X882067D01*
G01X883108D02*
X883733Y653500D01*
G01X885083Y653875D02*
X885333Y653667D01*
X885625Y653542D01*
X886000Y653500D01*
X886375Y653583D01*
X886667Y653750D01*
X886875Y654042D01*
X886917Y654375D01*
X886833Y654708D01*
X886625Y654917D01*
X886333Y655083D01*
X886042Y655125D01*
X885750Y655083D01*
X885375Y654917D01*
X885500Y656000D01*
X886625D01*
G01X888392Y653792D02*
X888683Y653583D01*
X889017Y653500D01*
X889350Y653583D01*
X889642Y653833D01*
X889850Y654208D01*
X889933Y654583D01*
Y655042D01*
X889850Y655417D01*
X889642Y655750D01*
X889392Y655917D01*
X889100Y656000D01*
X888767Y655917D01*
X888517Y655750D01*
X888350Y655500D01*
X888267Y655167D01*
X888350Y654875D01*
X888558Y654583D01*
X888808Y654417D01*
X889100Y654375D01*
X889433Y654458D01*
X889683Y654667D01*
X889933Y655042D01*
G01X869290Y657190D02*
Y653190D01*
X876690D01*
G01X928517Y749992D02*
X928267Y750117D01*
X927975Y750200D01*
X927642D01*
X927267Y750075D01*
X926975Y749867D01*
X926767Y749617D01*
X926600Y749200D01*
X926558Y748825D01*
X926642Y748450D01*
X926767Y748200D01*
X927017Y747950D01*
X927308Y747783D01*
X927600Y747700D01*
X927892D01*
X928183Y747783D01*
X928433Y747908D01*
X928642Y748075D01*
G01X930700Y747700D02*
Y750200D01*
X930200Y749700D01*
G01Y747700D02*
X931200D01*
G01X933008Y748742D02*
X933300Y749033D01*
X933550Y749200D01*
X933883Y749283D01*
X934175Y749200D01*
X934383Y749033D01*
X934550Y748783D01*
X934592Y748492D01*
X934550Y748242D01*
X934383Y747992D01*
X934133Y747783D01*
X933842Y747700D01*
X933508Y747783D01*
X933217Y748033D01*
X933050Y748408D01*
X933008Y748825D01*
X933092Y749367D01*
X933217Y749658D01*
X933425Y749950D01*
X933717Y750158D01*
X934008Y750200D01*
X934300Y750117D01*
X934508Y749908D01*
G01X877367Y755161D02*
Y757661D01*
X878408D01*
X878742Y757536D01*
X878950Y757369D01*
X879033Y757036D01*
X878950Y756703D01*
X878700Y756494D01*
X878408Y756369D01*
X877367D01*
G01X878408D02*
X879033Y755161D01*
G01X880508Y757244D02*
X880758Y757494D01*
X881050Y757619D01*
X881383Y757661D01*
X881800Y757578D01*
X882092Y757369D01*
X882175Y757119D01*
X882133Y756869D01*
X881967Y756661D01*
X881133Y756244D01*
X880758Y755953D01*
X880508Y755536D01*
X880425Y755161D01*
X882175D01*
G01X883608Y756203D02*
X883900Y756494D01*
X884150Y756661D01*
X884483Y756744D01*
X884775Y756661D01*
X884983Y756494D01*
X885150Y756244D01*
X885192Y755953D01*
X885150Y755703D01*
X884983Y755453D01*
X884733Y755244D01*
X884442Y755161D01*
X884108Y755244D01*
X883817Y755494D01*
X883650Y755869D01*
X883608Y756286D01*
X883692Y756828D01*
X883817Y757119D01*
X884025Y757411D01*
X884317Y757619D01*
X884608Y757661D01*
X884900Y757578D01*
X885108Y757369D01*
G01X872500Y754500D02*
Y758500D01*
X865100D01*
G01X877367Y759661D02*
Y762161D01*
X878408D01*
X878742Y762036D01*
X878950Y761869D01*
X879033Y761536D01*
X878950Y761203D01*
X878700Y760994D01*
X878408Y760869D01*
X877367D01*
G01X878408D02*
X879033Y759661D01*
G01X880383Y760161D02*
X880633Y759869D01*
X880967Y759703D01*
X881342Y759661D01*
X881675Y759703D01*
X882008Y759911D01*
X882217Y760161D01*
X882258Y760411D01*
X882175Y760703D01*
X881883Y760911D01*
X881592Y760994D01*
X881217D01*
G01X881592D02*
X881842Y761119D01*
X882050Y761328D01*
X882133Y761578D01*
X882050Y761828D01*
X881842Y762036D01*
X881467Y762161D01*
X881092Y762119D01*
X880717Y761953D01*
G01X884900Y759661D02*
Y762161D01*
X883358Y760369D01*
X885442D01*
G01X865100Y763000D02*
Y759000D01*
X872500D01*
G01X914467Y751300D02*
Y753800D01*
X915508D01*
X915842Y753675D01*
X916050Y753508D01*
X916133Y753175D01*
X916050Y752842D01*
X915800Y752633D01*
X915508Y752508D01*
X914467D01*
G01X915508D02*
X916133Y751300D01*
G01X918317D02*
X918400Y751842D01*
X918525Y752300D01*
X918692Y752717D01*
X918900Y753175D01*
X919233Y753800D01*
X917567D01*
G01X920583Y751675D02*
X920833Y751467D01*
X921125Y751342D01*
X921500Y751300D01*
X921875Y751383D01*
X922167Y751550D01*
X922375Y751842D01*
X922417Y752175D01*
X922333Y752508D01*
X922125Y752717D01*
X921833Y752883D01*
X921542Y752925D01*
X921250Y752883D01*
X920875Y752717D01*
X921000Y753800D01*
X922125D01*
G01X923100Y738217D02*
X920600D01*
Y739258D01*
X920725Y739592D01*
X920892Y739800D01*
X921225Y739883D01*
X921558Y739800D01*
X921767Y739550D01*
X921892Y739258D01*
Y738217D01*
G01Y739258D02*
X923100Y739883D01*
G01X922725Y741233D02*
X922933Y741483D01*
X923058Y741775D01*
X923100Y742150D01*
X923017Y742525D01*
X922850Y742817D01*
X922558Y743025D01*
X922225Y743067D01*
X921892Y742983D01*
X921683Y742775D01*
X921517Y742483D01*
X921475Y742192D01*
X921517Y741900D01*
X921683Y741525D01*
X920600Y741650D01*
Y742775D01*
G01X923100Y745250D02*
X920600D01*
X921100Y744750D01*
G01X923100D02*
Y745750D01*
G01X921017Y747558D02*
X920767Y747808D01*
X920642Y748100D01*
X920600Y748433D01*
X920683Y748850D01*
X920892Y749142D01*
X921142Y749225D01*
X921392Y749183D01*
X921600Y749017D01*
X922017Y748183D01*
X922308Y747808D01*
X922725Y747558D01*
X923100Y747475D01*
Y749225D01*
G01X920100Y755300D02*
X924100D01*
Y762700D01*
G01X928417Y746192D02*
X928167Y746317D01*
X927875Y746400D01*
X927542D01*
X927167Y746275D01*
X926875Y746067D01*
X926667Y745817D01*
X926500Y745400D01*
X926458Y745025D01*
X926542Y744650D01*
X926667Y744400D01*
X926917Y744150D01*
X927208Y743983D01*
X927500Y743900D01*
X927792D01*
X928083Y743983D01*
X928333Y744108D01*
X928542Y744275D01*
G01X930600Y743900D02*
Y746400D01*
X930100Y745900D01*
G01Y743900D02*
X931100D01*
G01X932783Y744275D02*
X933033Y744067D01*
X933325Y743942D01*
X933700Y743900D01*
X934075Y743983D01*
X934367Y744150D01*
X934575Y744442D01*
X934617Y744775D01*
X934533Y745108D01*
X934325Y745317D01*
X934033Y745483D01*
X933742Y745525D01*
X933450Y745483D01*
X933075Y745317D01*
X933200Y746400D01*
X934325D01*
G01X899000Y759200D02*
X898958Y758867D01*
X898792Y758575D01*
X898542Y758325D01*
X898250Y758158D01*
X897917Y758075D01*
X897583D01*
X897250Y758158D01*
X896958Y758325D01*
X896708Y758575D01*
X896542Y758867D01*
X896500Y759200D01*
X896542Y759533D01*
X896708Y759825D01*
X896958Y760075D01*
X897250Y760242D01*
X897583Y760325D01*
X897917D01*
X898250Y760242D01*
X898542Y760075D01*
X898792Y759825D01*
X898958Y759533D01*
X899000Y759200D01*
G01X898333Y759533D02*
X899000Y760033D01*
G01X896917Y761508D02*
X896667Y761758D01*
X896542Y762050D01*
X896500Y762383D01*
X896583Y762800D01*
X896792Y763092D01*
X897042Y763175D01*
X897292Y763133D01*
X897500Y762967D01*
X897917Y762133D01*
X898208Y761758D01*
X898625Y761508D01*
X899000Y761425D01*
Y763175D01*
G01X898708Y764692D02*
X898917Y764983D01*
X899000Y765317D01*
X898917Y765650D01*
X898667Y765942D01*
X898292Y766150D01*
X897917Y766233D01*
X897458D01*
X897083Y766150D01*
X896750Y765942D01*
X896583Y765692D01*
X896500Y765400D01*
X896583Y765067D01*
X896750Y764817D01*
X897000Y764650D01*
X897333Y764567D01*
X897625Y764650D01*
X897917Y764858D01*
X898083Y765108D01*
X898125Y765400D01*
X898042Y765733D01*
X897833Y765983D01*
X897458Y766233D01*
G01X900500Y769600D02*
Y755600D01*
G01X913500D02*
Y769600D01*
G01X900500Y755600D02*
X913500D01*
G01X879367Y775792D02*
X879117Y775917D01*
X878825Y776000D01*
X878492D01*
X878117Y775875D01*
X877825Y775667D01*
X877617Y775417D01*
X877450Y775000D01*
X877408Y774625D01*
X877492Y774250D01*
X877617Y774000D01*
X877867Y773750D01*
X878158Y773583D01*
X878450Y773500D01*
X878742D01*
X879033Y773583D01*
X879283Y773708D01*
X879492Y773875D01*
G01X880758Y774542D02*
X881050Y774833D01*
X881300Y775000D01*
X881633Y775083D01*
X881925Y775000D01*
X882133Y774833D01*
X882300Y774583D01*
X882342Y774292D01*
X882300Y774042D01*
X882133Y773792D01*
X881883Y773583D01*
X881592Y773500D01*
X881258Y773583D01*
X880967Y773833D01*
X880800Y774208D01*
X880758Y774625D01*
X880842Y775167D01*
X880967Y775458D01*
X881175Y775750D01*
X881467Y775958D01*
X881758Y776000D01*
X882050Y775917D01*
X882258Y775708D01*
G01X873067Y850661D02*
Y853161D01*
X874108D01*
X874442Y853036D01*
X874650Y852869D01*
X874733Y852536D01*
X874650Y852203D01*
X874400Y851994D01*
X874108Y851869D01*
X873067D01*
G01X874108D02*
X874733Y850661D01*
G01X877000D02*
Y853161D01*
X876500Y852661D01*
G01Y850661D02*
X877500D01*
G01X880017D02*
X880100Y851203D01*
X880225Y851661D01*
X880392Y852078D01*
X880600Y852536D01*
X880933Y853161D01*
X879267D01*
G01X873067Y855161D02*
Y857661D01*
X874108D01*
X874442Y857536D01*
X874650Y857369D01*
X874733Y857036D01*
X874650Y856703D01*
X874400Y856494D01*
X874108Y856369D01*
X873067D01*
G01X874108D02*
X874733Y855161D01*
G01X876208Y857244D02*
X876458Y857494D01*
X876750Y857619D01*
X877083Y857661D01*
X877500Y857578D01*
X877792Y857369D01*
X877875Y857119D01*
X877833Y856869D01*
X877667Y856661D01*
X876833Y856244D01*
X876458Y855953D01*
X876208Y855536D01*
X876125Y855161D01*
X877875D01*
G01X879183Y855661D02*
X879433Y855369D01*
X879767Y855203D01*
X880142Y855161D01*
X880475Y855203D01*
X880808Y855411D01*
X881017Y855661D01*
X881058Y855911D01*
X880975Y856203D01*
X880683Y856411D01*
X880392Y856494D01*
X880017D01*
G01X880392D02*
X880642Y856619D01*
X880850Y856828D01*
X880933Y857078D01*
X880850Y857328D01*
X880642Y857536D01*
X880267Y857661D01*
X879892Y857619D01*
X879517Y857453D01*
G01X877367Y768661D02*
Y771161D01*
X878408D01*
X878742Y771036D01*
X878950Y770869D01*
X879033Y770536D01*
X878950Y770203D01*
X878700Y769994D01*
X878408Y769869D01*
X877367D01*
G01X878408D02*
X879033Y768661D01*
G01X880383Y769161D02*
X880633Y768869D01*
X880967Y768703D01*
X881342Y768661D01*
X881675Y768703D01*
X882008Y768911D01*
X882217Y769161D01*
X882258Y769411D01*
X882175Y769703D01*
X881883Y769911D01*
X881592Y769994D01*
X881217D01*
G01X881592D02*
X881842Y770119D01*
X882050Y770328D01*
X882133Y770578D01*
X882050Y770828D01*
X881842Y771036D01*
X881467Y771161D01*
X881092Y771119D01*
X880717Y770953D01*
G01X884400Y771161D02*
X884067Y771078D01*
X883817Y770869D01*
X883650Y770619D01*
X883525Y770286D01*
X883483Y769911D01*
X883525Y769536D01*
X883650Y769203D01*
X883817Y768953D01*
X884067Y768744D01*
X884400Y768661D01*
X884733Y768744D01*
X884983Y768953D01*
X885150Y769203D01*
X885275Y769536D01*
X885317Y769911D01*
X885275Y770286D01*
X885150Y770619D01*
X884983Y770869D01*
X884733Y771078D01*
X884400Y771161D01*
G01X865100Y772000D02*
Y768000D01*
X872500D01*
G01X877367Y764161D02*
Y766661D01*
X878408D01*
X878742Y766536D01*
X878950Y766369D01*
X879033Y766036D01*
X878950Y765703D01*
X878700Y765494D01*
X878408Y765369D01*
X877367D01*
G01X878408D02*
X879033Y764161D01*
G01X880383Y764661D02*
X880633Y764369D01*
X880967Y764203D01*
X881342Y764161D01*
X881675Y764203D01*
X882008Y764411D01*
X882217Y764661D01*
X882258Y764911D01*
X882175Y765203D01*
X881883Y765411D01*
X881592Y765494D01*
X881217D01*
G01X881592D02*
X881842Y765619D01*
X882050Y765828D01*
X882133Y766078D01*
X882050Y766328D01*
X881842Y766536D01*
X881467Y766661D01*
X881092Y766619D01*
X880717Y766453D01*
G01X883483Y764661D02*
X883733Y764369D01*
X884067Y764203D01*
X884442Y764161D01*
X884775Y764203D01*
X885108Y764411D01*
X885317Y764661D01*
X885358Y764911D01*
X885275Y765203D01*
X884983Y765411D01*
X884692Y765494D01*
X884317D01*
G01X884692D02*
X884942Y765619D01*
X885150Y765828D01*
X885233Y766078D01*
X885150Y766328D01*
X884942Y766536D01*
X884567Y766661D01*
X884192Y766619D01*
X883817Y766453D01*
G01X865100Y767500D02*
Y763500D01*
X872500D01*
G01X870500Y805000D02*
X866500D01*
Y797600D01*
G01X885220Y805661D02*
Y808161D01*
X886261D01*
X886595Y808036D01*
X886803Y807869D01*
X886886Y807536D01*
X886803Y807203D01*
X886553Y806994D01*
X886261Y806869D01*
X885220D01*
G01X886261D02*
X886886Y805661D01*
G01X889653D02*
Y808161D01*
X888111Y806369D01*
X890195D01*
G01X891461Y806703D02*
X891753Y806994D01*
X892003Y807161D01*
X892336Y807244D01*
X892628Y807161D01*
X892836Y806994D01*
X893003Y806744D01*
X893045Y806453D01*
X893003Y806203D01*
X892836Y805953D01*
X892586Y805744D01*
X892295Y805661D01*
X891961Y805744D01*
X891670Y805994D01*
X891503Y806369D01*
X891461Y806786D01*
X891545Y807328D01*
X891670Y807619D01*
X891878Y807911D01*
X892170Y808119D01*
X892461Y808161D01*
X892753Y808078D01*
X892961Y807869D01*
G01X872953Y809000D02*
Y805000D01*
X880353D01*
G01X885220Y809661D02*
Y812161D01*
X886261D01*
X886595Y812036D01*
X886803Y811869D01*
X886886Y811536D01*
X886803Y811203D01*
X886553Y810994D01*
X886261Y810869D01*
X885220D01*
G01X886261D02*
X886886Y809661D01*
G01X889653D02*
Y812161D01*
X888111Y810369D01*
X890195D01*
G01X892170Y809661D02*
X892253Y810203D01*
X892378Y810661D01*
X892545Y811078D01*
X892753Y811536D01*
X893086Y812161D01*
X891420D01*
G01X880353Y809000D02*
Y813000D01*
X872953D01*
G01X883067Y801661D02*
Y804161D01*
X884108D01*
X884442Y804036D01*
X884650Y803869D01*
X884733Y803536D01*
X884650Y803203D01*
X884400Y802994D01*
X884108Y802869D01*
X883067D01*
G01X884108D02*
X884733Y801661D01*
G01X886083Y802036D02*
X886333Y801828D01*
X886625Y801703D01*
X887000Y801661D01*
X887375Y801744D01*
X887667Y801911D01*
X887875Y802203D01*
X887917Y802536D01*
X887833Y802869D01*
X887625Y803078D01*
X887333Y803244D01*
X887042Y803286D01*
X886750Y803244D01*
X886375Y803078D01*
X886500Y804161D01*
X887625D01*
G01X890100Y801661D02*
Y804161D01*
X889600Y803661D01*
G01Y801661D02*
X890600D01*
G01X878200Y801000D02*
Y805000D01*
X870800D01*
G01X883067Y813661D02*
Y816161D01*
X884108D01*
X884442Y816036D01*
X884650Y815869D01*
X884733Y815536D01*
X884650Y815203D01*
X884400Y814994D01*
X884108Y814869D01*
X883067D01*
G01X884108D02*
X884733Y813661D01*
G01X886083Y814036D02*
X886333Y813828D01*
X886625Y813703D01*
X887000Y813661D01*
X887375Y813744D01*
X887667Y813911D01*
X887875Y814203D01*
X887917Y814536D01*
X887833Y814869D01*
X887625Y815078D01*
X887333Y815244D01*
X887042Y815286D01*
X886750Y815244D01*
X886375Y815078D01*
X886500Y816161D01*
X887625D01*
G01X889308Y815744D02*
X889558Y815994D01*
X889850Y816119D01*
X890183Y816161D01*
X890600Y816078D01*
X890892Y815869D01*
X890975Y815619D01*
X890933Y815369D01*
X890767Y815161D01*
X889933Y814744D01*
X889558Y814453D01*
X889308Y814036D01*
X889225Y813661D01*
X890975D01*
G01X870800Y817000D02*
Y813000D01*
X878200D01*
G01X905400Y846967D02*
X902900D01*
Y848008D01*
X903025Y848342D01*
X903192Y848550D01*
X903525Y848633D01*
X903858Y848550D01*
X904067Y848300D01*
X904192Y848008D01*
Y846967D01*
G01Y848008D02*
X905400Y848633D01*
G01X904358Y850108D02*
X904067Y850400D01*
X903900Y850650D01*
X903817Y850983D01*
X903900Y851275D01*
X904067Y851483D01*
X904317Y851650D01*
X904608Y851692D01*
X904858Y851650D01*
X905108Y851483D01*
X905317Y851233D01*
X905400Y850942D01*
X905317Y850608D01*
X905067Y850317D01*
X904692Y850150D01*
X904275Y850108D01*
X903733Y850192D01*
X903442Y850317D01*
X903150Y850525D01*
X902942Y850817D01*
X902900Y851108D01*
X902983Y851400D01*
X903192Y851608D01*
G01X904900Y853083D02*
X905192Y853333D01*
X905358Y853667D01*
X905400Y854042D01*
X905358Y854375D01*
X905150Y854708D01*
X904900Y854917D01*
X904650Y854958D01*
X904358Y854875D01*
X904150Y854583D01*
X904067Y854292D01*
Y853917D01*
G01Y854292D02*
X903942Y854542D01*
X903733Y854750D01*
X903483Y854833D01*
X903233Y854750D01*
X903025Y854542D01*
X902900Y854167D01*
X902942Y853792D01*
X903108Y853417D01*
G01X913400Y846967D02*
X910900D01*
Y848008D01*
X911025Y848342D01*
X911192Y848550D01*
X911525Y848633D01*
X911858Y848550D01*
X912067Y848300D01*
X912192Y848008D01*
Y846967D01*
G01Y848008D02*
X913400Y848633D01*
G01X912358Y850108D02*
X912067Y850400D01*
X911900Y850650D01*
X911817Y850983D01*
X911900Y851275D01*
X912067Y851483D01*
X912317Y851650D01*
X912608Y851692D01*
X912858Y851650D01*
X913108Y851483D01*
X913317Y851233D01*
X913400Y850942D01*
X913317Y850608D01*
X913067Y850317D01*
X912692Y850150D01*
X912275Y850108D01*
X911733Y850192D01*
X911442Y850317D01*
X911150Y850525D01*
X910942Y850817D01*
X910900Y851108D01*
X910983Y851400D01*
X911192Y851608D01*
G01X912358Y853208D02*
X912067Y853500D01*
X911900Y853750D01*
X911817Y854083D01*
X911900Y854375D01*
X912067Y854583D01*
X912317Y854750D01*
X912608Y854792D01*
X912858Y854750D01*
X913108Y854583D01*
X913317Y854333D01*
X913400Y854042D01*
X913317Y853708D01*
X913067Y853417D01*
X912692Y853250D01*
X912275Y853208D01*
X911733Y853292D01*
X911442Y853417D01*
X911150Y853625D01*
X910942Y853917D01*
X910900Y854208D01*
X910983Y854500D01*
X911192Y854708D01*
G01X909400Y846967D02*
X906900D01*
Y848008D01*
X907025Y848342D01*
X907192Y848550D01*
X907525Y848633D01*
X907858Y848550D01*
X908067Y848300D01*
X908192Y848008D01*
Y846967D01*
G01Y848008D02*
X909400Y848633D01*
G01X908358Y850108D02*
X908067Y850400D01*
X907900Y850650D01*
X907817Y850983D01*
X907900Y851275D01*
X908067Y851483D01*
X908317Y851650D01*
X908608Y851692D01*
X908858Y851650D01*
X909108Y851483D01*
X909317Y851233D01*
X909400Y850942D01*
X909317Y850608D01*
X909067Y850317D01*
X908692Y850150D01*
X908275Y850108D01*
X907733Y850192D01*
X907442Y850317D01*
X907150Y850525D01*
X906942Y850817D01*
X906900Y851108D01*
X906983Y851400D01*
X907192Y851608D01*
G01X909400Y853917D02*
X908858Y854000D01*
X908400Y854125D01*
X907983Y854292D01*
X907525Y854500D01*
X906900Y854833D01*
Y853167D01*
G01X901400Y846967D02*
X898900D01*
Y848008D01*
X899025Y848342D01*
X899192Y848550D01*
X899525Y848633D01*
X899858Y848550D01*
X900067Y848300D01*
X900192Y848008D01*
Y846967D01*
G01Y848008D02*
X901400Y848633D01*
G01X900358Y850108D02*
X900067Y850400D01*
X899900Y850650D01*
X899817Y850983D01*
X899900Y851275D01*
X900067Y851483D01*
X900317Y851650D01*
X900608Y851692D01*
X900858Y851650D01*
X901108Y851483D01*
X901317Y851233D01*
X901400Y850942D01*
X901317Y850608D01*
X901067Y850317D01*
X900692Y850150D01*
X900275Y850108D01*
X899733Y850192D01*
X899442Y850317D01*
X899150Y850525D01*
X898942Y850817D01*
X898900Y851108D01*
X898983Y851400D01*
X899192Y851608D01*
G01X901400Y854000D02*
X901358Y854292D01*
X901233Y854625D01*
X901025Y854833D01*
X900733Y854917D01*
X900442Y854833D01*
X900192Y854583D01*
X900067Y854208D01*
Y853792D01*
X899983Y853542D01*
X899775Y853333D01*
X899483Y853250D01*
X899192Y853375D01*
X898983Y853667D01*
X898900Y854000D01*
X898983Y854333D01*
X899192Y854625D01*
X899483Y854750D01*
X899775Y854667D01*
X899983Y854458D01*
X900067Y854208D01*
Y853792D01*
X900192Y853417D01*
X900442Y853167D01*
X900733Y853083D01*
X901025Y853167D01*
X901233Y853375D01*
X901358Y853708D01*
X901400Y854000D01*
G01X892497Y781330D02*
Y783830D01*
X893538D01*
X893872Y783705D01*
X894080Y783538D01*
X894163Y783205D01*
X894080Y782872D01*
X893830Y782663D01*
X893538Y782538D01*
X892497D01*
G01X893538D02*
X894163Y781330D01*
G01X896347D02*
X896430Y781872D01*
X896555Y782330D01*
X896722Y782747D01*
X896930Y783205D01*
X897263Y783830D01*
X895597D01*
G01X899530Y781330D02*
Y783830D01*
X899030Y783330D01*
G01Y781330D02*
X900030D01*
G01X906800Y784800D02*
Y780800D01*
X914200D01*
G01X921500Y762800D02*
Y766800D01*
X914100D01*
G01X892453Y773150D02*
Y775650D01*
X893494D01*
X893828Y775525D01*
X894036Y775358D01*
X894119Y775025D01*
X894036Y774692D01*
X893786Y774483D01*
X893494Y774358D01*
X892453D01*
G01X893494D02*
X894119Y773150D01*
G01X896303D02*
X896386Y773692D01*
X896511Y774150D01*
X896678Y774567D01*
X896886Y775025D01*
X897219Y775650D01*
X895553D01*
G01X898694Y774192D02*
X898986Y774483D01*
X899236Y774650D01*
X899569Y774733D01*
X899861Y774650D01*
X900069Y774483D01*
X900236Y774233D01*
X900278Y773942D01*
X900236Y773692D01*
X900069Y773442D01*
X899819Y773233D01*
X899528Y773150D01*
X899194Y773233D01*
X898903Y773483D01*
X898736Y773858D01*
X898694Y774275D01*
X898778Y774817D01*
X898903Y775108D01*
X899111Y775400D01*
X899403Y775608D01*
X899694Y775650D01*
X899986Y775567D01*
X900194Y775358D01*
G01X914200Y772000D02*
Y776000D01*
X906800D01*
G01X892467Y777100D02*
Y779600D01*
X893508D01*
X893842Y779475D01*
X894050Y779308D01*
X894133Y778975D01*
X894050Y778642D01*
X893800Y778433D01*
X893508Y778308D01*
X892467D01*
G01X893508D02*
X894133Y777100D01*
G01X896317D02*
X896400Y777642D01*
X896525Y778100D01*
X896692Y778517D01*
X896900Y778975D01*
X897233Y779600D01*
X895567D01*
G01X899417Y777100D02*
X899500Y777642D01*
X899625Y778100D01*
X899792Y778517D01*
X900000Y778975D01*
X900333Y779600D01*
X898667D01*
G01X914200Y776000D02*
Y780000D01*
X906800D01*
G01X950400Y831867D02*
X947900D01*
Y832908D01*
X948025Y833242D01*
X948192Y833450D01*
X948525Y833533D01*
X948858Y833450D01*
X949067Y833200D01*
X949192Y832908D01*
Y831867D01*
G01Y832908D02*
X950400Y833533D01*
G01Y835800D02*
X950358Y836092D01*
X950233Y836425D01*
X950025Y836633D01*
X949733Y836717D01*
X949442Y836633D01*
X949192Y836383D01*
X949067Y836008D01*
Y835592D01*
X948983Y835342D01*
X948775Y835133D01*
X948483Y835050D01*
X948192Y835175D01*
X947983Y835467D01*
X947900Y835800D01*
X947983Y836133D01*
X948192Y836425D01*
X948483Y836550D01*
X948775Y836467D01*
X948983Y836258D01*
X949067Y836008D01*
Y835592D01*
X949192Y835217D01*
X949442Y834967D01*
X949733Y834883D01*
X950025Y834967D01*
X950233Y835175D01*
X950358Y835508D01*
X950400Y835800D01*
G01X947900Y838900D02*
X947983Y838567D01*
X948192Y838317D01*
X948442Y838150D01*
X948775Y838025D01*
X949150Y837983D01*
X949525Y838025D01*
X949858Y838150D01*
X950108Y838317D01*
X950317Y838567D01*
X950400Y838900D01*
X950317Y839233D01*
X950108Y839483D01*
X949858Y839650D01*
X949525Y839775D01*
X949150Y839817D01*
X948775Y839775D01*
X948442Y839650D01*
X948192Y839483D01*
X947983Y839233D01*
X947900Y838900D01*
G01X946500Y843800D02*
X950500D01*
Y851200D01*
G01X958400Y831867D02*
X955900D01*
Y832908D01*
X956025Y833242D01*
X956192Y833450D01*
X956525Y833533D01*
X956858Y833450D01*
X957067Y833200D01*
X957192Y832908D01*
Y831867D01*
G01Y832908D02*
X958400Y833533D01*
G01Y835800D02*
X958358Y836092D01*
X958233Y836425D01*
X958025Y836633D01*
X957733Y836717D01*
X957442Y836633D01*
X957192Y836383D01*
X957067Y836008D01*
Y835592D01*
X956983Y835342D01*
X956775Y835133D01*
X956483Y835050D01*
X956192Y835175D01*
X955983Y835467D01*
X955900Y835800D01*
X955983Y836133D01*
X956192Y836425D01*
X956483Y836550D01*
X956775Y836467D01*
X956983Y836258D01*
X957067Y836008D01*
Y835592D01*
X957192Y835217D01*
X957442Y834967D01*
X957733Y834883D01*
X958025Y834967D01*
X958233Y835175D01*
X958358Y835508D01*
X958400Y835800D01*
G01Y838900D02*
X955900D01*
X956400Y838400D01*
G01X958400D02*
Y839400D01*
G01X959500Y851200D02*
X955500D01*
Y843800D01*
G01X944300Y831467D02*
X941800D01*
Y832508D01*
X941925Y832842D01*
X942092Y833050D01*
X942425Y833133D01*
X942758Y833050D01*
X942967Y832800D01*
X943092Y832508D01*
Y831467D01*
G01Y832508D02*
X944300Y833133D01*
G01Y835400D02*
X944258Y835692D01*
X944133Y836025D01*
X943925Y836233D01*
X943633Y836317D01*
X943342Y836233D01*
X943092Y835983D01*
X942967Y835608D01*
Y835192D01*
X942883Y834942D01*
X942675Y834733D01*
X942383Y834650D01*
X942092Y834775D01*
X941883Y835067D01*
X941800Y835400D01*
X941883Y835733D01*
X942092Y836025D01*
X942383Y836150D01*
X942675Y836067D01*
X942883Y835858D01*
X942967Y835608D01*
Y835192D01*
X943092Y834817D01*
X943342Y834567D01*
X943633Y834483D01*
X943925Y834567D01*
X944133Y834775D01*
X944258Y835108D01*
X944300Y835400D01*
G01Y839000D02*
X941800D01*
X943592Y837458D01*
Y839542D01*
G01X946000Y851200D02*
X942000D01*
Y843800D01*
G01X954400Y831867D02*
X951900D01*
Y832908D01*
X952025Y833242D01*
X952192Y833450D01*
X952525Y833533D01*
X952858Y833450D01*
X953067Y833200D01*
X953192Y832908D01*
Y831867D01*
G01Y832908D02*
X954400Y833533D01*
G01Y835800D02*
X954358Y836092D01*
X954233Y836425D01*
X954025Y836633D01*
X953733Y836717D01*
X953442Y836633D01*
X953192Y836383D01*
X953067Y836008D01*
Y835592D01*
X952983Y835342D01*
X952775Y835133D01*
X952483Y835050D01*
X952192Y835175D01*
X951983Y835467D01*
X951900Y835800D01*
X951983Y836133D01*
X952192Y836425D01*
X952483Y836550D01*
X952775Y836467D01*
X952983Y836258D01*
X953067Y836008D01*
Y835592D01*
X953192Y835217D01*
X953442Y834967D01*
X953733Y834883D01*
X954025Y834967D01*
X954233Y835175D01*
X954358Y835508D01*
X954400Y835800D01*
G01X954025Y837983D02*
X954233Y838233D01*
X954358Y838525D01*
X954400Y838900D01*
X954317Y839275D01*
X954150Y839567D01*
X953858Y839775D01*
X953525Y839817D01*
X953192Y839733D01*
X952983Y839525D01*
X952817Y839233D01*
X952775Y838942D01*
X952817Y838650D01*
X952983Y838275D01*
X951900Y838400D01*
Y839525D01*
G01X951000Y843800D02*
X955000D01*
Y851200D01*
G01X936300Y831467D02*
X933800D01*
Y832508D01*
X933925Y832842D01*
X934092Y833050D01*
X934425Y833133D01*
X934758Y833050D01*
X934967Y832800D01*
X935092Y832508D01*
Y831467D01*
G01Y832508D02*
X936300Y833133D01*
G01Y835400D02*
X936258Y835692D01*
X936133Y836025D01*
X935925Y836233D01*
X935633Y836317D01*
X935342Y836233D01*
X935092Y835983D01*
X934967Y835608D01*
Y835192D01*
X934883Y834942D01*
X934675Y834733D01*
X934383Y834650D01*
X934092Y834775D01*
X933883Y835067D01*
X933800Y835400D01*
X933883Y835733D01*
X934092Y836025D01*
X934383Y836150D01*
X934675Y836067D01*
X934883Y835858D01*
X934967Y835608D01*
Y835192D01*
X935092Y834817D01*
X935342Y834567D01*
X935633Y834483D01*
X935925Y834567D01*
X936133Y834775D01*
X936258Y835108D01*
X936300Y835400D01*
G01Y838417D02*
X935758Y838500D01*
X935300Y838625D01*
X934883Y838792D01*
X934425Y839000D01*
X933800Y839333D01*
Y837667D01*
G01X937000Y851200D02*
X933000D01*
Y843800D01*
G01X940300Y831467D02*
X937800D01*
Y832508D01*
X937925Y832842D01*
X938092Y833050D01*
X938425Y833133D01*
X938758Y833050D01*
X938967Y832800D01*
X939092Y832508D01*
Y831467D01*
G01Y832508D02*
X940300Y833133D01*
G01Y835400D02*
X940258Y835692D01*
X940133Y836025D01*
X939925Y836233D01*
X939633Y836317D01*
X939342Y836233D01*
X939092Y835983D01*
X938967Y835608D01*
Y835192D01*
X938883Y834942D01*
X938675Y834733D01*
X938383Y834650D01*
X938092Y834775D01*
X937883Y835067D01*
X937800Y835400D01*
X937883Y835733D01*
X938092Y836025D01*
X938383Y836150D01*
X938675Y836067D01*
X938883Y835858D01*
X938967Y835608D01*
Y835192D01*
X939092Y834817D01*
X939342Y834567D01*
X939633Y834483D01*
X939925Y834567D01*
X940133Y834775D01*
X940258Y835108D01*
X940300Y835400D01*
G01Y838500D02*
X940258Y838792D01*
X940133Y839125D01*
X939925Y839333D01*
X939633Y839417D01*
X939342Y839333D01*
X939092Y839083D01*
X938967Y838708D01*
Y838292D01*
X938883Y838042D01*
X938675Y837833D01*
X938383Y837750D01*
X938092Y837875D01*
X937883Y838167D01*
X937800Y838500D01*
X937883Y838833D01*
X938092Y839125D01*
X938383Y839250D01*
X938675Y839167D01*
X938883Y838958D01*
X938967Y838708D01*
Y838292D01*
X939092Y837917D01*
X939342Y837667D01*
X939633Y837583D01*
X939925Y837667D01*
X940133Y837875D01*
X940258Y838208D01*
X940300Y838500D01*
G01X941500Y851200D02*
X937500D01*
Y843800D01*
G01X879367Y780292D02*
X879117Y780417D01*
X878825Y780500D01*
X878492D01*
X878117Y780375D01*
X877825Y780167D01*
X877617Y779917D01*
X877450Y779500D01*
X877408Y779125D01*
X877492Y778750D01*
X877617Y778500D01*
X877867Y778250D01*
X878158Y778083D01*
X878450Y778000D01*
X878742D01*
X879033Y778083D01*
X879283Y778208D01*
X879492Y778375D01*
G01X880633D02*
X880883Y778167D01*
X881175Y778042D01*
X881550Y778000D01*
X881925Y778083D01*
X882217Y778250D01*
X882425Y778542D01*
X882467Y778875D01*
X882383Y779208D01*
X882175Y779417D01*
X881883Y779583D01*
X881592Y779625D01*
X881300Y779583D01*
X880925Y779417D01*
X881050Y780500D01*
X882175D01*
G01X934533Y804000D02*
Y802208D01*
X934700Y801833D01*
X935033Y801583D01*
X935450Y801500D01*
X935867Y801583D01*
X936200Y801833D01*
X936367Y802208D01*
Y804000D01*
G01X937842Y801792D02*
X938133Y801583D01*
X938467Y801500D01*
X938800Y801583D01*
X939092Y801833D01*
X939300Y802208D01*
X939383Y802583D01*
Y803042D01*
X939300Y803417D01*
X939092Y803750D01*
X938842Y803917D01*
X938550Y804000D01*
X938217Y803917D01*
X937967Y803750D01*
X937800Y803500D01*
X937717Y803167D01*
X937800Y802875D01*
X938008Y802583D01*
X938258Y802417D01*
X938550Y802375D01*
X938883Y802458D01*
X939133Y802667D01*
X939383Y803042D01*
G01X952000Y767150D02*
X931000D01*
Y798800D01*
X942000D01*
Y767150D01*
G01X933350D02*
X936500Y770300D01*
X939650Y767150D01*
G01X913500Y769600D02*
X900500D01*
G01X917400Y847600D02*
X917358Y847267D01*
X917192Y846975D01*
X916942Y846725D01*
X916650Y846558D01*
X916317Y846475D01*
X915983D01*
X915650Y846558D01*
X915358Y846725D01*
X915108Y846975D01*
X914942Y847267D01*
X914900Y847600D01*
X914942Y847933D01*
X915108Y848225D01*
X915358Y848475D01*
X915650Y848642D01*
X915983Y848725D01*
X916317D01*
X916650Y848642D01*
X916942Y848475D01*
X917192Y848225D01*
X917358Y847933D01*
X917400Y847600D01*
G01X916733Y847933D02*
X917400Y848433D01*
G01Y850700D02*
X914900D01*
X915400Y850200D01*
G01X917400D02*
Y851200D01*
G01Y853717D02*
X916858Y853800D01*
X916400Y853925D01*
X915983Y854092D01*
X915525Y854300D01*
X914900Y854633D01*
Y852967D01*
G01X868867Y897953D02*
X868617Y898078D01*
X868325Y898161D01*
X867992D01*
X867617Y898036D01*
X867325Y897828D01*
X867117Y897578D01*
X866950Y897161D01*
X866908Y896786D01*
X866992Y896411D01*
X867117Y896161D01*
X867367Y895911D01*
X867658Y895744D01*
X867950Y895661D01*
X868242D01*
X868533Y895744D01*
X868783Y895869D01*
X868992Y896036D01*
G01X871550Y895661D02*
Y898161D01*
X870008Y896369D01*
X872092D01*
G01X922708Y890317D02*
X922583Y890067D01*
X922500Y889775D01*
Y889442D01*
X922625Y889067D01*
X922833Y888775D01*
X923083Y888567D01*
X923500Y888400D01*
X923875Y888358D01*
X924250Y888442D01*
X924500Y888567D01*
X924750Y888817D01*
X924917Y889108D01*
X925000Y889400D01*
Y889692D01*
X924917Y889983D01*
X924792Y890233D01*
X924625Y890442D01*
G01X925000Y892500D02*
X922500D01*
X923000Y892000D01*
G01X925000D02*
Y893000D01*
G01Y896100D02*
X922500D01*
X924292Y894558D01*
Y896642D01*
G01X931317Y901292D02*
X931067Y901417D01*
X930775Y901500D01*
X930442D01*
X930067Y901375D01*
X929775Y901167D01*
X929567Y900917D01*
X929400Y900500D01*
X929358Y900125D01*
X929442Y899750D01*
X929567Y899500D01*
X929817Y899250D01*
X930108Y899083D01*
X930400Y899000D01*
X930692D01*
X930983Y899083D01*
X931233Y899208D01*
X931442Y899375D01*
G01X933500Y899000D02*
Y901500D01*
X933000Y901000D01*
G01Y899000D02*
X934000D01*
G01X936600D02*
X936892Y899042D01*
X937225Y899167D01*
X937433Y899375D01*
X937517Y899667D01*
X937433Y899958D01*
X937183Y900208D01*
X936808Y900333D01*
X936392D01*
X936142Y900417D01*
X935933Y900625D01*
X935850Y900917D01*
X935975Y901208D01*
X936267Y901417D01*
X936600Y901500D01*
X936933Y901417D01*
X937225Y901208D01*
X937350Y900917D01*
X937267Y900625D01*
X937058Y900417D01*
X936808Y900333D01*
X936392D01*
X936017Y900208D01*
X935767Y899958D01*
X935683Y899667D01*
X935767Y899375D01*
X935975Y899167D01*
X936308Y899042D01*
X936600Y899000D01*
G01X877700Y867500D02*
Y871500D01*
X870300D01*
G01X873067Y864161D02*
Y866661D01*
X874108D01*
X874442Y866536D01*
X874650Y866369D01*
X874733Y866036D01*
X874650Y865703D01*
X874400Y865494D01*
X874108Y865369D01*
X873067D01*
G01X874108D02*
X874733Y864161D01*
G01X876208Y866244D02*
X876458Y866494D01*
X876750Y866619D01*
X877083Y866661D01*
X877500Y866578D01*
X877792Y866369D01*
X877875Y866119D01*
X877833Y865869D01*
X877667Y865661D01*
X876833Y865244D01*
X876458Y864953D01*
X876208Y864536D01*
X876125Y864161D01*
X877875D01*
G01X880100D02*
Y866661D01*
X879600Y866161D01*
G01Y864161D02*
X880600D01*
G01X870300Y885000D02*
Y881000D01*
X877700D01*
G01X873067Y859661D02*
Y862161D01*
X874108D01*
X874442Y862036D01*
X874650Y861869D01*
X874733Y861536D01*
X874650Y861203D01*
X874400Y860994D01*
X874108Y860869D01*
X873067D01*
G01X874108D02*
X874733Y859661D01*
G01X876208Y861744D02*
X876458Y861994D01*
X876750Y862119D01*
X877083Y862161D01*
X877500Y862078D01*
X877792Y861869D01*
X877875Y861619D01*
X877833Y861369D01*
X877667Y861161D01*
X876833Y860744D01*
X876458Y860453D01*
X876208Y860036D01*
X876125Y859661D01*
X877875D01*
G01X879308Y861744D02*
X879558Y861994D01*
X879850Y862119D01*
X880183Y862161D01*
X880600Y862078D01*
X880892Y861869D01*
X880975Y861619D01*
X880933Y861369D01*
X880767Y861161D01*
X879933Y860744D01*
X879558Y860453D01*
X879308Y860036D01*
X879225Y859661D01*
X880975D01*
G01X870300Y880500D02*
Y876500D01*
X877700D01*
G01X870300Y876000D02*
Y872000D01*
X877700D01*
G01X928500Y926567D02*
X926000D01*
Y927608D01*
X926125Y927942D01*
X926292Y928150D01*
X926625Y928233D01*
X926958Y928150D01*
X927167Y927900D01*
X927292Y927608D01*
Y926567D01*
G01Y927608D02*
X928500Y928233D01*
G01X927458Y929708D02*
X927167Y930000D01*
X927000Y930250D01*
X926917Y930583D01*
X927000Y930875D01*
X927167Y931083D01*
X927417Y931250D01*
X927708Y931292D01*
X927958Y931250D01*
X928208Y931083D01*
X928417Y930833D01*
X928500Y930542D01*
X928417Y930208D01*
X928167Y929917D01*
X927792Y929750D01*
X927375Y929708D01*
X926833Y929792D01*
X926542Y929917D01*
X926250Y930125D01*
X926042Y930417D01*
X926000Y930708D01*
X926083Y931000D01*
X926292Y931208D01*
G01X926417Y932808D02*
X926167Y933058D01*
X926042Y933350D01*
X926000Y933683D01*
X926083Y934100D01*
X926292Y934392D01*
X926542Y934475D01*
X926792Y934433D01*
X927000Y934267D01*
X927417Y933433D01*
X927708Y933058D01*
X928125Y932808D01*
X928500Y932725D01*
Y934475D01*
G01X929260Y921070D02*
X925260D01*
Y913670D01*
G01X917580Y866070D02*
X913580D01*
Y858670D01*
G01X924500Y926567D02*
X922000D01*
Y927608D01*
X922125Y927942D01*
X922292Y928150D01*
X922625Y928233D01*
X922958Y928150D01*
X923167Y927900D01*
X923292Y927608D01*
Y926567D01*
G01Y927608D02*
X924500Y928233D01*
G01X923458Y929708D02*
X923167Y930000D01*
X923000Y930250D01*
X922917Y930583D01*
X923000Y930875D01*
X923167Y931083D01*
X923417Y931250D01*
X923708Y931292D01*
X923958Y931250D01*
X924208Y931083D01*
X924417Y930833D01*
X924500Y930542D01*
X924417Y930208D01*
X924167Y929917D01*
X923792Y929750D01*
X923375Y929708D01*
X922833Y929792D01*
X922542Y929917D01*
X922250Y930125D01*
X922042Y930417D01*
X922000Y930708D01*
X922083Y931000D01*
X922292Y931208D01*
G01X924500Y934100D02*
X922000D01*
X923792Y932558D01*
Y934642D01*
G01X924760Y921070D02*
X920760D01*
Y913670D01*
G01X908100Y926867D02*
X905600D01*
Y927908D01*
X905725Y928242D01*
X905892Y928450D01*
X906225Y928533D01*
X906558Y928450D01*
X906767Y928200D01*
X906892Y927908D01*
Y926867D01*
G01Y927908D02*
X908100Y928533D01*
G01X907058Y930008D02*
X906767Y930300D01*
X906600Y930550D01*
X906517Y930883D01*
X906600Y931175D01*
X906767Y931383D01*
X907017Y931550D01*
X907308Y931592D01*
X907558Y931550D01*
X907808Y931383D01*
X908017Y931133D01*
X908100Y930842D01*
X908017Y930508D01*
X907767Y930217D01*
X907392Y930050D01*
X906975Y930008D01*
X906433Y930092D01*
X906142Y930217D01*
X905850Y930425D01*
X905642Y930717D01*
X905600Y931008D01*
X905683Y931300D01*
X905892Y931508D01*
G01X907725Y932983D02*
X907933Y933233D01*
X908058Y933525D01*
X908100Y933900D01*
X908017Y934275D01*
X907850Y934567D01*
X907558Y934775D01*
X907225Y934817D01*
X906892Y934733D01*
X906683Y934525D01*
X906517Y934233D01*
X906475Y933942D01*
X906517Y933650D01*
X906683Y933275D01*
X905600Y933400D01*
Y934525D01*
G01X911760Y921070D02*
X907760D01*
Y913670D01*
G01X926670Y866040D02*
X922670D01*
Y858640D01*
G01X922170Y866040D02*
X918170D01*
Y858640D01*
G01X909080Y858670D02*
X913080D01*
Y866070D01*
G01X920000Y926567D02*
X917500D01*
Y927608D01*
X917625Y927942D01*
X917792Y928150D01*
X918125Y928233D01*
X918458Y928150D01*
X918667Y927900D01*
X918792Y927608D01*
Y926567D01*
G01Y927608D02*
X920000Y928233D01*
G01X918958Y929708D02*
X918667Y930000D01*
X918500Y930250D01*
X918417Y930583D01*
X918500Y930875D01*
X918667Y931083D01*
X918917Y931250D01*
X919208Y931292D01*
X919458Y931250D01*
X919708Y931083D01*
X919917Y930833D01*
X920000Y930542D01*
X919917Y930208D01*
X919667Y929917D01*
X919292Y929750D01*
X918875Y929708D01*
X918333Y929792D01*
X918042Y929917D01*
X917750Y930125D01*
X917542Y930417D01*
X917500Y930708D01*
X917583Y931000D01*
X917792Y931208D01*
G01X919708Y932892D02*
X919917Y933183D01*
X920000Y933517D01*
X919917Y933850D01*
X919667Y934142D01*
X919292Y934350D01*
X918917Y934433D01*
X918458D01*
X918083Y934350D01*
X917750Y934142D01*
X917583Y933892D01*
X917500Y933600D01*
X917583Y933267D01*
X917750Y933017D01*
X918000Y932850D01*
X918333Y932767D01*
X918625Y932850D01*
X918917Y933058D01*
X919083Y933308D01*
X919125Y933600D01*
X919042Y933933D01*
X918833Y934183D01*
X918458Y934433D01*
G01X916380Y913714D02*
X920380D01*
Y921114D01*
G01X915500Y926567D02*
X913000D01*
Y927608D01*
X913125Y927942D01*
X913292Y928150D01*
X913625Y928233D01*
X913958Y928150D01*
X914167Y927900D01*
X914292Y927608D01*
Y926567D01*
G01Y927608D02*
X915500Y928233D01*
G01Y930417D02*
X914958Y930500D01*
X914500Y930625D01*
X914083Y930792D01*
X913625Y931000D01*
X913000Y931333D01*
Y929667D01*
G01Y933600D02*
X913083Y933267D01*
X913292Y933017D01*
X913542Y932850D01*
X913875Y932725D01*
X914250Y932683D01*
X914625Y932725D01*
X914958Y932850D01*
X915208Y933017D01*
X915417Y933267D01*
X915500Y933600D01*
X915417Y933933D01*
X915208Y934183D01*
X914958Y934350D01*
X914625Y934475D01*
X914250Y934517D01*
X913875Y934475D01*
X913542Y934350D01*
X913292Y934183D01*
X913083Y933933D01*
X913000Y933600D01*
G01X912260Y913670D02*
X916260D01*
Y921070D01*
G01X944067Y916000D02*
Y918500D01*
X945108D01*
X945442Y918375D01*
X945650Y918208D01*
X945733Y917875D01*
X945650Y917542D01*
X945400Y917333D01*
X945108Y917208D01*
X944067D01*
G01X945108D02*
X945733Y916000D01*
G01X948000D02*
X948292Y916042D01*
X948625Y916167D01*
X948833Y916375D01*
X948917Y916667D01*
X948833Y916958D01*
X948583Y917208D01*
X948208Y917333D01*
X947792D01*
X947542Y917417D01*
X947333Y917625D01*
X947250Y917917D01*
X947375Y918208D01*
X947667Y918417D01*
X948000Y918500D01*
X948333Y918417D01*
X948625Y918208D01*
X948750Y917917D01*
X948667Y917625D01*
X948458Y917417D01*
X948208Y917333D01*
X947792D01*
X947417Y917208D01*
X947167Y916958D01*
X947083Y916667D01*
X947167Y916375D01*
X947375Y916167D01*
X947708Y916042D01*
X948000Y916000D01*
G01X950183Y916500D02*
X950433Y916208D01*
X950767Y916042D01*
X951142Y916000D01*
X951475Y916042D01*
X951808Y916250D01*
X952017Y916500D01*
X952058Y916750D01*
X951975Y917042D01*
X951683Y917250D01*
X951392Y917333D01*
X951017D01*
G01X951392D02*
X951642Y917458D01*
X951850Y917667D01*
X951933Y917917D01*
X951850Y918167D01*
X951642Y918375D01*
X951267Y918500D01*
X950892Y918458D01*
X950517Y918292D01*
G01X960200Y896500D02*
Y900500D01*
X952800D01*
G01X928517Y907000D02*
Y909500D01*
X929558D01*
X929892Y909375D01*
X930100Y909208D01*
X930183Y908875D01*
X930100Y908542D01*
X929850Y908333D01*
X929558Y908208D01*
X928517D01*
G01X929558D02*
X930183Y907000D01*
G01X931533Y907375D02*
X931783Y907167D01*
X932075Y907042D01*
X932450Y907000D01*
X932825Y907083D01*
X933117Y907250D01*
X933325Y907542D01*
X933367Y907875D01*
X933283Y908208D01*
X933075Y908417D01*
X932783Y908583D01*
X932492Y908625D01*
X932200Y908583D01*
X931825Y908417D01*
X931950Y909500D01*
X933075D01*
G01X935550Y907000D02*
Y909500D01*
X935050Y909000D01*
G01Y907000D02*
X936050D01*
G01X937733Y907500D02*
X937983Y907208D01*
X938317Y907042D01*
X938692Y907000D01*
X939025Y907042D01*
X939358Y907250D01*
X939567Y907500D01*
X939608Y907750D01*
X939525Y908042D01*
X939233Y908250D01*
X938942Y908333D01*
X938567D01*
G01X938942D02*
X939192Y908458D01*
X939400Y908667D01*
X939483Y908917D01*
X939400Y909167D01*
X939192Y909375D01*
X938817Y909500D01*
X938442Y909458D01*
X938067Y909292D01*
G01X946200Y896500D02*
Y900500D01*
X938800D01*
G01X928017Y883500D02*
Y886000D01*
X929058D01*
X929392Y885875D01*
X929600Y885708D01*
X929683Y885375D01*
X929600Y885042D01*
X929350Y884833D01*
X929058Y884708D01*
X928017D01*
G01X929058D02*
X929683Y883500D01*
G01X931033Y883875D02*
X931283Y883667D01*
X931575Y883542D01*
X931950Y883500D01*
X932325Y883583D01*
X932617Y883750D01*
X932825Y884042D01*
X932867Y884375D01*
X932783Y884708D01*
X932575Y884917D01*
X932283Y885083D01*
X931992Y885125D01*
X931700Y885083D01*
X931325Y884917D01*
X931450Y886000D01*
X932575D01*
G01X935050Y883500D02*
Y886000D01*
X934550Y885500D01*
G01Y883500D02*
X935550D01*
G01X938150Y886000D02*
X937817Y885917D01*
X937567Y885708D01*
X937400Y885458D01*
X937275Y885125D01*
X937233Y884750D01*
X937275Y884375D01*
X937400Y884042D01*
X937567Y883792D01*
X937817Y883583D01*
X938150Y883500D01*
X938483Y883583D01*
X938733Y883792D01*
X938900Y884042D01*
X939025Y884375D01*
X939067Y884750D01*
X939025Y885125D01*
X938900Y885458D01*
X938733Y885708D01*
X938483Y885917D01*
X938150Y886000D01*
G01X928300Y877500D02*
Y873500D01*
X935700D01*
G01X868867Y902453D02*
X868617Y902578D01*
X868325Y902661D01*
X867992D01*
X867617Y902536D01*
X867325Y902328D01*
X867117Y902078D01*
X866950Y901661D01*
X866908Y901286D01*
X866992Y900911D01*
X867117Y900661D01*
X867367Y900411D01*
X867658Y900244D01*
X867950Y900161D01*
X868242D01*
X868533Y900244D01*
X868783Y900369D01*
X868992Y900536D01*
G01X870133Y900661D02*
X870383Y900369D01*
X870717Y900203D01*
X871092Y900161D01*
X871425Y900203D01*
X871758Y900411D01*
X871967Y900661D01*
X872008Y900911D01*
X871925Y901203D01*
X871633Y901411D01*
X871342Y901494D01*
X870967D01*
G01X871342D02*
X871592Y901619D01*
X871800Y901828D01*
X871883Y902078D01*
X871800Y902328D01*
X871592Y902536D01*
X871217Y902661D01*
X870842Y902619D01*
X870467Y902453D01*
G01X929817Y889792D02*
X929567Y889917D01*
X929275Y890000D01*
X928942D01*
X928567Y889875D01*
X928275Y889667D01*
X928067Y889417D01*
X927900Y889000D01*
X927858Y888625D01*
X927942Y888250D01*
X928067Y888000D01*
X928317Y887750D01*
X928608Y887583D01*
X928900Y887500D01*
X929192D01*
X929483Y887583D01*
X929733Y887708D01*
X929942Y887875D01*
G01X932000Y887500D02*
Y890000D01*
X931500Y889500D01*
G01Y887500D02*
X932500D01*
G01X934183Y888000D02*
X934433Y887708D01*
X934767Y887542D01*
X935142Y887500D01*
X935475Y887542D01*
X935808Y887750D01*
X936017Y888000D01*
X936058Y888250D01*
X935975Y888542D01*
X935683Y888750D01*
X935392Y888833D01*
X935017D01*
G01X935392D02*
X935642Y888958D01*
X935850Y889167D01*
X935933Y889417D01*
X935850Y889667D01*
X935642Y889875D01*
X935267Y890000D01*
X934892Y889958D01*
X934517Y889792D01*
G01X931317Y905292D02*
X931067Y905417D01*
X930775Y905500D01*
X930442D01*
X930067Y905375D01*
X929775Y905167D01*
X929567Y904917D01*
X929400Y904500D01*
X929358Y904125D01*
X929442Y903750D01*
X929567Y903500D01*
X929817Y903250D01*
X930108Y903083D01*
X930400Y903000D01*
X930692D01*
X930983Y903083D01*
X931233Y903208D01*
X931442Y903375D01*
G01X933500Y903000D02*
Y905500D01*
X933000Y905000D01*
G01Y903000D02*
X934000D01*
G01X936517D02*
X936600Y903542D01*
X936725Y904000D01*
X936892Y904417D01*
X937100Y904875D01*
X937433Y905500D01*
X935767D01*
G01X880200Y910833D02*
X881992D01*
X882367Y911000D01*
X882617Y911333D01*
X882700Y911750D01*
X882617Y912167D01*
X882367Y912500D01*
X881992Y912667D01*
X880200D01*
G01X882700Y914850D02*
X882658Y915142D01*
X882533Y915475D01*
X882325Y915683D01*
X882033Y915767D01*
X881742Y915683D01*
X881492Y915433D01*
X881367Y915058D01*
Y914642D01*
X881283Y914392D01*
X881075Y914183D01*
X880783Y914100D01*
X880492Y914225D01*
X880283Y914517D01*
X880200Y914850D01*
X880283Y915183D01*
X880492Y915475D01*
X880783Y915600D01*
X881075Y915517D01*
X881283Y915308D01*
X881367Y915058D01*
Y914642D01*
X881492Y914267D01*
X881742Y914017D01*
X882033Y913933D01*
X882325Y914017D01*
X882533Y914225D01*
X882658Y914558D01*
X882700Y914850D01*
G01X920190Y906964D02*
Y885964D01*
X888540D01*
Y896964D01*
X920190D01*
G01Y888314D02*
X917040Y891464D01*
X920190Y894614D01*
G01X945270Y872130D02*
X943070Y869930D01*
G01X945270Y872130D02*
X943070Y874330D01*
G01Y879130D02*
Y865130D01*
G01X964570D02*
X943770D01*
G01X943070Y879130D02*
X964570D01*
G01X944900Y919500D02*
X944567Y919542D01*
X944275Y919708D01*
X944025Y919958D01*
X943858Y920250D01*
X943775Y920583D01*
Y920917D01*
X943858Y921250D01*
X944025Y921542D01*
X944275Y921792D01*
X944567Y921958D01*
X944900Y922000D01*
X945233Y921958D01*
X945525Y921792D01*
X945775Y921542D01*
X945942Y921250D01*
X946025Y920917D01*
Y920583D01*
X945942Y920250D01*
X945775Y919958D01*
X945525Y919708D01*
X945233Y919542D01*
X944900Y919500D01*
G01X945233Y920167D02*
X945733Y919500D01*
G01X947083Y920000D02*
X947333Y919708D01*
X947667Y919542D01*
X948042Y919500D01*
X948375Y919542D01*
X948708Y919750D01*
X948917Y920000D01*
X948958Y920250D01*
X948875Y920542D01*
X948583Y920750D01*
X948292Y920833D01*
X947917D01*
G01X948292D02*
X948542Y920958D01*
X948750Y921167D01*
X948833Y921417D01*
X948750Y921667D01*
X948542Y921875D01*
X948167Y922000D01*
X947792Y921958D01*
X947417Y921792D01*
G01X950183Y920000D02*
X950433Y919708D01*
X950767Y919542D01*
X951142Y919500D01*
X951475Y919542D01*
X951808Y919750D01*
X952017Y920000D01*
X952058Y920250D01*
X951975Y920542D01*
X951683Y920750D01*
X951392Y920833D01*
X951017D01*
G01X951392D02*
X951642Y920958D01*
X951850Y921167D01*
X951933Y921417D01*
X951850Y921667D01*
X951642Y921875D01*
X951267Y922000D01*
X950892Y921958D01*
X950517Y921792D01*
G01X958000Y914500D02*
X944000D01*
G01X958000Y901500D02*
Y914500D01*
G01X944000Y901500D02*
X958000D01*
G01X944000Y914500D02*
Y901500D01*
G01X940500Y859000D02*
Y873000D01*
G01X927500Y859000D02*
X940500D01*
G01X927500Y873000D02*
Y859000D01*
G01X940500Y873000D02*
X927500D01*
G01X875267Y1185159D02*
X875017Y1185284D01*
X874725Y1185367D01*
X874392D01*
X874017Y1185242D01*
X873725Y1185034D01*
X873517Y1184784D01*
X873350Y1184367D01*
X873308Y1183992D01*
X873392Y1183617D01*
X873517Y1183367D01*
X873767Y1183117D01*
X874058Y1182950D01*
X874350Y1182867D01*
X874642D01*
X874933Y1182950D01*
X875183Y1183075D01*
X875392Y1183242D01*
G01X877367Y1182867D02*
X877450Y1183409D01*
X877575Y1183867D01*
X877742Y1184284D01*
X877950Y1184742D01*
X878283Y1185367D01*
X876617D01*
G01X880550D02*
X880217Y1185284D01*
X879967Y1185075D01*
X879800Y1184825D01*
X879675Y1184492D01*
X879633Y1184117D01*
X879675Y1183742D01*
X879800Y1183409D01*
X879967Y1183159D01*
X880217Y1182950D01*
X880550Y1182867D01*
X880883Y1182950D01*
X881133Y1183159D01*
X881300Y1183409D01*
X881425Y1183742D01*
X881467Y1184117D01*
X881425Y1184492D01*
X881300Y1184825D01*
X881133Y1185075D01*
X880883Y1185284D01*
X880550Y1185367D01*
G01X882942Y1183159D02*
X883233Y1182950D01*
X883567Y1182867D01*
X883900Y1182950D01*
X884192Y1183200D01*
X884400Y1183575D01*
X884483Y1183950D01*
Y1184409D01*
X884400Y1184784D01*
X884192Y1185117D01*
X883942Y1185284D01*
X883650Y1185367D01*
X883317Y1185284D01*
X883067Y1185117D01*
X882900Y1184867D01*
X882817Y1184534D01*
X882900Y1184242D01*
X883108Y1183950D01*
X883358Y1183784D01*
X883650Y1183742D01*
X883983Y1183825D01*
X884233Y1184034D01*
X884483Y1184409D01*
G01X895567Y1187859D02*
X895317Y1187984D01*
X895025Y1188067D01*
X894692D01*
X894317Y1187942D01*
X894025Y1187734D01*
X893817Y1187484D01*
X893650Y1187067D01*
X893608Y1186692D01*
X893692Y1186317D01*
X893817Y1186067D01*
X894067Y1185817D01*
X894358Y1185650D01*
X894650Y1185567D01*
X894942D01*
X895233Y1185650D01*
X895483Y1185775D01*
X895692Y1185942D01*
G01X896958Y1186609D02*
X897250Y1186900D01*
X897500Y1187067D01*
X897833Y1187150D01*
X898125Y1187067D01*
X898333Y1186900D01*
X898500Y1186650D01*
X898542Y1186359D01*
X898500Y1186109D01*
X898333Y1185859D01*
X898083Y1185650D01*
X897792Y1185567D01*
X897458Y1185650D01*
X897167Y1185900D01*
X897000Y1186275D01*
X896958Y1186692D01*
X897042Y1187234D01*
X897167Y1187525D01*
X897375Y1187817D01*
X897667Y1188025D01*
X897958Y1188067D01*
X898250Y1187984D01*
X898458Y1187775D01*
G01X901350Y1185567D02*
Y1188067D01*
X899808Y1186275D01*
X901892D01*
G01X903242Y1185859D02*
X903533Y1185650D01*
X903867Y1185567D01*
X904200Y1185650D01*
X904492Y1185900D01*
X904700Y1186275D01*
X904783Y1186650D01*
Y1187109D01*
X904700Y1187484D01*
X904492Y1187817D01*
X904242Y1187984D01*
X903950Y1188067D01*
X903617Y1187984D01*
X903367Y1187817D01*
X903200Y1187567D01*
X903117Y1187234D01*
X903200Y1186942D01*
X903408Y1186650D01*
X903658Y1186484D01*
X903950Y1186442D01*
X904283Y1186525D01*
X904533Y1186734D01*
X904783Y1187109D01*
G01X956500Y1235967D02*
X954000D01*
Y1237008D01*
X954125Y1237342D01*
X954292Y1237550D01*
X954625Y1237633D01*
X954958Y1237550D01*
X955167Y1237300D01*
X955292Y1237008D01*
Y1235967D01*
G01Y1237008D02*
X956500Y1237633D01*
G01Y1239900D02*
X954000D01*
X954500Y1239400D01*
G01X956500D02*
Y1240400D01*
G01X954000Y1243000D02*
X954083Y1242667D01*
X954292Y1242417D01*
X954542Y1242250D01*
X954875Y1242125D01*
X955250Y1242083D01*
X955625Y1242125D01*
X955958Y1242250D01*
X956208Y1242417D01*
X956417Y1242667D01*
X956500Y1243000D01*
X956417Y1243333D01*
X956208Y1243583D01*
X955958Y1243750D01*
X955625Y1243875D01*
X955250Y1243917D01*
X954875Y1243875D01*
X954542Y1243750D01*
X954292Y1243583D01*
X954083Y1243333D01*
X954000Y1243000D01*
G01X956500Y1246100D02*
X956458Y1246392D01*
X956333Y1246725D01*
X956125Y1246933D01*
X955833Y1247017D01*
X955542Y1246933D01*
X955292Y1246683D01*
X955167Y1246308D01*
Y1245892D01*
X955083Y1245642D01*
X954875Y1245433D01*
X954583Y1245350D01*
X954292Y1245475D01*
X954083Y1245767D01*
X954000Y1246100D01*
X954083Y1246433D01*
X954292Y1246725D01*
X954583Y1246850D01*
X954875Y1246767D01*
X955083Y1246558D01*
X955167Y1246308D01*
Y1245892D01*
X955292Y1245517D01*
X955542Y1245267D01*
X955833Y1245183D01*
X956125Y1245267D01*
X956333Y1245475D01*
X956458Y1245808D01*
X956500Y1246100D01*
G01Y1249700D02*
X954000D01*
X955792Y1248158D01*
Y1250242D01*
G01X957500Y1231700D02*
X953500D01*
Y1224300D01*
G01X948500Y1235967D02*
X946000D01*
Y1237008D01*
X946125Y1237342D01*
X946292Y1237550D01*
X946625Y1237633D01*
X946958Y1237550D01*
X947167Y1237300D01*
X947292Y1237008D01*
Y1235967D01*
G01Y1237008D02*
X948500Y1237633D01*
G01Y1239900D02*
X946000D01*
X946500Y1239400D01*
G01X948500D02*
Y1240400D01*
G01X946000Y1243000D02*
X946083Y1242667D01*
X946292Y1242417D01*
X946542Y1242250D01*
X946875Y1242125D01*
X947250Y1242083D01*
X947625Y1242125D01*
X947958Y1242250D01*
X948208Y1242417D01*
X948417Y1242667D01*
X948500Y1243000D01*
X948417Y1243333D01*
X948208Y1243583D01*
X947958Y1243750D01*
X947625Y1243875D01*
X947250Y1243917D01*
X946875Y1243875D01*
X946542Y1243750D01*
X946292Y1243583D01*
X946083Y1243333D01*
X946000Y1243000D01*
G01X948500Y1246100D02*
X948458Y1246392D01*
X948333Y1246725D01*
X948125Y1246933D01*
X947833Y1247017D01*
X947542Y1246933D01*
X947292Y1246683D01*
X947167Y1246308D01*
Y1245892D01*
X947083Y1245642D01*
X946875Y1245433D01*
X946583Y1245350D01*
X946292Y1245475D01*
X946083Y1245767D01*
X946000Y1246100D01*
X946083Y1246433D01*
X946292Y1246725D01*
X946583Y1246850D01*
X946875Y1246767D01*
X947083Y1246558D01*
X947167Y1246308D01*
Y1245892D01*
X947292Y1245517D01*
X947542Y1245267D01*
X947833Y1245183D01*
X948125Y1245267D01*
X948333Y1245475D01*
X948458Y1245808D01*
X948500Y1246100D01*
G01X948125Y1248283D02*
X948333Y1248533D01*
X948458Y1248825D01*
X948500Y1249200D01*
X948417Y1249575D01*
X948250Y1249867D01*
X947958Y1250075D01*
X947625Y1250117D01*
X947292Y1250033D01*
X947083Y1249825D01*
X946917Y1249533D01*
X946875Y1249242D01*
X946917Y1248950D01*
X947083Y1248575D01*
X946000Y1248700D01*
Y1249825D01*
G01X949500Y1231700D02*
X945500D01*
Y1224300D01*
G01X960500Y1235967D02*
X958000D01*
Y1237008D01*
X958125Y1237342D01*
X958292Y1237550D01*
X958625Y1237633D01*
X958958Y1237550D01*
X959167Y1237300D01*
X959292Y1237008D01*
Y1235967D01*
G01Y1237008D02*
X960500Y1237633D01*
G01Y1239900D02*
X958000D01*
X958500Y1239400D01*
G01X960500D02*
Y1240400D01*
G01X958000Y1243000D02*
X958083Y1242667D01*
X958292Y1242417D01*
X958542Y1242250D01*
X958875Y1242125D01*
X959250Y1242083D01*
X959625Y1242125D01*
X959958Y1242250D01*
X960208Y1242417D01*
X960417Y1242667D01*
X960500Y1243000D01*
X960417Y1243333D01*
X960208Y1243583D01*
X959958Y1243750D01*
X959625Y1243875D01*
X959250Y1243917D01*
X958875Y1243875D01*
X958542Y1243750D01*
X958292Y1243583D01*
X958083Y1243333D01*
X958000Y1243000D01*
G01X960208Y1245392D02*
X960417Y1245683D01*
X960500Y1246017D01*
X960417Y1246350D01*
X960167Y1246642D01*
X959792Y1246850D01*
X959417Y1246933D01*
X958958D01*
X958583Y1246850D01*
X958250Y1246642D01*
X958083Y1246392D01*
X958000Y1246100D01*
X958083Y1245767D01*
X958250Y1245517D01*
X958500Y1245350D01*
X958833Y1245267D01*
X959125Y1245350D01*
X959417Y1245558D01*
X959583Y1245808D01*
X959625Y1246100D01*
X959542Y1246433D01*
X959333Y1246683D01*
X958958Y1246933D01*
G01X958417Y1248408D02*
X958167Y1248658D01*
X958042Y1248950D01*
X958000Y1249283D01*
X958083Y1249700D01*
X958292Y1249992D01*
X958542Y1250075D01*
X958792Y1250033D01*
X959000Y1249867D01*
X959417Y1249033D01*
X959708Y1248658D01*
X960125Y1248408D01*
X960500Y1248325D01*
Y1250075D01*
G01X957500Y1224300D02*
X961500D01*
Y1231700D01*
G01X952500Y1235967D02*
X950000D01*
Y1237008D01*
X950125Y1237342D01*
X950292Y1237550D01*
X950625Y1237633D01*
X950958Y1237550D01*
X951167Y1237300D01*
X951292Y1237008D01*
Y1235967D01*
G01Y1237008D02*
X952500Y1237633D01*
G01Y1239900D02*
X950000D01*
X950500Y1239400D01*
G01X952500D02*
Y1240400D01*
G01X950000Y1243000D02*
X950083Y1242667D01*
X950292Y1242417D01*
X950542Y1242250D01*
X950875Y1242125D01*
X951250Y1242083D01*
X951625Y1242125D01*
X951958Y1242250D01*
X952208Y1242417D01*
X952417Y1242667D01*
X952500Y1243000D01*
X952417Y1243333D01*
X952208Y1243583D01*
X951958Y1243750D01*
X951625Y1243875D01*
X951250Y1243917D01*
X950875Y1243875D01*
X950542Y1243750D01*
X950292Y1243583D01*
X950083Y1243333D01*
X950000Y1243000D01*
G01X952208Y1245392D02*
X952417Y1245683D01*
X952500Y1246017D01*
X952417Y1246350D01*
X952167Y1246642D01*
X951792Y1246850D01*
X951417Y1246933D01*
X950958D01*
X950583Y1246850D01*
X950250Y1246642D01*
X950083Y1246392D01*
X950000Y1246100D01*
X950083Y1245767D01*
X950250Y1245517D01*
X950500Y1245350D01*
X950833Y1245267D01*
X951125Y1245350D01*
X951417Y1245558D01*
X951583Y1245808D01*
X951625Y1246100D01*
X951542Y1246433D01*
X951333Y1246683D01*
X950958Y1246933D01*
G01X952000Y1248283D02*
X952292Y1248533D01*
X952458Y1248867D01*
X952500Y1249242D01*
X952458Y1249575D01*
X952250Y1249908D01*
X952000Y1250117D01*
X951750Y1250158D01*
X951458Y1250075D01*
X951250Y1249783D01*
X951167Y1249492D01*
Y1249117D01*
G01Y1249492D02*
X951042Y1249742D01*
X950833Y1249950D01*
X950583Y1250033D01*
X950333Y1249950D01*
X950125Y1249742D01*
X950000Y1249367D01*
X950042Y1248992D01*
X950208Y1248617D01*
G01X949500Y1224300D02*
X953500D01*
Y1231700D01*
G01X944500Y1235967D02*
X942000D01*
Y1237008D01*
X942125Y1237342D01*
X942292Y1237550D01*
X942625Y1237633D01*
X942958Y1237550D01*
X943167Y1237300D01*
X943292Y1237008D01*
Y1235967D01*
G01Y1237008D02*
X944500Y1237633D01*
G01Y1239900D02*
X942000D01*
X942500Y1239400D01*
G01X944500D02*
Y1240400D01*
G01X942000Y1243000D02*
X942083Y1242667D01*
X942292Y1242417D01*
X942542Y1242250D01*
X942875Y1242125D01*
X943250Y1242083D01*
X943625Y1242125D01*
X943958Y1242250D01*
X944208Y1242417D01*
X944417Y1242667D01*
X944500Y1243000D01*
X944417Y1243333D01*
X944208Y1243583D01*
X943958Y1243750D01*
X943625Y1243875D01*
X943250Y1243917D01*
X942875Y1243875D01*
X942542Y1243750D01*
X942292Y1243583D01*
X942083Y1243333D01*
X942000Y1243000D01*
G01X944208Y1245392D02*
X944417Y1245683D01*
X944500Y1246017D01*
X944417Y1246350D01*
X944167Y1246642D01*
X943792Y1246850D01*
X943417Y1246933D01*
X942958D01*
X942583Y1246850D01*
X942250Y1246642D01*
X942083Y1246392D01*
X942000Y1246100D01*
X942083Y1245767D01*
X942250Y1245517D01*
X942500Y1245350D01*
X942833Y1245267D01*
X943125Y1245350D01*
X943417Y1245558D01*
X943583Y1245808D01*
X943625Y1246100D01*
X943542Y1246433D01*
X943333Y1246683D01*
X942958Y1246933D01*
G01X943458Y1248408D02*
X943167Y1248700D01*
X943000Y1248950D01*
X942917Y1249283D01*
X943000Y1249575D01*
X943167Y1249783D01*
X943417Y1249950D01*
X943708Y1249992D01*
X943958Y1249950D01*
X944208Y1249783D01*
X944417Y1249533D01*
X944500Y1249242D01*
X944417Y1248908D01*
X944167Y1248617D01*
X943792Y1248450D01*
X943375Y1248408D01*
X942833Y1248492D01*
X942542Y1248617D01*
X942250Y1248825D01*
X942042Y1249117D01*
X942000Y1249408D01*
X942083Y1249700D01*
X942292Y1249908D01*
G01X945500Y1231700D02*
X941500D01*
Y1224300D01*
G01X865334Y1180017D02*
X862834D01*
Y1181058D01*
X862959Y1181392D01*
X863126Y1181600D01*
X863459Y1181683D01*
X863792Y1181600D01*
X864001Y1181350D01*
X864126Y1181058D01*
Y1180017D01*
G01Y1181058D02*
X865334Y1181683D01*
G01X864959Y1183033D02*
X865167Y1183283D01*
X865292Y1183575D01*
X865334Y1183950D01*
X865251Y1184325D01*
X865084Y1184617D01*
X864792Y1184825D01*
X864459Y1184867D01*
X864126Y1184783D01*
X863917Y1184575D01*
X863751Y1184283D01*
X863709Y1183992D01*
X863751Y1183700D01*
X863917Y1183325D01*
X862834Y1183450D01*
Y1184575D01*
G01Y1187050D02*
X862917Y1186717D01*
X863126Y1186467D01*
X863376Y1186300D01*
X863709Y1186175D01*
X864084Y1186133D01*
X864459Y1186175D01*
X864792Y1186300D01*
X865042Y1186467D01*
X865251Y1186717D01*
X865334Y1187050D01*
X865251Y1187383D01*
X865042Y1187633D01*
X864792Y1187800D01*
X864459Y1187925D01*
X864084Y1187967D01*
X863709Y1187925D01*
X863376Y1187800D01*
X863126Y1187633D01*
X862917Y1187383D01*
X862834Y1187050D01*
G01X865042Y1189442D02*
X865251Y1189733D01*
X865334Y1190067D01*
X865251Y1190400D01*
X865001Y1190692D01*
X864626Y1190900D01*
X864251Y1190983D01*
X863792D01*
X863417Y1190900D01*
X863084Y1190692D01*
X862917Y1190442D01*
X862834Y1190150D01*
X862917Y1189817D01*
X863084Y1189567D01*
X863334Y1189400D01*
X863667Y1189317D01*
X863959Y1189400D01*
X864251Y1189608D01*
X864417Y1189858D01*
X864459Y1190150D01*
X864376Y1190483D01*
X864167Y1190733D01*
X863792Y1190983D01*
G01X866900Y1182800D02*
X870900D01*
Y1190200D01*
G01X889634Y1178617D02*
X887134D01*
Y1179658D01*
X887259Y1179992D01*
X887426Y1180200D01*
X887759Y1180283D01*
X888092Y1180200D01*
X888301Y1179950D01*
X888426Y1179658D01*
Y1178617D01*
G01Y1179658D02*
X889634Y1180283D01*
G01X889259Y1181633D02*
X889467Y1181883D01*
X889592Y1182175D01*
X889634Y1182550D01*
X889551Y1182925D01*
X889384Y1183217D01*
X889092Y1183425D01*
X888759Y1183467D01*
X888426Y1183383D01*
X888217Y1183175D01*
X888051Y1182883D01*
X888009Y1182592D01*
X888051Y1182300D01*
X888217Y1181925D01*
X887134Y1182050D01*
Y1183175D01*
G01Y1185650D02*
X887217Y1185317D01*
X887426Y1185067D01*
X887676Y1184900D01*
X888009Y1184775D01*
X888384Y1184733D01*
X888759Y1184775D01*
X889092Y1184900D01*
X889342Y1185067D01*
X889551Y1185317D01*
X889634Y1185650D01*
X889551Y1185983D01*
X889342Y1186233D01*
X889092Y1186400D01*
X888759Y1186525D01*
X888384Y1186567D01*
X888009Y1186525D01*
X887676Y1186400D01*
X887426Y1186233D01*
X887217Y1185983D01*
X887134Y1185650D01*
G01X889259Y1187833D02*
X889467Y1188083D01*
X889592Y1188375D01*
X889634Y1188750D01*
X889551Y1189125D01*
X889384Y1189417D01*
X889092Y1189625D01*
X888759Y1189667D01*
X888426Y1189583D01*
X888217Y1189375D01*
X888051Y1189083D01*
X888009Y1188792D01*
X888051Y1188500D01*
X888217Y1188125D01*
X887134Y1188250D01*
Y1189375D01*
G01X886000Y1191900D02*
X890000D01*
Y1199300D01*
G01X865434Y1197550D02*
X865392Y1197217D01*
X865226Y1196925D01*
X864976Y1196675D01*
X864684Y1196508D01*
X864351Y1196425D01*
X864017D01*
X863684Y1196508D01*
X863392Y1196675D01*
X863142Y1196925D01*
X862976Y1197217D01*
X862934Y1197550D01*
X862976Y1197883D01*
X863142Y1198175D01*
X863392Y1198425D01*
X863684Y1198592D01*
X864017Y1198675D01*
X864351D01*
X864684Y1198592D01*
X864976Y1198425D01*
X865226Y1198175D01*
X865392Y1197883D01*
X865434Y1197550D01*
G01X864767Y1197883D02*
X865434Y1198383D01*
G01X863351Y1199858D02*
X863101Y1200108D01*
X862976Y1200400D01*
X862934Y1200733D01*
X863017Y1201150D01*
X863226Y1201442D01*
X863476Y1201525D01*
X863726Y1201483D01*
X863934Y1201317D01*
X864351Y1200483D01*
X864642Y1200108D01*
X865059Y1199858D01*
X865434Y1199775D01*
Y1201525D01*
G01X864392Y1202958D02*
X864101Y1203250D01*
X863934Y1203500D01*
X863851Y1203833D01*
X863934Y1204125D01*
X864101Y1204333D01*
X864351Y1204500D01*
X864642Y1204542D01*
X864892Y1204500D01*
X865142Y1204333D01*
X865351Y1204083D01*
X865434Y1203792D01*
X865351Y1203458D01*
X865101Y1203167D01*
X864726Y1203000D01*
X864309Y1202958D01*
X863767Y1203042D01*
X863476Y1203167D01*
X863184Y1203375D01*
X862976Y1203667D01*
X862934Y1203958D01*
X863017Y1204250D01*
X863226Y1204458D01*
G01X865434Y1206850D02*
X865392Y1207142D01*
X865267Y1207475D01*
X865059Y1207683D01*
X864767Y1207767D01*
X864476Y1207683D01*
X864226Y1207433D01*
X864101Y1207058D01*
Y1206642D01*
X864017Y1206392D01*
X863809Y1206183D01*
X863517Y1206100D01*
X863226Y1206225D01*
X863017Y1206517D01*
X862934Y1206850D01*
X863017Y1207183D01*
X863226Y1207475D01*
X863517Y1207600D01*
X863809Y1207517D01*
X864017Y1207308D01*
X864101Y1207058D01*
Y1206642D01*
X864226Y1206267D01*
X864476Y1206017D01*
X864767Y1205933D01*
X865059Y1206017D01*
X865267Y1206225D01*
X865392Y1206558D01*
X865434Y1206850D01*
G01X867500Y1208900D02*
Y1194900D01*
G01X880500Y1208900D02*
X867500D01*
G01X880500Y1194900D02*
Y1208900D01*
G01X867500Y1194900D02*
X880500D01*
G01X934983Y1217500D02*
Y1215708D01*
X935150Y1215333D01*
X935483Y1215083D01*
X935900Y1215000D01*
X936317Y1215083D01*
X936650Y1215333D01*
X936817Y1215708D01*
Y1217500D01*
G01X938083Y1215500D02*
X938333Y1215208D01*
X938667Y1215042D01*
X939042Y1215000D01*
X939375Y1215042D01*
X939708Y1215250D01*
X939917Y1215500D01*
X939958Y1215750D01*
X939875Y1216042D01*
X939583Y1216250D01*
X939292Y1216333D01*
X938917D01*
G01X939292D02*
X939542Y1216458D01*
X939750Y1216667D01*
X939833Y1216917D01*
X939750Y1217167D01*
X939542Y1217375D01*
X939167Y1217500D01*
X938792Y1217458D01*
X938417Y1217292D01*
G01X942100Y1217500D02*
X941767Y1217417D01*
X941517Y1217208D01*
X941350Y1216958D01*
X941225Y1216625D01*
X941183Y1216250D01*
X941225Y1215875D01*
X941350Y1215542D01*
X941517Y1215292D01*
X941767Y1215083D01*
X942100Y1215000D01*
X942433Y1215083D01*
X942683Y1215292D01*
X942850Y1215542D01*
X942975Y1215875D01*
X943017Y1216250D01*
X942975Y1216625D01*
X942850Y1216958D01*
X942683Y1217208D01*
X942433Y1217417D01*
X942100Y1217500D01*
G01X946050Y1209100D02*
X943050D01*
G01X952300Y1196550D02*
Y1194550D01*
G01X955400Y1218450D02*
Y1220450D01*
G01X945150Y1200650D02*
Y1195650D01*
X950150D01*
G01X945150Y1214350D02*
Y1219350D01*
X950150D01*
G01X905083Y1226266D02*
Y1224474D01*
X905250Y1224099D01*
X905583Y1223849D01*
X906000Y1223766D01*
X906417Y1223849D01*
X906750Y1224099D01*
X906917Y1224474D01*
Y1226266D01*
G01X909100Y1223766D02*
Y1226266D01*
X908600Y1225766D01*
G01Y1223766D02*
X909600D01*
G01X912200D02*
X912492Y1223808D01*
X912825Y1223933D01*
X913033Y1224141D01*
X913117Y1224433D01*
X913033Y1224724D01*
X912783Y1224974D01*
X912408Y1225099D01*
X911992D01*
X911742Y1225183D01*
X911533Y1225391D01*
X911450Y1225683D01*
X911575Y1225974D01*
X911867Y1226183D01*
X912200Y1226266D01*
X912533Y1226183D01*
X912825Y1225974D01*
X912950Y1225683D01*
X912867Y1225391D01*
X912658Y1225183D01*
X912408Y1225099D01*
X911992D01*
X911617Y1224974D01*
X911367Y1224724D01*
X911283Y1224433D01*
X911367Y1224141D01*
X911575Y1223933D01*
X911908Y1223808D01*
X912200Y1223766D01*
G01X882473Y1309819D02*
X882348Y1309569D01*
X882265Y1309277D01*
Y1308944D01*
X882390Y1308569D01*
X882598Y1308277D01*
X882848Y1308069D01*
X883265Y1307902D01*
X883640Y1307860D01*
X884015Y1307944D01*
X884265Y1308069D01*
X884515Y1308319D01*
X884682Y1308610D01*
X884765Y1308902D01*
Y1309194D01*
X884682Y1309485D01*
X884557Y1309735D01*
X884390Y1309944D01*
G01Y1311085D02*
X884598Y1311335D01*
X884723Y1311627D01*
X884765Y1312002D01*
X884682Y1312377D01*
X884515Y1312669D01*
X884223Y1312877D01*
X883890Y1312919D01*
X883557Y1312835D01*
X883348Y1312627D01*
X883182Y1312335D01*
X883140Y1312044D01*
X883182Y1311752D01*
X883348Y1311377D01*
X882265Y1311502D01*
Y1312627D01*
G01Y1315102D02*
X882348Y1314769D01*
X882557Y1314519D01*
X882807Y1314352D01*
X883140Y1314227D01*
X883515Y1314185D01*
X883890Y1314227D01*
X884223Y1314352D01*
X884473Y1314519D01*
X884682Y1314769D01*
X884765Y1315102D01*
X884682Y1315435D01*
X884473Y1315685D01*
X884223Y1315852D01*
X883890Y1315977D01*
X883515Y1316019D01*
X883140Y1315977D01*
X882807Y1315852D01*
X882557Y1315685D01*
X882348Y1315435D01*
X882265Y1315102D01*
G01X884473Y1317494D02*
X884682Y1317785D01*
X884765Y1318119D01*
X884682Y1318452D01*
X884432Y1318744D01*
X884057Y1318952D01*
X883682Y1319035D01*
X883223D01*
X882848Y1318952D01*
X882515Y1318744D01*
X882348Y1318494D01*
X882265Y1318202D01*
X882348Y1317869D01*
X882515Y1317619D01*
X882765Y1317452D01*
X883098Y1317369D01*
X883390Y1317452D01*
X883682Y1317660D01*
X883848Y1317910D01*
X883890Y1318202D01*
X883807Y1318535D01*
X883598Y1318785D01*
X883223Y1319035D01*
G01X866406Y1286164D02*
Y1304864D01*
X876706D01*
Y1286164D01*
X866406D01*
G01X869776Y1308792D02*
X869651Y1308542D01*
X869568Y1308250D01*
Y1307917D01*
X869693Y1307542D01*
X869901Y1307250D01*
X870151Y1307042D01*
X870568Y1306875D01*
X870943Y1306833D01*
X871318Y1306917D01*
X871568Y1307042D01*
X871818Y1307292D01*
X871985Y1307583D01*
X872068Y1307875D01*
Y1308167D01*
X871985Y1308458D01*
X871860Y1308708D01*
X871693Y1308917D01*
G01Y1310058D02*
X871901Y1310308D01*
X872026Y1310600D01*
X872068Y1310975D01*
X871985Y1311350D01*
X871818Y1311642D01*
X871526Y1311850D01*
X871193Y1311892D01*
X870860Y1311808D01*
X870651Y1311600D01*
X870485Y1311308D01*
X870443Y1311017D01*
X870485Y1310725D01*
X870651Y1310350D01*
X869568Y1310475D01*
Y1311600D01*
G01X872068Y1314075D02*
X869568D01*
X870068Y1313575D01*
G01X872068D02*
Y1314575D01*
G01X869568Y1317175D02*
X869651Y1316842D01*
X869860Y1316592D01*
X870110Y1316425D01*
X870443Y1316300D01*
X870818Y1316258D01*
X871193Y1316300D01*
X871526Y1316425D01*
X871776Y1316592D01*
X871985Y1316842D01*
X872068Y1317175D01*
X871985Y1317508D01*
X871776Y1317758D01*
X871526Y1317925D01*
X871193Y1318050D01*
X870818Y1318092D01*
X870443Y1318050D01*
X870110Y1317925D01*
X869860Y1317758D01*
X869651Y1317508D01*
X869568Y1317175D01*
G01X878906Y1286164D02*
Y1304864D01*
X889206D01*
Y1286164D01*
X878906D01*
G01X942300Y1328700D02*
Y1359700D01*
X986300D01*
Y1328700D01*
X942300D01*
G01X937574Y1408873D02*
X937449Y1408623D01*
X937366Y1408331D01*
Y1407998D01*
X937491Y1407623D01*
X937699Y1407331D01*
X937949Y1407123D01*
X938366Y1406956D01*
X938741Y1406914D01*
X939116Y1406998D01*
X939366Y1407123D01*
X939616Y1407373D01*
X939783Y1407664D01*
X939866Y1407956D01*
Y1408248D01*
X939783Y1408539D01*
X939658Y1408789D01*
X939491Y1408998D01*
G01Y1410139D02*
X939699Y1410389D01*
X939824Y1410681D01*
X939866Y1411056D01*
X939783Y1411431D01*
X939616Y1411723D01*
X939324Y1411931D01*
X938991Y1411973D01*
X938658Y1411889D01*
X938449Y1411681D01*
X938283Y1411389D01*
X938241Y1411098D01*
X938283Y1410806D01*
X938449Y1410431D01*
X937366Y1410556D01*
Y1411681D01*
G01X938824Y1413364D02*
X938533Y1413656D01*
X938366Y1413906D01*
X938283Y1414239D01*
X938366Y1414531D01*
X938533Y1414739D01*
X938783Y1414906D01*
X939074Y1414948D01*
X939324Y1414906D01*
X939574Y1414739D01*
X939783Y1414489D01*
X939866Y1414198D01*
X939783Y1413864D01*
X939533Y1413573D01*
X939158Y1413406D01*
X938741Y1413364D01*
X938199Y1413448D01*
X937908Y1413573D01*
X937616Y1413781D01*
X937408Y1414073D01*
X937366Y1414364D01*
X937449Y1414656D01*
X937658Y1414864D01*
G01X939866Y1417256D02*
X937366D01*
X937866Y1416756D01*
G01X939866D02*
Y1417756D01*
G01X924574Y1408973D02*
X924449Y1408723D01*
X924366Y1408431D01*
Y1408098D01*
X924491Y1407723D01*
X924699Y1407431D01*
X924949Y1407223D01*
X925366Y1407056D01*
X925741Y1407014D01*
X926116Y1407098D01*
X926366Y1407223D01*
X926616Y1407473D01*
X926783Y1407764D01*
X926866Y1408056D01*
Y1408348D01*
X926783Y1408639D01*
X926658Y1408889D01*
X926491Y1409098D01*
G01Y1410239D02*
X926699Y1410489D01*
X926824Y1410781D01*
X926866Y1411156D01*
X926783Y1411531D01*
X926616Y1411823D01*
X926324Y1412031D01*
X925991Y1412073D01*
X925658Y1411989D01*
X925449Y1411781D01*
X925283Y1411489D01*
X925241Y1411198D01*
X925283Y1410906D01*
X925449Y1410531D01*
X924366Y1410656D01*
Y1411781D01*
G01X925824Y1413464D02*
X925533Y1413756D01*
X925366Y1414006D01*
X925283Y1414339D01*
X925366Y1414631D01*
X925533Y1414839D01*
X925783Y1415006D01*
X926074Y1415048D01*
X926324Y1415006D01*
X926574Y1414839D01*
X926783Y1414589D01*
X926866Y1414298D01*
X926783Y1413964D01*
X926533Y1413673D01*
X926158Y1413506D01*
X925741Y1413464D01*
X925199Y1413548D01*
X924908Y1413673D01*
X924616Y1413881D01*
X924408Y1414173D01*
X924366Y1414464D01*
X924449Y1414756D01*
X924658Y1414964D01*
G01X924366Y1417356D02*
X924449Y1417023D01*
X924658Y1416773D01*
X924908Y1416606D01*
X925241Y1416481D01*
X925616Y1416439D01*
X925991Y1416481D01*
X926324Y1416606D01*
X926574Y1416773D01*
X926783Y1417023D01*
X926866Y1417356D01*
X926783Y1417689D01*
X926574Y1417939D01*
X926324Y1418106D01*
X925991Y1418231D01*
X925616Y1418273D01*
X925241Y1418231D01*
X924908Y1418106D01*
X924658Y1417939D01*
X924449Y1417689D01*
X924366Y1417356D01*
G01X902374Y1409173D02*
X902249Y1408923D01*
X902166Y1408631D01*
Y1408298D01*
X902291Y1407923D01*
X902499Y1407631D01*
X902749Y1407423D01*
X903166Y1407256D01*
X903541Y1407214D01*
X903916Y1407298D01*
X904166Y1407423D01*
X904416Y1407673D01*
X904583Y1407964D01*
X904666Y1408256D01*
Y1408548D01*
X904583Y1408839D01*
X904458Y1409089D01*
X904291Y1409298D01*
G01Y1410439D02*
X904499Y1410689D01*
X904624Y1410981D01*
X904666Y1411356D01*
X904583Y1411731D01*
X904416Y1412023D01*
X904124Y1412231D01*
X903791Y1412273D01*
X903458Y1412189D01*
X903249Y1411981D01*
X903083Y1411689D01*
X903041Y1411398D01*
X903083Y1411106D01*
X903249Y1410731D01*
X902166Y1410856D01*
Y1411981D01*
G01X904291Y1413539D02*
X904499Y1413789D01*
X904624Y1414081D01*
X904666Y1414456D01*
X904583Y1414831D01*
X904416Y1415123D01*
X904124Y1415331D01*
X903791Y1415373D01*
X903458Y1415289D01*
X903249Y1415081D01*
X903083Y1414789D01*
X903041Y1414498D01*
X903083Y1414206D01*
X903249Y1413831D01*
X902166Y1413956D01*
Y1415081D01*
G01X904374Y1416848D02*
X904583Y1417139D01*
X904666Y1417473D01*
X904583Y1417806D01*
X904333Y1418098D01*
X903958Y1418306D01*
X903583Y1418389D01*
X903124D01*
X902749Y1418306D01*
X902416Y1418098D01*
X902249Y1417848D01*
X902166Y1417556D01*
X902249Y1417223D01*
X902416Y1416973D01*
X902666Y1416806D01*
X902999Y1416723D01*
X903291Y1416806D01*
X903583Y1417014D01*
X903749Y1417264D01*
X903791Y1417556D01*
X903708Y1417889D01*
X903499Y1418139D01*
X903124Y1418389D01*
G01X949095Y1373245D02*
X948970Y1372995D01*
X948887Y1372703D01*
Y1372370D01*
X949012Y1371995D01*
X949220Y1371703D01*
X949470Y1371495D01*
X949887Y1371328D01*
X950262Y1371286D01*
X950637Y1371370D01*
X950887Y1371495D01*
X951137Y1371745D01*
X951304Y1372036D01*
X951387Y1372328D01*
Y1372620D01*
X951304Y1372911D01*
X951179Y1373161D01*
X951012Y1373370D01*
G01Y1374511D02*
X951220Y1374761D01*
X951345Y1375053D01*
X951387Y1375428D01*
X951304Y1375803D01*
X951137Y1376095D01*
X950845Y1376303D01*
X950512Y1376345D01*
X950179Y1376261D01*
X949970Y1376053D01*
X949804Y1375761D01*
X949762Y1375470D01*
X949804Y1375178D01*
X949970Y1374803D01*
X948887Y1374928D01*
Y1376053D01*
G01X950345Y1377736D02*
X950054Y1378028D01*
X949887Y1378278D01*
X949804Y1378611D01*
X949887Y1378903D01*
X950054Y1379111D01*
X950304Y1379278D01*
X950595Y1379320D01*
X950845Y1379278D01*
X951095Y1379111D01*
X951304Y1378861D01*
X951387Y1378570D01*
X951304Y1378236D01*
X951054Y1377945D01*
X950679Y1377778D01*
X950262Y1377736D01*
X949720Y1377820D01*
X949429Y1377945D01*
X949137Y1378153D01*
X948929Y1378445D01*
X948887Y1378736D01*
X948970Y1379028D01*
X949179Y1379236D01*
G01X950887Y1380711D02*
X951179Y1380961D01*
X951345Y1381295D01*
X951387Y1381670D01*
X951345Y1382003D01*
X951137Y1382336D01*
X950887Y1382545D01*
X950637Y1382586D01*
X950345Y1382503D01*
X950137Y1382211D01*
X950054Y1381920D01*
Y1381545D01*
G01Y1381920D02*
X949929Y1382170D01*
X949720Y1382378D01*
X949470Y1382461D01*
X949220Y1382378D01*
X949012Y1382170D01*
X948887Y1381795D01*
X948929Y1381420D01*
X949095Y1381045D01*
G01X933567Y1422700D02*
Y1425200D01*
X934608D01*
X934942Y1425075D01*
X935150Y1424908D01*
X935233Y1424575D01*
X935150Y1424242D01*
X934900Y1424033D01*
X934608Y1423908D01*
X933567D01*
G01X934608D02*
X935233Y1422700D01*
G01X937500D02*
Y1425200D01*
X937000Y1424700D01*
G01Y1422700D02*
X938000D01*
G01X940600Y1425200D02*
X940267Y1425117D01*
X940017Y1424908D01*
X939850Y1424658D01*
X939725Y1424325D01*
X939683Y1423950D01*
X939725Y1423575D01*
X939850Y1423242D01*
X940017Y1422992D01*
X940267Y1422783D01*
X940600Y1422700D01*
X940933Y1422783D01*
X941183Y1422992D01*
X941350Y1423242D01*
X941475Y1423575D01*
X941517Y1423950D01*
X941475Y1424325D01*
X941350Y1424658D01*
X941183Y1424908D01*
X940933Y1425117D01*
X940600Y1425200D01*
G01X944200Y1422700D02*
Y1425200D01*
X942658Y1423408D01*
X944742D01*
G01X945883Y1423075D02*
X946133Y1422867D01*
X946425Y1422742D01*
X946800Y1422700D01*
X947175Y1422783D01*
X947467Y1422950D01*
X947675Y1423242D01*
X947717Y1423575D01*
X947633Y1423908D01*
X947425Y1424117D01*
X947133Y1424283D01*
X946842Y1424325D01*
X946550Y1424283D01*
X946175Y1424117D01*
X946300Y1425200D01*
X947425D01*
G01X899567Y1422900D02*
Y1425400D01*
X900608D01*
X900942Y1425275D01*
X901150Y1425108D01*
X901233Y1424775D01*
X901150Y1424442D01*
X900900Y1424233D01*
X900608Y1424108D01*
X899567D01*
G01X900608D02*
X901233Y1422900D01*
G01X903500D02*
Y1425400D01*
X903000Y1424900D01*
G01Y1422900D02*
X904000D01*
G01X906600Y1425400D02*
X906267Y1425317D01*
X906017Y1425108D01*
X905850Y1424858D01*
X905725Y1424525D01*
X905683Y1424150D01*
X905725Y1423775D01*
X905850Y1423442D01*
X906017Y1423192D01*
X906267Y1422983D01*
X906600Y1422900D01*
X906933Y1422983D01*
X907183Y1423192D01*
X907350Y1423442D01*
X907475Y1423775D01*
X907517Y1424150D01*
X907475Y1424525D01*
X907350Y1424858D01*
X907183Y1425108D01*
X906933Y1425317D01*
X906600Y1425400D01*
G01X910200Y1422900D02*
Y1425400D01*
X908658Y1423608D01*
X910742D01*
G01X912800Y1422900D02*
Y1425400D01*
X912300Y1424900D01*
G01Y1422900D02*
X913300D01*
G01X916467Y1422700D02*
Y1425200D01*
X917508D01*
X917842Y1425075D01*
X918050Y1424908D01*
X918133Y1424575D01*
X918050Y1424242D01*
X917800Y1424033D01*
X917508Y1423908D01*
X916467D01*
G01X917508D02*
X918133Y1422700D01*
G01X920400D02*
Y1425200D01*
X919900Y1424700D01*
G01Y1422700D02*
X920900D01*
G01X923500Y1425200D02*
X923167Y1425117D01*
X922917Y1424908D01*
X922750Y1424658D01*
X922625Y1424325D01*
X922583Y1423950D01*
X922625Y1423575D01*
X922750Y1423242D01*
X922917Y1422992D01*
X923167Y1422783D01*
X923500Y1422700D01*
X923833Y1422783D01*
X924083Y1422992D01*
X924250Y1423242D01*
X924375Y1423575D01*
X924417Y1423950D01*
X924375Y1424325D01*
X924250Y1424658D01*
X924083Y1424908D01*
X923833Y1425117D01*
X923500Y1425200D01*
G01X927100Y1422700D02*
Y1425200D01*
X925558Y1423408D01*
X927642D01*
G01X928783Y1423200D02*
X929033Y1422908D01*
X929367Y1422742D01*
X929742Y1422700D01*
X930075Y1422742D01*
X930408Y1422950D01*
X930617Y1423200D01*
X930658Y1423450D01*
X930575Y1423742D01*
X930283Y1423950D01*
X929992Y1424033D01*
X929617D01*
G01X929992D02*
X930242Y1424158D01*
X930450Y1424367D01*
X930533Y1424617D01*
X930450Y1424867D01*
X930242Y1425075D01*
X929867Y1425200D01*
X929492Y1425158D01*
X929117Y1424992D01*
G01X908666Y1407423D02*
X906166D01*
Y1408464D01*
X906291Y1408798D01*
X906458Y1409006D01*
X906791Y1409089D01*
X907124Y1409006D01*
X907333Y1408756D01*
X907458Y1408464D01*
Y1407423D01*
G01Y1408464D02*
X908666Y1409089D01*
G01Y1411356D02*
X906166D01*
X906666Y1410856D01*
G01X908666D02*
Y1411856D01*
G01X906166Y1414456D02*
X906249Y1414123D01*
X906458Y1413873D01*
X906708Y1413706D01*
X907041Y1413581D01*
X907416Y1413539D01*
X907791Y1413581D01*
X908124Y1413706D01*
X908374Y1413873D01*
X908583Y1414123D01*
X908666Y1414456D01*
X908583Y1414789D01*
X908374Y1415039D01*
X908124Y1415206D01*
X907791Y1415331D01*
X907416Y1415373D01*
X907041Y1415331D01*
X906708Y1415206D01*
X906458Y1415039D01*
X906249Y1414789D01*
X906166Y1414456D01*
G01X908666Y1418056D02*
X906166D01*
X907958Y1416514D01*
Y1418598D01*
G01X906583Y1419864D02*
X906333Y1420114D01*
X906208Y1420406D01*
X906166Y1420739D01*
X906249Y1421156D01*
X906458Y1421448D01*
X906708Y1421531D01*
X906958Y1421489D01*
X907166Y1421323D01*
X907583Y1420489D01*
X907874Y1420114D01*
X908291Y1419864D01*
X908666Y1419781D01*
Y1421531D01*
G01X922866Y1407223D02*
X920366D01*
Y1408264D01*
X920491Y1408598D01*
X920658Y1408806D01*
X920991Y1408889D01*
X921324Y1408806D01*
X921533Y1408556D01*
X921658Y1408264D01*
Y1407223D01*
G01Y1408264D02*
X922866Y1408889D01*
G01Y1411156D02*
X920366D01*
X920866Y1410656D01*
G01X922866D02*
Y1411656D01*
G01X920366Y1414256D02*
X920449Y1413923D01*
X920658Y1413673D01*
X920908Y1413506D01*
X921241Y1413381D01*
X921616Y1413339D01*
X921991Y1413381D01*
X922324Y1413506D01*
X922574Y1413673D01*
X922783Y1413923D01*
X922866Y1414256D01*
X922783Y1414589D01*
X922574Y1414839D01*
X922324Y1415006D01*
X921991Y1415131D01*
X921616Y1415173D01*
X921241Y1415131D01*
X920908Y1415006D01*
X920658Y1414839D01*
X920449Y1414589D01*
X920366Y1414256D01*
G01X922866Y1417856D02*
X920366D01*
X922158Y1416314D01*
Y1418398D01*
G01X922866Y1420956D02*
X920366D01*
X922158Y1419414D01*
Y1421498D01*
G01X935866Y1407123D02*
X933366D01*
Y1408164D01*
X933491Y1408498D01*
X933658Y1408706D01*
X933991Y1408789D01*
X934324Y1408706D01*
X934533Y1408456D01*
X934658Y1408164D01*
Y1407123D01*
G01Y1408164D02*
X935866Y1408789D01*
G01Y1411056D02*
X933366D01*
X933866Y1410556D01*
G01X935866D02*
Y1411556D01*
G01X933366Y1414156D02*
X933449Y1413823D01*
X933658Y1413573D01*
X933908Y1413406D01*
X934241Y1413281D01*
X934616Y1413239D01*
X934991Y1413281D01*
X935324Y1413406D01*
X935574Y1413573D01*
X935783Y1413823D01*
X935866Y1414156D01*
X935783Y1414489D01*
X935574Y1414739D01*
X935324Y1414906D01*
X934991Y1415031D01*
X934616Y1415073D01*
X934241Y1415031D01*
X933908Y1414906D01*
X933658Y1414739D01*
X933449Y1414489D01*
X933366Y1414156D01*
G01X935866Y1417756D02*
X933366D01*
X935158Y1416214D01*
Y1418298D01*
G01X934824Y1419564D02*
X934533Y1419856D01*
X934366Y1420106D01*
X934283Y1420439D01*
X934366Y1420731D01*
X934533Y1420939D01*
X934783Y1421106D01*
X935074Y1421148D01*
X935324Y1421106D01*
X935574Y1420939D01*
X935783Y1420689D01*
X935866Y1420398D01*
X935783Y1420064D01*
X935533Y1419773D01*
X935158Y1419606D01*
X934741Y1419564D01*
X934199Y1419648D01*
X933908Y1419773D01*
X933616Y1419981D01*
X933408Y1420273D01*
X933366Y1420564D01*
X933449Y1420856D01*
X933658Y1421064D01*
G01X871937Y1392329D02*
X867937D01*
Y1384929D01*
G01X870702Y1407436D02*
Y1409936D01*
X871743D01*
X872077Y1409811D01*
X872285Y1409644D01*
X872368Y1409311D01*
X872285Y1408978D01*
X872035Y1408769D01*
X871743Y1408644D01*
X870702D01*
G01X871743D02*
X872368Y1407436D01*
G01X874635D02*
Y1409936D01*
X874135Y1409436D01*
G01Y1407436D02*
X875135D01*
G01X877735Y1409936D02*
X877402Y1409853D01*
X877152Y1409644D01*
X876985Y1409394D01*
X876860Y1409061D01*
X876818Y1408686D01*
X876860Y1408311D01*
X876985Y1407978D01*
X877152Y1407728D01*
X877402Y1407519D01*
X877735Y1407436D01*
X878068Y1407519D01*
X878318Y1407728D01*
X878485Y1407978D01*
X878610Y1408311D01*
X878652Y1408686D01*
X878610Y1409061D01*
X878485Y1409394D01*
X878318Y1409644D01*
X878068Y1409853D01*
X877735Y1409936D01*
G01X881335Y1407436D02*
Y1409936D01*
X879793Y1408144D01*
X881877D01*
G01X883935Y1407436D02*
X884227Y1407478D01*
X884560Y1407603D01*
X884768Y1407811D01*
X884852Y1408103D01*
X884768Y1408394D01*
X884518Y1408644D01*
X884143Y1408769D01*
X883727D01*
X883477Y1408853D01*
X883268Y1409061D01*
X883185Y1409353D01*
X883310Y1409644D01*
X883602Y1409853D01*
X883935Y1409936D01*
X884268Y1409853D01*
X884560Y1409644D01*
X884685Y1409353D01*
X884602Y1409061D01*
X884393Y1408853D01*
X884143Y1408769D01*
X883727D01*
X883352Y1408644D01*
X883102Y1408394D01*
X883018Y1408103D01*
X883102Y1407811D01*
X883310Y1407603D01*
X883643Y1407478D01*
X883935Y1407436D01*
G01X949038Y1414818D02*
Y1410818D01*
X956438D01*
G01X869667Y1425100D02*
Y1427600D01*
X870708D01*
X871042Y1427475D01*
X871250Y1427308D01*
X871333Y1426975D01*
X871250Y1426642D01*
X871000Y1426433D01*
X870708Y1426308D01*
X869667D01*
G01X870708D02*
X871333Y1425100D01*
G01X873600D02*
Y1427600D01*
X873100Y1427100D01*
G01Y1425100D02*
X874100D01*
G01X876700Y1427600D02*
X876367Y1427517D01*
X876117Y1427308D01*
X875950Y1427058D01*
X875825Y1426725D01*
X875783Y1426350D01*
X875825Y1425975D01*
X875950Y1425642D01*
X876117Y1425392D01*
X876367Y1425183D01*
X876700Y1425100D01*
X877033Y1425183D01*
X877283Y1425392D01*
X877450Y1425642D01*
X877575Y1425975D01*
X877617Y1426350D01*
X877575Y1426725D01*
X877450Y1427058D01*
X877283Y1427308D01*
X877033Y1427517D01*
X876700Y1427600D01*
G01X880300Y1425100D02*
Y1427600D01*
X878758Y1425808D01*
X880842D01*
G01X882192Y1425392D02*
X882483Y1425183D01*
X882817Y1425100D01*
X883150Y1425183D01*
X883442Y1425433D01*
X883650Y1425808D01*
X883733Y1426183D01*
Y1426642D01*
X883650Y1427017D01*
X883442Y1427350D01*
X883192Y1427517D01*
X882900Y1427600D01*
X882567Y1427517D01*
X882317Y1427350D01*
X882150Y1427100D01*
X882067Y1426767D01*
X882150Y1426475D01*
X882358Y1426183D01*
X882608Y1426017D01*
X882900Y1425975D01*
X883233Y1426058D01*
X883483Y1426267D01*
X883733Y1426642D01*
G01X949038Y1431318D02*
Y1427318D01*
X956438D01*
G01X894106Y1407227D02*
X891606D01*
Y1408268D01*
X891731Y1408602D01*
X891898Y1408810D01*
X892231Y1408893D01*
X892564Y1408810D01*
X892773Y1408560D01*
X892898Y1408268D01*
Y1407227D01*
G01Y1408268D02*
X894106Y1408893D01*
G01Y1411160D02*
X891606D01*
X892106Y1410660D01*
G01X894106D02*
Y1411660D01*
G01X891606Y1414260D02*
X891689Y1413927D01*
X891898Y1413677D01*
X892148Y1413510D01*
X892481Y1413385D01*
X892856Y1413343D01*
X893231Y1413385D01*
X893564Y1413510D01*
X893814Y1413677D01*
X894023Y1413927D01*
X894106Y1414260D01*
X894023Y1414593D01*
X893814Y1414843D01*
X893564Y1415010D01*
X893231Y1415135D01*
X892856Y1415177D01*
X892481Y1415135D01*
X892148Y1415010D01*
X891898Y1414843D01*
X891689Y1414593D01*
X891606Y1414260D01*
G01X893731Y1416443D02*
X893939Y1416693D01*
X894064Y1416985D01*
X894106Y1417360D01*
X894023Y1417735D01*
X893856Y1418027D01*
X893564Y1418235D01*
X893231Y1418277D01*
X892898Y1418193D01*
X892689Y1417985D01*
X892523Y1417693D01*
X892481Y1417402D01*
X892523Y1417110D01*
X892689Y1416735D01*
X891606Y1416860D01*
Y1417985D01*
G01Y1420460D02*
X891689Y1420127D01*
X891898Y1419877D01*
X892148Y1419710D01*
X892481Y1419585D01*
X892856Y1419543D01*
X893231Y1419585D01*
X893564Y1419710D01*
X893814Y1419877D01*
X894023Y1420127D01*
X894106Y1420460D01*
X894023Y1420793D01*
X893814Y1421043D01*
X893564Y1421210D01*
X893231Y1421335D01*
X892856Y1421377D01*
X892481Y1421335D01*
X892148Y1421210D01*
X891898Y1421043D01*
X891689Y1420793D01*
X891606Y1420460D01*
G01X894700Y1423967D02*
X892200D01*
Y1425008D01*
X892325Y1425342D01*
X892492Y1425550D01*
X892825Y1425633D01*
X893158Y1425550D01*
X893367Y1425300D01*
X893492Y1425008D01*
Y1423967D01*
G01Y1425008D02*
X894700Y1425633D01*
G01Y1427900D02*
X892200D01*
X892700Y1427400D01*
G01X894700D02*
Y1428400D01*
G01X892200Y1431000D02*
X892283Y1430667D01*
X892492Y1430417D01*
X892742Y1430250D01*
X893075Y1430125D01*
X893450Y1430083D01*
X893825Y1430125D01*
X894158Y1430250D01*
X894408Y1430417D01*
X894617Y1430667D01*
X894700Y1431000D01*
X894617Y1431333D01*
X894408Y1431583D01*
X894158Y1431750D01*
X893825Y1431875D01*
X893450Y1431917D01*
X893075Y1431875D01*
X892742Y1431750D01*
X892492Y1431583D01*
X892283Y1431333D01*
X892200Y1431000D01*
G01X894325Y1433183D02*
X894533Y1433433D01*
X894658Y1433725D01*
X894700Y1434100D01*
X894617Y1434475D01*
X894450Y1434767D01*
X894158Y1434975D01*
X893825Y1435017D01*
X893492Y1434933D01*
X893283Y1434725D01*
X893117Y1434433D01*
X893075Y1434142D01*
X893117Y1433850D01*
X893283Y1433475D01*
X892200Y1433600D01*
Y1434725D01*
G01X894700Y1437200D02*
X892200D01*
X892700Y1436700D01*
G01X894700D02*
Y1437700D01*
G01X914208Y1409467D02*
X914083Y1409217D01*
X914000Y1408925D01*
Y1408592D01*
X914125Y1408217D01*
X914333Y1407925D01*
X914583Y1407717D01*
X915000Y1407550D01*
X915375Y1407508D01*
X915750Y1407592D01*
X916000Y1407717D01*
X916250Y1407967D01*
X916417Y1408258D01*
X916500Y1408550D01*
Y1408842D01*
X916417Y1409133D01*
X916292Y1409383D01*
X916125Y1409592D01*
G01Y1410733D02*
X916333Y1410983D01*
X916458Y1411275D01*
X916500Y1411650D01*
X916417Y1412025D01*
X916250Y1412317D01*
X915958Y1412525D01*
X915625Y1412567D01*
X915292Y1412483D01*
X915083Y1412275D01*
X914917Y1411983D01*
X914875Y1411692D01*
X914917Y1411400D01*
X915083Y1411025D01*
X914000Y1411150D01*
Y1412275D01*
G01X915458Y1413958D02*
X915167Y1414250D01*
X915000Y1414500D01*
X914917Y1414833D01*
X915000Y1415125D01*
X915167Y1415333D01*
X915417Y1415500D01*
X915708Y1415542D01*
X915958Y1415500D01*
X916208Y1415333D01*
X916417Y1415083D01*
X916500Y1414792D01*
X916417Y1414458D01*
X916167Y1414167D01*
X915792Y1414000D01*
X915375Y1413958D01*
X914833Y1414042D01*
X914542Y1414167D01*
X914250Y1414375D01*
X914042Y1414667D01*
X914000Y1414958D01*
X914083Y1415250D01*
X914292Y1415458D01*
G01X914417Y1417058D02*
X914167Y1417308D01*
X914042Y1417600D01*
X914000Y1417933D01*
X914083Y1418350D01*
X914292Y1418642D01*
X914542Y1418725D01*
X914792Y1418683D01*
X915000Y1418517D01*
X915417Y1417683D01*
X915708Y1417308D01*
X916125Y1417058D01*
X916500Y1416975D01*
Y1418725D01*
G01X887814Y1408977D02*
X887689Y1408727D01*
X887606Y1408435D01*
Y1408102D01*
X887731Y1407727D01*
X887939Y1407435D01*
X888189Y1407227D01*
X888606Y1407060D01*
X888981Y1407018D01*
X889356Y1407102D01*
X889606Y1407227D01*
X889856Y1407477D01*
X890023Y1407768D01*
X890106Y1408060D01*
Y1408352D01*
X890023Y1408643D01*
X889898Y1408893D01*
X889731Y1409102D01*
G01Y1410243D02*
X889939Y1410493D01*
X890064Y1410785D01*
X890106Y1411160D01*
X890023Y1411535D01*
X889856Y1411827D01*
X889564Y1412035D01*
X889231Y1412077D01*
X888898Y1411993D01*
X888689Y1411785D01*
X888523Y1411493D01*
X888481Y1411202D01*
X888523Y1410910D01*
X888689Y1410535D01*
X887606Y1410660D01*
Y1411785D01*
G01X889064Y1413468D02*
X888773Y1413760D01*
X888606Y1414010D01*
X888523Y1414343D01*
X888606Y1414635D01*
X888773Y1414843D01*
X889023Y1415010D01*
X889314Y1415052D01*
X889564Y1415010D01*
X889814Y1414843D01*
X890023Y1414593D01*
X890106Y1414302D01*
X890023Y1413968D01*
X889773Y1413677D01*
X889398Y1413510D01*
X888981Y1413468D01*
X888439Y1413552D01*
X888148Y1413677D01*
X887856Y1413885D01*
X887648Y1414177D01*
X887606Y1414468D01*
X887689Y1414760D01*
X887898Y1414968D01*
G01X890106Y1417860D02*
X887606D01*
X889398Y1416318D01*
Y1418402D01*
G01X887808Y1425567D02*
X887683Y1425317D01*
X887600Y1425025D01*
Y1424692D01*
X887725Y1424317D01*
X887933Y1424025D01*
X888183Y1423817D01*
X888600Y1423650D01*
X888975Y1423608D01*
X889350Y1423692D01*
X889600Y1423817D01*
X889850Y1424067D01*
X890017Y1424358D01*
X890100Y1424650D01*
Y1424942D01*
X890017Y1425233D01*
X889892Y1425483D01*
X889725Y1425692D01*
G01Y1426833D02*
X889933Y1427083D01*
X890058Y1427375D01*
X890100Y1427750D01*
X890017Y1428125D01*
X889850Y1428417D01*
X889558Y1428625D01*
X889225Y1428667D01*
X888892Y1428583D01*
X888683Y1428375D01*
X888517Y1428083D01*
X888475Y1427792D01*
X888517Y1427500D01*
X888683Y1427125D01*
X887600Y1427250D01*
Y1428375D01*
G01X889058Y1430058D02*
X888767Y1430350D01*
X888600Y1430600D01*
X888517Y1430933D01*
X888600Y1431225D01*
X888767Y1431433D01*
X889017Y1431600D01*
X889308Y1431642D01*
X889558Y1431600D01*
X889808Y1431433D01*
X890017Y1431183D01*
X890100Y1430892D01*
X890017Y1430558D01*
X889767Y1430267D01*
X889392Y1430100D01*
X888975Y1430058D01*
X888433Y1430142D01*
X888142Y1430267D01*
X887850Y1430475D01*
X887642Y1430767D01*
X887600Y1431058D01*
X887683Y1431350D01*
X887892Y1431558D01*
G01X889725Y1433033D02*
X889933Y1433283D01*
X890058Y1433575D01*
X890100Y1433950D01*
X890017Y1434325D01*
X889850Y1434617D01*
X889558Y1434825D01*
X889225Y1434867D01*
X888892Y1434783D01*
X888683Y1434575D01*
X888517Y1434283D01*
X888475Y1433992D01*
X888517Y1433700D01*
X888683Y1433325D01*
X887600Y1433450D01*
Y1434575D01*
G01X876918Y1364386D02*
X876793Y1364136D01*
X876710Y1363844D01*
Y1363511D01*
X876835Y1363136D01*
X877043Y1362844D01*
X877293Y1362636D01*
X877710Y1362469D01*
X878085Y1362427D01*
X878460Y1362511D01*
X878710Y1362636D01*
X878960Y1362886D01*
X879127Y1363177D01*
X879210Y1363469D01*
Y1363761D01*
X879127Y1364052D01*
X879002Y1364302D01*
X878835Y1364511D01*
G01Y1365652D02*
X879043Y1365902D01*
X879168Y1366194D01*
X879210Y1366569D01*
X879127Y1366944D01*
X878960Y1367236D01*
X878668Y1367444D01*
X878335Y1367486D01*
X878002Y1367402D01*
X877793Y1367194D01*
X877627Y1366902D01*
X877585Y1366611D01*
X877627Y1366319D01*
X877793Y1365944D01*
X876710Y1366069D01*
Y1367194D01*
G01X879210Y1369669D02*
X876710D01*
X877210Y1369169D01*
G01X879210D02*
Y1370169D01*
G01Y1372686D02*
X878668Y1372769D01*
X878210Y1372894D01*
X877793Y1373061D01*
X877335Y1373269D01*
X876710Y1373602D01*
Y1371936D01*
G01X906585Y1400219D02*
Y1381519D01*
X896285D01*
Y1400219D01*
X906585D01*
G01X881120Y1364386D02*
X880995Y1364136D01*
X880912Y1363844D01*
Y1363511D01*
X881037Y1363136D01*
X881245Y1362844D01*
X881495Y1362636D01*
X881912Y1362469D01*
X882287Y1362427D01*
X882662Y1362511D01*
X882912Y1362636D01*
X883162Y1362886D01*
X883329Y1363177D01*
X883412Y1363469D01*
Y1363761D01*
X883329Y1364052D01*
X883204Y1364302D01*
X883037Y1364511D01*
G01Y1365652D02*
X883245Y1365902D01*
X883370Y1366194D01*
X883412Y1366569D01*
X883329Y1366944D01*
X883162Y1367236D01*
X882870Y1367444D01*
X882537Y1367486D01*
X882204Y1367402D01*
X881995Y1367194D01*
X881829Y1366902D01*
X881787Y1366611D01*
X881829Y1366319D01*
X881995Y1365944D01*
X880912Y1366069D01*
Y1367194D01*
G01X883412Y1369669D02*
X880912D01*
X881412Y1369169D01*
G01X883412D02*
Y1370169D01*
G01Y1372769D02*
X883370Y1373061D01*
X883245Y1373394D01*
X883037Y1373602D01*
X882745Y1373686D01*
X882454Y1373602D01*
X882204Y1373352D01*
X882079Y1372977D01*
Y1372561D01*
X881995Y1372311D01*
X881787Y1372102D01*
X881495Y1372019D01*
X881204Y1372144D01*
X880995Y1372436D01*
X880912Y1372769D01*
X880995Y1373102D01*
X881204Y1373394D01*
X881495Y1373519D01*
X881787Y1373436D01*
X881995Y1373227D01*
X882079Y1372977D01*
Y1372561D01*
X882204Y1372186D01*
X882454Y1371936D01*
X882745Y1371852D01*
X883037Y1371936D01*
X883245Y1372144D01*
X883370Y1372477D01*
X883412Y1372769D01*
G01X919085Y1400219D02*
Y1381519D01*
X908785D01*
Y1400219D01*
X919085D01*
G01X872624Y1364386D02*
X872499Y1364136D01*
X872416Y1363844D01*
Y1363511D01*
X872541Y1363136D01*
X872749Y1362844D01*
X872999Y1362636D01*
X873416Y1362469D01*
X873791Y1362427D01*
X874166Y1362511D01*
X874416Y1362636D01*
X874666Y1362886D01*
X874833Y1363177D01*
X874916Y1363469D01*
Y1363761D01*
X874833Y1364052D01*
X874708Y1364302D01*
X874541Y1364511D01*
G01Y1365652D02*
X874749Y1365902D01*
X874874Y1366194D01*
X874916Y1366569D01*
X874833Y1366944D01*
X874666Y1367236D01*
X874374Y1367444D01*
X874041Y1367486D01*
X873708Y1367402D01*
X873499Y1367194D01*
X873333Y1366902D01*
X873291Y1366611D01*
X873333Y1366319D01*
X873499Y1365944D01*
X872416Y1366069D01*
Y1367194D01*
G01X874916Y1369669D02*
X872416D01*
X872916Y1369169D01*
G01X874916D02*
Y1370169D01*
G01Y1373269D02*
X872416D01*
X874208Y1371727D01*
Y1373811D01*
G01X893926Y1400251D02*
Y1381551D01*
X883626D01*
Y1400251D01*
X893926D01*
G01X960750Y1401400D02*
Y1405400D01*
X953350D01*
G01X960750Y1397400D02*
Y1401400D01*
X953350D01*
G01X929983Y1402600D02*
Y1405100D01*
X930817D01*
X931150Y1404975D01*
X931400Y1404808D01*
X931608Y1404558D01*
X931775Y1404267D01*
X931817Y1403850D01*
X931775Y1403433D01*
X931608Y1403142D01*
X931400Y1402892D01*
X931150Y1402725D01*
X930817Y1402600D01*
X929983D01*
G01X934500D02*
Y1405100D01*
X932958Y1403308D01*
X935042D01*
G01X936308Y1403642D02*
X936600Y1403933D01*
X936850Y1404100D01*
X937183Y1404183D01*
X937475Y1404100D01*
X937683Y1403933D01*
X937850Y1403683D01*
X937892Y1403392D01*
X937850Y1403142D01*
X937683Y1402892D01*
X937433Y1402683D01*
X937142Y1402600D01*
X936808Y1402683D01*
X936517Y1402933D01*
X936350Y1403308D01*
X936308Y1403725D01*
X936392Y1404267D01*
X936517Y1404558D01*
X936725Y1404850D01*
X937017Y1405058D01*
X937308Y1405100D01*
X937600Y1405017D01*
X937808Y1404808D01*
G01X921900Y1362950D02*
X947100D01*
Y1401250D01*
X921900D01*
Y1362950D01*
G01X955967Y1464292D02*
X955717Y1464417D01*
X955425Y1464500D01*
X955092D01*
X954717Y1464375D01*
X954425Y1464167D01*
X954217Y1463917D01*
X954050Y1463500D01*
X954008Y1463125D01*
X954092Y1462750D01*
X954217Y1462500D01*
X954467Y1462250D01*
X954758Y1462083D01*
X955050Y1462000D01*
X955342D01*
X955633Y1462083D01*
X955883Y1462208D01*
X956092Y1462375D01*
G01X957233D02*
X957483Y1462167D01*
X957775Y1462042D01*
X958150Y1462000D01*
X958525Y1462083D01*
X958817Y1462250D01*
X959025Y1462542D01*
X959067Y1462875D01*
X958983Y1463208D01*
X958775Y1463417D01*
X958483Y1463583D01*
X958192Y1463625D01*
X957900Y1463583D01*
X957525Y1463417D01*
X957650Y1464500D01*
X958775D01*
G01X960333Y1462375D02*
X960583Y1462167D01*
X960875Y1462042D01*
X961250Y1462000D01*
X961625Y1462083D01*
X961917Y1462250D01*
X962125Y1462542D01*
X962167Y1462875D01*
X962083Y1463208D01*
X961875Y1463417D01*
X961583Y1463583D01*
X961292Y1463625D01*
X961000Y1463583D01*
X960625Y1463417D01*
X960750Y1464500D01*
X961875D01*
G01X963433Y1462375D02*
X963683Y1462167D01*
X963975Y1462042D01*
X964350Y1462000D01*
X964725Y1462083D01*
X965017Y1462250D01*
X965225Y1462542D01*
X965267Y1462875D01*
X965183Y1463208D01*
X964975Y1463417D01*
X964683Y1463583D01*
X964392Y1463625D01*
X964100Y1463583D01*
X963725Y1463417D01*
X963850Y1464500D01*
X964975D01*
G01X939130Y1453883D02*
X939088Y1453550D01*
X938922Y1453258D01*
X938672Y1453008D01*
X938380Y1452841D01*
X938047Y1452758D01*
X937713D01*
X937380Y1452841D01*
X937088Y1453008D01*
X936838Y1453258D01*
X936672Y1453550D01*
X936630Y1453883D01*
X936672Y1454216D01*
X936838Y1454508D01*
X937088Y1454758D01*
X937380Y1454925D01*
X937713Y1455008D01*
X938047D01*
X938380Y1454925D01*
X938672Y1454758D01*
X938922Y1454508D01*
X939088Y1454216D01*
X939130Y1453883D01*
G01X938463Y1454216D02*
X939130Y1454716D01*
G01X937047Y1456191D02*
X936797Y1456441D01*
X936672Y1456733D01*
X936630Y1457066D01*
X936713Y1457483D01*
X936922Y1457775D01*
X937172Y1457858D01*
X937422Y1457816D01*
X937630Y1457650D01*
X938047Y1456816D01*
X938338Y1456441D01*
X938755Y1456191D01*
X939130Y1456108D01*
Y1457858D01*
G01X936630Y1460083D02*
X936713Y1459750D01*
X936922Y1459500D01*
X937172Y1459333D01*
X937505Y1459208D01*
X937880Y1459166D01*
X938255Y1459208D01*
X938588Y1459333D01*
X938838Y1459500D01*
X939047Y1459750D01*
X939130Y1460083D01*
X939047Y1460416D01*
X938838Y1460666D01*
X938588Y1460833D01*
X938255Y1460958D01*
X937880Y1461000D01*
X937505Y1460958D01*
X937172Y1460833D01*
X936922Y1460666D01*
X936713Y1460416D01*
X936630Y1460083D01*
G01Y1463183D02*
X936713Y1462850D01*
X936922Y1462600D01*
X937172Y1462433D01*
X937505Y1462308D01*
X937880Y1462266D01*
X938255Y1462308D01*
X938588Y1462433D01*
X938838Y1462600D01*
X939047Y1462850D01*
X939130Y1463183D01*
X939047Y1463516D01*
X938838Y1463766D01*
X938588Y1463933D01*
X938255Y1464058D01*
X937880Y1464100D01*
X937505Y1464058D01*
X937172Y1463933D01*
X936922Y1463766D01*
X936713Y1463516D01*
X936630Y1463183D01*
G01X960516Y1455772D02*
X946516D01*
G01Y1442772D02*
X960516D01*
G01X946516Y1455772D02*
Y1442772D01*
G01X954368Y1458099D02*
Y1460599D01*
X955409D01*
X955743Y1460474D01*
X955951Y1460307D01*
X956034Y1459974D01*
X955951Y1459641D01*
X955701Y1459432D01*
X955409Y1459307D01*
X954368D01*
G01X955409D02*
X956034Y1458099D01*
G01X958301D02*
Y1460599D01*
X957801Y1460099D01*
G01Y1458099D02*
X958801D01*
G01X961401Y1460599D02*
X961068Y1460516D01*
X960818Y1460307D01*
X960651Y1460057D01*
X960526Y1459724D01*
X960484Y1459349D01*
X960526Y1458974D01*
X960651Y1458641D01*
X960818Y1458391D01*
X961068Y1458182D01*
X961401Y1458099D01*
X961734Y1458182D01*
X961984Y1458391D01*
X962151Y1458641D01*
X962276Y1458974D01*
X962318Y1459349D01*
X962276Y1459724D01*
X962151Y1460057D01*
X961984Y1460307D01*
X961734Y1460516D01*
X961401Y1460599D01*
G01X963709Y1460182D02*
X963959Y1460432D01*
X964251Y1460557D01*
X964584Y1460599D01*
X965001Y1460516D01*
X965293Y1460307D01*
X965376Y1460057D01*
X965334Y1459807D01*
X965168Y1459599D01*
X964334Y1459182D01*
X963959Y1458891D01*
X963709Y1458474D01*
X963626Y1458099D01*
X965376D01*
G01X966809Y1459141D02*
X967101Y1459432D01*
X967351Y1459599D01*
X967684Y1459682D01*
X967976Y1459599D01*
X968184Y1459432D01*
X968351Y1459182D01*
X968393Y1458891D01*
X968351Y1458641D01*
X968184Y1458391D01*
X967934Y1458182D01*
X967643Y1458099D01*
X967309Y1458182D01*
X967018Y1458432D01*
X966851Y1458807D01*
X966809Y1459224D01*
X966893Y1459766D01*
X967018Y1460057D01*
X967226Y1460349D01*
X967518Y1460557D01*
X967809Y1460599D01*
X968101Y1460516D01*
X968309Y1460307D01*
G01X935130Y1453050D02*
X932630D01*
Y1454091D01*
X932755Y1454425D01*
X932922Y1454633D01*
X933255Y1454716D01*
X933588Y1454633D01*
X933797Y1454383D01*
X933922Y1454091D01*
Y1453050D01*
G01Y1454091D02*
X935130Y1454716D01*
G01Y1456983D02*
X932630D01*
X933130Y1456483D01*
G01X935130D02*
Y1457483D01*
G01X932630Y1460083D02*
X932713Y1459750D01*
X932922Y1459500D01*
X933172Y1459333D01*
X933505Y1459208D01*
X933880Y1459166D01*
X934255Y1459208D01*
X934588Y1459333D01*
X934838Y1459500D01*
X935047Y1459750D01*
X935130Y1460083D01*
X935047Y1460416D01*
X934838Y1460666D01*
X934588Y1460833D01*
X934255Y1460958D01*
X933880Y1461000D01*
X933505Y1460958D01*
X933172Y1460833D01*
X932922Y1460666D01*
X932713Y1460416D01*
X932630Y1460083D01*
G01X933047Y1462391D02*
X932797Y1462641D01*
X932672Y1462933D01*
X932630Y1463266D01*
X932713Y1463683D01*
X932922Y1463975D01*
X933172Y1464058D01*
X933422Y1464016D01*
X933630Y1463850D01*
X934047Y1463016D01*
X934338Y1462641D01*
X934755Y1462391D01*
X935130Y1462308D01*
Y1464058D01*
G01X934755Y1465366D02*
X934963Y1465616D01*
X935088Y1465908D01*
X935130Y1466283D01*
X935047Y1466658D01*
X934880Y1466950D01*
X934588Y1467158D01*
X934255Y1467200D01*
X933922Y1467116D01*
X933713Y1466908D01*
X933547Y1466616D01*
X933505Y1466325D01*
X933547Y1466033D01*
X933713Y1465658D01*
X932630Y1465783D01*
Y1466908D01*
G01X946016Y1450972D02*
X942016D01*
Y1443572D01*
G01X953268Y1470099D02*
Y1472599D01*
X954309D01*
X954643Y1472474D01*
X954851Y1472307D01*
X954934Y1471974D01*
X954851Y1471641D01*
X954601Y1471432D01*
X954309Y1471307D01*
X953268D01*
G01X954309D02*
X954934Y1470099D01*
G01X957201D02*
Y1472599D01*
X956701Y1472099D01*
G01Y1470099D02*
X957701D01*
G01X960301D02*
Y1472599D01*
X959801Y1472099D01*
G01Y1470099D02*
X960801D01*
G01X963401D02*
Y1472599D01*
X962901Y1472099D01*
G01Y1470099D02*
X963901D01*
G01X966501D02*
Y1472599D01*
X966001Y1472099D01*
G01Y1470099D02*
X967001D01*
G01X953268Y1466099D02*
Y1468599D01*
X954309D01*
X954643Y1468474D01*
X954851Y1468307D01*
X954934Y1467974D01*
X954851Y1467641D01*
X954601Y1467432D01*
X954309Y1467307D01*
X953268D01*
G01X954309D02*
X954934Y1466099D01*
G01X957201D02*
Y1468599D01*
X956701Y1468099D01*
G01Y1466099D02*
X957701D01*
G01X960301Y1468599D02*
X959968Y1468516D01*
X959718Y1468307D01*
X959551Y1468057D01*
X959426Y1467724D01*
X959384Y1467349D01*
X959426Y1466974D01*
X959551Y1466641D01*
X959718Y1466391D01*
X959968Y1466182D01*
X960301Y1466099D01*
X960634Y1466182D01*
X960884Y1466391D01*
X961051Y1466641D01*
X961176Y1466974D01*
X961218Y1467349D01*
X961176Y1467724D01*
X961051Y1468057D01*
X960884Y1468307D01*
X960634Y1468516D01*
X960301Y1468599D01*
G01X962609Y1467141D02*
X962901Y1467432D01*
X963151Y1467599D01*
X963484Y1467682D01*
X963776Y1467599D01*
X963984Y1467432D01*
X964151Y1467182D01*
X964193Y1466891D01*
X964151Y1466641D01*
X963984Y1466391D01*
X963734Y1466182D01*
X963443Y1466099D01*
X963109Y1466182D01*
X962818Y1466432D01*
X962651Y1466807D01*
X962609Y1467224D01*
X962693Y1467766D01*
X962818Y1468057D01*
X963026Y1468349D01*
X963318Y1468557D01*
X963609Y1468599D01*
X963901Y1468516D01*
X964109Y1468307D01*
G01X966501Y1466099D02*
Y1468599D01*
X966001Y1468099D01*
G01Y1466099D02*
X967001D01*
G01X1044532Y1757D02*
X1044932Y1424D01*
X1045399Y1224D01*
X1045999Y1157D01*
X1046599Y1290D01*
X1047066Y1557D01*
X1047399Y2024D01*
X1047466Y2557D01*
X1047332Y3090D01*
X1046999Y3424D01*
X1046532Y3690D01*
X1046066Y3757D01*
X1045599Y3690D01*
X1044999Y3424D01*
X1045199Y5157D01*
X1046999D01*
G01X1015303Y1157D02*
Y5157D01*
X1012836Y2290D01*
X1016170D01*
G01X981541Y1957D02*
X981941Y1490D01*
X982475Y1224D01*
X983075Y1157D01*
X983608Y1224D01*
X984141Y1557D01*
X984475Y1957D01*
X984541Y2357D01*
X984408Y2824D01*
X983941Y3157D01*
X983475Y3290D01*
X982875D01*
G01X983475D02*
X983875Y3490D01*
X984208Y3824D01*
X984341Y4224D01*
X984208Y4624D01*
X983875Y4957D01*
X983275Y5157D01*
X982675Y5090D01*
X982075Y4824D01*
G01X1020207Y239873D02*
X1019674Y240206D01*
X1019074Y240406D01*
X1018540D01*
X1018007Y240206D01*
X1017607Y239873D01*
X1017407Y239406D01*
X1017540Y238939D01*
X1017874Y238539D01*
X1018474Y238273D01*
X1019274Y238139D01*
X1019740Y237873D01*
X1019940Y237406D01*
X1019807Y236939D01*
X1019474Y236606D01*
X1019007Y236406D01*
X1018540D01*
X1018074Y236539D01*
X1017674Y236873D01*
G01X1014207Y240406D02*
Y236406D01*
G01X1009607Y237739D02*
Y240406D01*
G01Y236673D02*
X1009740Y236606D01*
Y236473D01*
X1009607Y236406D01*
X1009474Y236473D01*
Y236606D01*
X1009607Y236673D01*
G01X1005007Y236406D02*
Y240406D01*
G01X1005940Y237739D02*
X1004074D01*
G01X1051907Y325006D02*
Y248032D01*
X964907D01*
Y325006D01*
X1051907D01*
G01X1028140Y322906D02*
Y318906D01*
X1026540D01*
X1026007Y319106D01*
X1025607Y319573D01*
X1025474Y320106D01*
X1025607Y320639D01*
X1025940Y321039D01*
X1026540Y321239D01*
X1028140D01*
G01X1023140Y322906D02*
Y320239D01*
G01Y320773D02*
X1022807Y320506D01*
X1022474Y320306D01*
X1022007Y320239D01*
X1021674Y320306D01*
X1021274Y320506D01*
G01X1018607Y321106D02*
X1016474D01*
X1016674Y320639D01*
X1017007Y320373D01*
X1017474Y320239D01*
X1017940Y320306D01*
X1018340Y320506D01*
X1018607Y320973D01*
X1018740Y321373D01*
Y321773D01*
X1018607Y322173D01*
X1018274Y322573D01*
X1017874Y322839D01*
X1017407Y322906D01*
X1016940Y322773D01*
X1016474Y322373D01*
G01X1014007Y322439D02*
X1013674Y322706D01*
X1013207Y322906D01*
X1012807D01*
X1012407Y322773D01*
X1012140Y322573D01*
X1012007Y322306D01*
X1012074Y321906D01*
X1012340Y321706D01*
X1013540Y321306D01*
X1013807Y320839D01*
X1013674Y320506D01*
X1013407Y320306D01*
X1013007Y320239D01*
X1012607Y320306D01*
X1012207Y320506D01*
G01X1009407Y322439D02*
X1009074Y322706D01*
X1008607Y322906D01*
X1008207D01*
X1007807Y322773D01*
X1007540Y322573D01*
X1007407Y322306D01*
X1007474Y321906D01*
X1007740Y321706D01*
X1008940Y321306D01*
X1009207Y320839D01*
X1009074Y320506D01*
X1008807Y320306D01*
X1008407Y320239D01*
X1008007Y320306D01*
X1007607Y320506D01*
G01X1000474Y322906D02*
Y318906D01*
X997940D01*
G01X998874Y320839D02*
X1000474D01*
G01X994607Y320239D02*
Y322906D01*
G01Y319173D02*
X994740Y319106D01*
Y318973D01*
X994607Y318906D01*
X994474Y318973D01*
Y319106D01*
X994607Y319173D01*
G01X990007Y318906D02*
Y322906D01*
G01X990940Y320239D02*
X989074D01*
G01X997093Y365674D02*
Y368174D01*
X997927D01*
X998260Y368049D01*
X998510Y367882D01*
X998718Y367632D01*
X998885Y367341D01*
X998927Y366924D01*
X998885Y366507D01*
X998718Y366216D01*
X998510Y365966D01*
X998260Y365799D01*
X997927Y365674D01*
X997093D01*
G01X1000277D02*
Y368174D01*
X1001277D01*
X1001610Y368049D01*
X1001860Y367757D01*
X1001943Y367424D01*
X1001860Y367091D01*
X1001652Y366841D01*
X1001277Y366716D01*
X1000277D01*
G01X1004543Y367007D02*
X1004710Y367132D01*
X1004835Y367341D01*
X1004918Y367632D01*
X1004835Y367882D01*
X1004668Y368049D01*
X1004377Y368174D01*
X1003252D01*
Y365674D01*
X1004627D01*
X1004918Y365841D01*
X1005085Y366091D01*
X1005168Y366382D01*
X1005085Y366674D01*
X1004835Y366924D01*
X1004543Y367007D01*
X1003252D01*
G01X1006518Y367757D02*
X1006768Y368007D01*
X1007060Y368132D01*
X1007393Y368174D01*
X1007810Y368091D01*
X1008102Y367882D01*
X1008185Y367632D01*
X1008143Y367382D01*
X1007977Y367174D01*
X1007143Y366757D01*
X1006768Y366466D01*
X1006518Y366049D01*
X1006435Y365674D01*
X1008185D01*
G01X1028973Y383184D02*
Y364484D01*
X1018673D01*
Y383184D01*
X1028973D01*
G01X1035347Y370090D02*
Y388090D01*
G01X1046547Y370090D02*
X1035347D01*
G01X1020426Y387528D02*
X1020176Y387653D01*
X1019884Y387736D01*
X1019551D01*
X1019176Y387611D01*
X1018884Y387403D01*
X1018676Y387153D01*
X1018509Y386736D01*
X1018467Y386361D01*
X1018551Y385986D01*
X1018676Y385736D01*
X1018926Y385486D01*
X1019217Y385319D01*
X1019509Y385236D01*
X1019801D01*
X1020092Y385319D01*
X1020342Y385444D01*
X1020551Y385611D01*
G01X1021817Y387319D02*
X1022067Y387569D01*
X1022359Y387694D01*
X1022692Y387736D01*
X1023109Y387653D01*
X1023401Y387444D01*
X1023484Y387194D01*
X1023442Y386944D01*
X1023276Y386736D01*
X1022442Y386319D01*
X1022067Y386028D01*
X1021817Y385611D01*
X1021734Y385236D01*
X1023484D01*
G01X1050350Y398000D02*
Y395500D01*
G01X1049392Y398000D02*
X1051308D01*
G01X1054367Y397792D02*
X1054117Y397917D01*
X1053825Y398000D01*
X1053492D01*
X1053117Y397875D01*
X1052825Y397667D01*
X1052617Y397417D01*
X1052450Y397000D01*
X1052408Y396625D01*
X1052492Y396250D01*
X1052617Y396000D01*
X1052867Y395750D01*
X1053158Y395583D01*
X1053450Y395500D01*
X1053742D01*
X1054033Y395583D01*
X1054283Y395708D01*
X1054492Y395875D01*
G01X1056550Y395500D02*
Y398000D01*
X1056050Y397500D01*
G01Y395500D02*
X1057050D01*
G01X1058733Y395875D02*
X1058983Y395667D01*
X1059275Y395542D01*
X1059650Y395500D01*
X1060025Y395583D01*
X1060317Y395750D01*
X1060525Y396042D01*
X1060567Y396375D01*
X1060483Y396708D01*
X1060275Y396917D01*
X1059983Y397083D01*
X1059692Y397125D01*
X1059400Y397083D01*
X1059025Y396917D01*
X1059150Y398000D01*
X1060275D01*
G01X1035347Y388090D02*
X1046547D01*
G01X978698Y570124D02*
X978448Y570249D01*
X978156Y570332D01*
X977823D01*
X977448Y570207D01*
X977156Y569999D01*
X976948Y569749D01*
X976781Y569332D01*
X976739Y568957D01*
X976823Y568582D01*
X976948Y568332D01*
X977198Y568082D01*
X977489Y567915D01*
X977781Y567832D01*
X978073D01*
X978364Y567915D01*
X978614Y568040D01*
X978823Y568207D01*
G01X980798Y567832D02*
X980881Y568374D01*
X981006Y568832D01*
X981173Y569249D01*
X981381Y569707D01*
X981714Y570332D01*
X980048D01*
G01X983189Y569915D02*
X983439Y570165D01*
X983731Y570290D01*
X984064Y570332D01*
X984481Y570249D01*
X984773Y570040D01*
X984856Y569790D01*
X984814Y569540D01*
X984648Y569332D01*
X983814Y568915D01*
X983439Y568624D01*
X983189Y568207D01*
X983106Y567832D01*
X984856D01*
G01X974917Y540892D02*
X974667Y541017D01*
X974375Y541100D01*
X974042D01*
X973667Y540975D01*
X973375Y540767D01*
X973167Y540517D01*
X973000Y540100D01*
X972958Y539725D01*
X973042Y539350D01*
X973167Y539100D01*
X973417Y538850D01*
X973708Y538683D01*
X974000Y538600D01*
X974292D01*
X974583Y538683D01*
X974833Y538808D01*
X975042Y538975D01*
G01X976183D02*
X976433Y538767D01*
X976725Y538642D01*
X977100Y538600D01*
X977475Y538683D01*
X977767Y538850D01*
X977975Y539142D01*
X978017Y539475D01*
X977933Y539808D01*
X977725Y540017D01*
X977433Y540183D01*
X977142Y540225D01*
X976850Y540183D01*
X976475Y540017D01*
X976600Y541100D01*
X977725D01*
G01X980200Y538600D02*
X980492Y538642D01*
X980825Y538767D01*
X981033Y538975D01*
X981117Y539267D01*
X981033Y539558D01*
X980783Y539808D01*
X980408Y539933D01*
X979992D01*
X979742Y540017D01*
X979533Y540225D01*
X979450Y540517D01*
X979575Y540808D01*
X979867Y541017D01*
X980200Y541100D01*
X980533Y541017D01*
X980825Y540808D01*
X980950Y540517D01*
X980867Y540225D01*
X980658Y540017D01*
X980408Y539933D01*
X979992D01*
X979617Y539808D01*
X979367Y539558D01*
X979283Y539267D01*
X979367Y538975D01*
X979575Y538767D01*
X979908Y538642D01*
X980200Y538600D01*
G01X999625Y537971D02*
Y540471D01*
X1000666D01*
X1001000Y540346D01*
X1001208Y540179D01*
X1001291Y539846D01*
X1001208Y539513D01*
X1000958Y539304D01*
X1000666Y539179D01*
X999625D01*
G01X1000666D02*
X1001291Y537971D01*
G01X1004058D02*
Y540471D01*
X1002516Y538679D01*
X1004600D01*
G01X1007158Y537971D02*
Y540471D01*
X1005616Y538679D01*
X1007700D01*
G01X1009758Y537971D02*
Y540471D01*
X1009258Y539971D01*
G01Y537971D02*
X1010258D01*
G01X994948Y537555D02*
Y541555D01*
X987548D01*
G01X1006317Y515800D02*
Y518300D01*
X1007358D01*
X1007692Y518175D01*
X1007900Y518008D01*
X1007983Y517675D01*
X1007900Y517342D01*
X1007650Y517133D01*
X1007358Y517008D01*
X1006317D01*
G01X1007358D02*
X1007983Y515800D01*
G01X1010750D02*
Y518300D01*
X1009208Y516508D01*
X1011292D01*
G01X1013350Y518300D02*
X1013017Y518217D01*
X1012767Y518008D01*
X1012600Y517758D01*
X1012475Y517425D01*
X1012433Y517050D01*
X1012475Y516675D01*
X1012600Y516342D01*
X1012767Y516092D01*
X1013017Y515883D01*
X1013350Y515800D01*
X1013683Y515883D01*
X1013933Y516092D01*
X1014100Y516342D01*
X1014225Y516675D01*
X1014267Y517050D01*
X1014225Y517425D01*
X1014100Y517758D01*
X1013933Y518008D01*
X1013683Y518217D01*
X1013350Y518300D01*
G01X1016450Y515800D02*
Y518300D01*
X1015950Y517800D01*
G01Y515800D02*
X1016950D01*
G01X997138Y515437D02*
Y519437D01*
X989738D01*
G01X1009217Y552500D02*
Y555000D01*
X1010258D01*
X1010592Y554875D01*
X1010800Y554708D01*
X1010883Y554375D01*
X1010800Y554042D01*
X1010550Y553833D01*
X1010258Y553708D01*
X1009217D01*
G01X1010258D02*
X1010883Y552500D01*
G01X1013650D02*
Y555000D01*
X1012108Y553208D01*
X1014192D01*
G01X1016750Y552500D02*
Y555000D01*
X1015208Y553208D01*
X1017292D01*
G01X1019267Y552500D02*
X1019350Y553042D01*
X1019475Y553500D01*
X1019642Y553917D01*
X1019850Y554375D01*
X1020183Y555000D01*
X1018517D01*
G01X1001541Y550081D02*
Y554081D01*
X994141D01*
G01X1005817Y525300D02*
Y527800D01*
X1006858D01*
X1007192Y527675D01*
X1007400Y527508D01*
X1007483Y527175D01*
X1007400Y526842D01*
X1007150Y526633D01*
X1006858Y526508D01*
X1005817D01*
G01X1006858D02*
X1007483Y525300D01*
G01X1010250D02*
Y527800D01*
X1008708Y526008D01*
X1010792D01*
G01X1012850Y525300D02*
Y527800D01*
X1012350Y527300D01*
G01Y525300D02*
X1013350D01*
G01X1015950D02*
X1016242Y525342D01*
X1016575Y525467D01*
X1016783Y525675D01*
X1016867Y525967D01*
X1016783Y526258D01*
X1016533Y526508D01*
X1016158Y526633D01*
X1015742D01*
X1015492Y526717D01*
X1015283Y526925D01*
X1015200Y527217D01*
X1015325Y527508D01*
X1015617Y527717D01*
X1015950Y527800D01*
X1016283Y527717D01*
X1016575Y527508D01*
X1016700Y527217D01*
X1016617Y526925D01*
X1016408Y526717D01*
X1016158Y526633D01*
X1015742D01*
X1015367Y526508D01*
X1015117Y526258D01*
X1015033Y525967D01*
X1015117Y525675D01*
X1015325Y525467D01*
X1015658Y525342D01*
X1015950Y525300D01*
G01X997163Y524457D02*
Y528457D01*
X989763D01*
G01X1009017Y548800D02*
Y551300D01*
X1010058D01*
X1010392Y551175D01*
X1010600Y551008D01*
X1010683Y550675D01*
X1010600Y550342D01*
X1010350Y550133D01*
X1010058Y550008D01*
X1009017D01*
G01X1010058D02*
X1010683Y548800D01*
G01X1013450D02*
Y551300D01*
X1011908Y549508D01*
X1013992D01*
G01X1015258Y549842D02*
X1015550Y550133D01*
X1015800Y550300D01*
X1016133Y550383D01*
X1016425Y550300D01*
X1016633Y550133D01*
X1016800Y549883D01*
X1016842Y549592D01*
X1016800Y549342D01*
X1016633Y549092D01*
X1016383Y548883D01*
X1016092Y548800D01*
X1015758Y548883D01*
X1015467Y549133D01*
X1015300Y549508D01*
X1015258Y549925D01*
X1015342Y550467D01*
X1015467Y550758D01*
X1015675Y551050D01*
X1015967Y551258D01*
X1016258Y551300D01*
X1016550Y551217D01*
X1016758Y551008D01*
G01X1019650Y548800D02*
Y551300D01*
X1018108Y549508D01*
X1020192D01*
G01X993129Y553101D02*
X989129D01*
Y545701D01*
G01X1003100Y516317D02*
X1000600D01*
Y517358D01*
X1000725Y517692D01*
X1000892Y517900D01*
X1001225Y517983D01*
X1001558Y517900D01*
X1001767Y517650D01*
X1001892Y517358D01*
Y516317D01*
G01Y517358D02*
X1003100Y517983D01*
G01Y520750D02*
X1000600D01*
X1002392Y519208D01*
Y521292D01*
G01X1001017Y522558D02*
X1000767Y522808D01*
X1000642Y523100D01*
X1000600Y523433D01*
X1000683Y523850D01*
X1000892Y524142D01*
X1001142Y524225D01*
X1001392Y524183D01*
X1001600Y524017D01*
X1002017Y523183D01*
X1002308Y522808D01*
X1002725Y522558D01*
X1003100Y522475D01*
Y524225D01*
G01Y526950D02*
X1000600D01*
X1002392Y525408D01*
Y527492D01*
G01X989333Y528468D02*
X985333D01*
Y521068D01*
G01X995096Y542497D02*
Y544997D01*
X996137D01*
X996471Y544872D01*
X996679Y544705D01*
X996762Y544372D01*
X996679Y544039D01*
X996429Y543830D01*
X996137Y543705D01*
X995096D01*
G01X996137D02*
X996762Y542497D01*
G01X998237Y543539D02*
X998529Y543830D01*
X998779Y543997D01*
X999112Y544080D01*
X999404Y543997D01*
X999612Y543830D01*
X999779Y543580D01*
X999821Y543289D01*
X999779Y543039D01*
X999612Y542789D01*
X999362Y542580D01*
X999071Y542497D01*
X998737Y542580D01*
X998446Y542830D01*
X998279Y543205D01*
X998237Y543622D01*
X998321Y544164D01*
X998446Y544455D01*
X998654Y544747D01*
X998946Y544955D01*
X999237Y544997D01*
X999529Y544914D01*
X999737Y544705D01*
G01X1002129Y544997D02*
X1001796Y544914D01*
X1001546Y544705D01*
X1001379Y544455D01*
X1001254Y544122D01*
X1001212Y543747D01*
X1001254Y543372D01*
X1001379Y543039D01*
X1001546Y542789D01*
X1001796Y542580D01*
X1002129Y542497D01*
X1002462Y542580D01*
X1002712Y542789D01*
X1002879Y543039D01*
X1003004Y543372D01*
X1003046Y543747D01*
X1003004Y544122D01*
X1002879Y544455D01*
X1002712Y544705D01*
X1002462Y544914D01*
X1002129Y544997D01*
G01X1004437Y544580D02*
X1004687Y544830D01*
X1004979Y544955D01*
X1005312Y544997D01*
X1005729Y544914D01*
X1006021Y544705D01*
X1006104Y544455D01*
X1006062Y544205D01*
X1005896Y543997D01*
X1005062Y543580D01*
X1004687Y543289D01*
X1004437Y542872D01*
X1004354Y542497D01*
X1006104D01*
G01X984200Y542300D02*
X988200D01*
Y549700D01*
G01X987200Y503517D02*
X984700D01*
Y504558D01*
X984825Y504892D01*
X984992Y505100D01*
X985325Y505183D01*
X985658Y505100D01*
X985867Y504850D01*
X985992Y504558D01*
Y503517D01*
G01Y504558D02*
X987200Y505183D01*
G01X986158Y506658D02*
X985867Y506950D01*
X985700Y507200D01*
X985617Y507533D01*
X985700Y507825D01*
X985867Y508033D01*
X986117Y508200D01*
X986408Y508242D01*
X986658Y508200D01*
X986908Y508033D01*
X987117Y507783D01*
X987200Y507492D01*
X987117Y507158D01*
X986867Y506867D01*
X986492Y506700D01*
X986075Y506658D01*
X985533Y506742D01*
X985242Y506867D01*
X984950Y507075D01*
X984742Y507367D01*
X984700Y507658D01*
X984783Y507950D01*
X984992Y508158D01*
G01X984700Y510550D02*
X984783Y510217D01*
X984992Y509967D01*
X985242Y509800D01*
X985575Y509675D01*
X985950Y509633D01*
X986325Y509675D01*
X986658Y509800D01*
X986908Y509967D01*
X987117Y510217D01*
X987200Y510550D01*
X987117Y510883D01*
X986908Y511133D01*
X986658Y511300D01*
X986325Y511425D01*
X985950Y511467D01*
X985575Y511425D01*
X985242Y511300D01*
X984992Y511133D01*
X984783Y510883D01*
X984700Y510550D01*
G01X987200Y513650D02*
X984700D01*
X985200Y513150D01*
G01X987200D02*
Y514150D01*
G01X981300Y516600D02*
X985300D01*
Y524000D01*
G01X960717Y540292D02*
X960467Y540417D01*
X960175Y540500D01*
X959842D01*
X959467Y540375D01*
X959175Y540167D01*
X958967Y539917D01*
X958800Y539500D01*
X958758Y539125D01*
X958842Y538750D01*
X958967Y538500D01*
X959217Y538250D01*
X959508Y538083D01*
X959800Y538000D01*
X960092D01*
X960383Y538083D01*
X960633Y538208D01*
X960842Y538375D01*
G01X961983Y538500D02*
X962233Y538208D01*
X962567Y538042D01*
X962942Y538000D01*
X963275Y538042D01*
X963608Y538250D01*
X963817Y538500D01*
X963858Y538750D01*
X963775Y539042D01*
X963483Y539250D01*
X963192Y539333D01*
X962817D01*
G01X963192D02*
X963442Y539458D01*
X963650Y539667D01*
X963733Y539917D01*
X963650Y540167D01*
X963442Y540375D01*
X963067Y540500D01*
X962692Y540458D01*
X962317Y540292D01*
G01X965917Y538000D02*
X966000Y538542D01*
X966125Y539000D01*
X966292Y539417D01*
X966500Y539875D01*
X966833Y540500D01*
X965167D01*
G01X966421Y545271D02*
Y557171D01*
G01X974421Y545271D02*
X966421D01*
G01X974421Y557171D02*
Y545271D01*
G01X966421Y557171D02*
X974421D01*
G01X970421Y555571D02*
X972021Y557171D01*
G01X970421Y555571D02*
X968821Y557171D01*
G01X966383Y514600D02*
Y512808D01*
X966550Y512433D01*
X966883Y512183D01*
X967300Y512100D01*
X967717Y512183D01*
X968050Y512433D01*
X968217Y512808D01*
Y514600D01*
G01X969608Y514183D02*
X969858Y514433D01*
X970150Y514558D01*
X970483Y514600D01*
X970900Y514517D01*
X971192Y514308D01*
X971275Y514058D01*
X971233Y513808D01*
X971067Y513600D01*
X970233Y513183D01*
X969858Y512892D01*
X969608Y512475D01*
X969525Y512100D01*
X971275D01*
G01X972583Y512600D02*
X972833Y512308D01*
X973167Y512142D01*
X973542Y512100D01*
X973875Y512142D01*
X974208Y512350D01*
X974417Y512600D01*
X974458Y512850D01*
X974375Y513142D01*
X974083Y513350D01*
X973792Y513433D01*
X973417D01*
G01X973792D02*
X974042Y513558D01*
X974250Y513767D01*
X974333Y514017D01*
X974250Y514267D01*
X974042Y514475D01*
X973667Y514600D01*
X973292Y514558D01*
X972917Y514392D01*
G01X964063Y519157D02*
Y531057D01*
G01X972063Y519157D02*
X964063D01*
G01X972063Y531057D02*
Y519157D01*
G01X964063Y531057D02*
X972063D01*
G01X968063Y529457D02*
X969663Y531057D01*
G01X968063Y529457D02*
X966463Y531057D01*
G01X978817Y574292D02*
X978567Y574417D01*
X978275Y574500D01*
X977942D01*
X977567Y574375D01*
X977275Y574167D01*
X977067Y573917D01*
X976900Y573500D01*
X976858Y573125D01*
X976942Y572750D01*
X977067Y572500D01*
X977317Y572250D01*
X977608Y572083D01*
X977900Y572000D01*
X978192D01*
X978483Y572083D01*
X978733Y572208D01*
X978942Y572375D01*
G01X980083D02*
X980333Y572167D01*
X980625Y572042D01*
X981000Y572000D01*
X981375Y572083D01*
X981667Y572250D01*
X981875Y572542D01*
X981917Y572875D01*
X981833Y573208D01*
X981625Y573417D01*
X981333Y573583D01*
X981042Y573625D01*
X980750Y573583D01*
X980375Y573417D01*
X980500Y574500D01*
X981625D01*
G01X983392Y572292D02*
X983683Y572083D01*
X984017Y572000D01*
X984350Y572083D01*
X984642Y572333D01*
X984850Y572708D01*
X984933Y573083D01*
Y573542D01*
X984850Y573917D01*
X984642Y574250D01*
X984392Y574417D01*
X984100Y574500D01*
X983767Y574417D01*
X983517Y574250D01*
X983350Y574000D01*
X983267Y573667D01*
X983350Y573375D01*
X983558Y573083D01*
X983808Y572917D01*
X984100Y572875D01*
X984433Y572958D01*
X984683Y573167D01*
X984933Y573542D01*
G01X974367Y760300D02*
Y762800D01*
X975408D01*
X975742Y762675D01*
X975950Y762508D01*
X976033Y762175D01*
X975950Y761842D01*
X975700Y761633D01*
X975408Y761508D01*
X974367D01*
G01X975408D02*
X976033Y760300D01*
G01X978217D02*
X978300Y760842D01*
X978425Y761300D01*
X978592Y761717D01*
X978800Y762175D01*
X979133Y762800D01*
X977467D01*
G01X981900Y760300D02*
Y762800D01*
X980358Y761008D01*
X982442D01*
G01X965820Y759010D02*
Y763010D01*
X958420D01*
G01X989208Y819317D02*
X989083Y819067D01*
X989000Y818775D01*
Y818442D01*
X989125Y818067D01*
X989333Y817775D01*
X989583Y817567D01*
X990000Y817400D01*
X990375Y817358D01*
X990750Y817442D01*
X991000Y817567D01*
X991250Y817817D01*
X991417Y818108D01*
X991500Y818400D01*
Y818692D01*
X991417Y818983D01*
X991292Y819233D01*
X991125Y819442D01*
G01X989417Y820708D02*
X989167Y820958D01*
X989042Y821250D01*
X989000Y821583D01*
X989083Y822000D01*
X989292Y822292D01*
X989542Y822375D01*
X989792Y822333D01*
X990000Y822167D01*
X990417Y821333D01*
X990708Y820958D01*
X991125Y820708D01*
X991500Y820625D01*
Y822375D01*
G01X991000Y823683D02*
X991292Y823933D01*
X991458Y824267D01*
X991500Y824642D01*
X991458Y824975D01*
X991250Y825308D01*
X991000Y825517D01*
X990750Y825558D01*
X990458Y825475D01*
X990250Y825183D01*
X990167Y824892D01*
Y824517D01*
G01Y824892D02*
X990042Y825142D01*
X989833Y825350D01*
X989583Y825433D01*
X989333Y825350D01*
X989125Y825142D01*
X989000Y824767D01*
X989042Y824392D01*
X989208Y824017D01*
G01X1004756Y835434D02*
X1004506Y835559D01*
X1004214Y835642D01*
X1003881D01*
X1003506Y835517D01*
X1003214Y835309D01*
X1003006Y835059D01*
X1002839Y834642D01*
X1002797Y834267D01*
X1002881Y833892D01*
X1003006Y833642D01*
X1003256Y833392D01*
X1003547Y833225D01*
X1003839Y833142D01*
X1004131D01*
X1004422Y833225D01*
X1004672Y833350D01*
X1004881Y833517D01*
G01X1006147Y835225D02*
X1006397Y835475D01*
X1006689Y835600D01*
X1007022Y835642D01*
X1007439Y835559D01*
X1007731Y835350D01*
X1007814Y835100D01*
X1007772Y834850D01*
X1007606Y834642D01*
X1006772Y834225D01*
X1006397Y833934D01*
X1006147Y833517D01*
X1006064Y833142D01*
X1007814D01*
G01X1009122Y833517D02*
X1009372Y833309D01*
X1009664Y833184D01*
X1010039Y833142D01*
X1010414Y833225D01*
X1010706Y833392D01*
X1010914Y833684D01*
X1010956Y834017D01*
X1010872Y834350D01*
X1010664Y834559D01*
X1010372Y834725D01*
X1010081Y834767D01*
X1009789Y834725D01*
X1009414Y834559D01*
X1009539Y835642D01*
X1010664D01*
G01X974367Y768300D02*
Y770800D01*
X975408D01*
X975742Y770675D01*
X975950Y770508D01*
X976033Y770175D01*
X975950Y769842D01*
X975700Y769633D01*
X975408Y769508D01*
X974367D01*
G01X975408D02*
X976033Y768300D01*
G01X978217D02*
X978300Y768842D01*
X978425Y769300D01*
X978592Y769717D01*
X978800Y770175D01*
X979133Y770800D01*
X977467D01*
G01X980608Y770383D02*
X980858Y770633D01*
X981150Y770758D01*
X981483Y770800D01*
X981900Y770717D01*
X982192Y770508D01*
X982275Y770258D01*
X982233Y770008D01*
X982067Y769800D01*
X981233Y769383D01*
X980858Y769092D01*
X980608Y768675D01*
X980525Y768300D01*
X982275D01*
G01X958420Y772010D02*
Y768010D01*
X965820D01*
G01X974367Y776300D02*
Y778800D01*
X975408D01*
X975742Y778675D01*
X975950Y778508D01*
X976033Y778175D01*
X975950Y777842D01*
X975700Y777633D01*
X975408Y777508D01*
X974367D01*
G01X975408D02*
X976033Y776300D01*
G01X978217D02*
X978300Y776842D01*
X978425Y777300D01*
X978592Y777717D01*
X978800Y778175D01*
X979133Y778800D01*
X977467D01*
G01X980483Y776800D02*
X980733Y776508D01*
X981067Y776342D01*
X981442Y776300D01*
X981775Y776342D01*
X982108Y776550D01*
X982317Y776800D01*
X982358Y777050D01*
X982275Y777342D01*
X981983Y777550D01*
X981692Y777633D01*
X981317D01*
G01X981692D02*
X981942Y777758D01*
X982150Y777967D01*
X982233Y778217D01*
X982150Y778467D01*
X981942Y778675D01*
X981567Y778800D01*
X981192Y778758D01*
X980817Y778592D01*
G01X965820Y777010D02*
Y781010D01*
X958420D01*
G01X974367Y764300D02*
Y766800D01*
X975408D01*
X975742Y766675D01*
X975950Y766508D01*
X976033Y766175D01*
X975950Y765842D01*
X975700Y765633D01*
X975408Y765508D01*
X974367D01*
G01X975408D02*
X976033Y764300D01*
G01X978217D02*
X978300Y764842D01*
X978425Y765300D01*
X978592Y765717D01*
X978800Y766175D01*
X979133Y766800D01*
X977467D01*
G01X981400Y764300D02*
X981692Y764342D01*
X982025Y764467D01*
X982233Y764675D01*
X982317Y764967D01*
X982233Y765258D01*
X981983Y765508D01*
X981608Y765633D01*
X981192D01*
X980942Y765717D01*
X980733Y765925D01*
X980650Y766217D01*
X980775Y766508D01*
X981067Y766717D01*
X981400Y766800D01*
X981733Y766717D01*
X982025Y766508D01*
X982150Y766217D01*
X982067Y765925D01*
X981858Y765717D01*
X981608Y765633D01*
X981192D01*
X980817Y765508D01*
X980567Y765258D01*
X980483Y764967D01*
X980567Y764675D01*
X980775Y764467D01*
X981108Y764342D01*
X981400Y764300D01*
G01X965820Y763510D02*
Y767510D01*
X958420D01*
G01X974367Y772300D02*
Y774800D01*
X975408D01*
X975742Y774675D01*
X975950Y774508D01*
X976033Y774175D01*
X975950Y773842D01*
X975700Y773633D01*
X975408Y773508D01*
X974367D01*
G01X975408D02*
X976033Y772300D01*
G01X978217D02*
X978300Y772842D01*
X978425Y773300D01*
X978592Y773717D01*
X978800Y774175D01*
X979133Y774800D01*
X977467D01*
G01X980692Y772592D02*
X980983Y772383D01*
X981317Y772300D01*
X981650Y772383D01*
X981942Y772633D01*
X982150Y773008D01*
X982233Y773383D01*
Y773842D01*
X982150Y774217D01*
X981942Y774550D01*
X981692Y774717D01*
X981400Y774800D01*
X981067Y774717D01*
X980817Y774550D01*
X980650Y774300D01*
X980567Y773967D01*
X980650Y773675D01*
X980858Y773383D01*
X981108Y773217D01*
X981400Y773175D01*
X981733Y773258D01*
X981983Y773467D01*
X982233Y773842D01*
G01X958420Y776510D02*
Y772510D01*
X965820D01*
G01X965982Y831915D02*
X963482D01*
Y832956D01*
X963607Y833290D01*
X963774Y833498D01*
X964107Y833581D01*
X964440Y833498D01*
X964649Y833248D01*
X964774Y832956D01*
Y831915D01*
G01Y832956D02*
X965982Y833581D01*
G01Y835848D02*
X965940Y836140D01*
X965815Y836473D01*
X965607Y836681D01*
X965315Y836765D01*
X965024Y836681D01*
X964774Y836431D01*
X964649Y836056D01*
Y835640D01*
X964565Y835390D01*
X964357Y835181D01*
X964065Y835098D01*
X963774Y835223D01*
X963565Y835515D01*
X963482Y835848D01*
X963565Y836181D01*
X963774Y836473D01*
X964065Y836598D01*
X964357Y836515D01*
X964565Y836306D01*
X964649Y836056D01*
Y835640D01*
X964774Y835265D01*
X965024Y835015D01*
X965315Y834931D01*
X965607Y835015D01*
X965815Y835223D01*
X965940Y835556D01*
X965982Y835848D01*
G01X963899Y838156D02*
X963649Y838406D01*
X963524Y838698D01*
X963482Y839031D01*
X963565Y839448D01*
X963774Y839740D01*
X964024Y839823D01*
X964274Y839781D01*
X964482Y839615D01*
X964899Y838781D01*
X965190Y838406D01*
X965607Y838156D01*
X965982Y838073D01*
Y839823D01*
G01X964093Y843800D02*
X968093D01*
Y851200D01*
G01X962400Y831867D02*
X959900D01*
Y832908D01*
X960025Y833242D01*
X960192Y833450D01*
X960525Y833533D01*
X960858Y833450D01*
X961067Y833200D01*
X961192Y832908D01*
Y831867D01*
G01Y832908D02*
X962400Y833533D01*
G01Y835800D02*
X962358Y836092D01*
X962233Y836425D01*
X962025Y836633D01*
X961733Y836717D01*
X961442Y836633D01*
X961192Y836383D01*
X961067Y836008D01*
Y835592D01*
X960983Y835342D01*
X960775Y835133D01*
X960483Y835050D01*
X960192Y835175D01*
X959983Y835467D01*
X959900Y835800D01*
X959983Y836133D01*
X960192Y836425D01*
X960483Y836550D01*
X960775Y836467D01*
X960983Y836258D01*
X961067Y836008D01*
Y835592D01*
X961192Y835217D01*
X961442Y834967D01*
X961733Y834883D01*
X962025Y834967D01*
X962233Y835175D01*
X962358Y835508D01*
X962400Y835800D01*
G01X961358Y838108D02*
X961067Y838400D01*
X960900Y838650D01*
X960817Y838983D01*
X960900Y839275D01*
X961067Y839483D01*
X961317Y839650D01*
X961608Y839692D01*
X961858Y839650D01*
X962108Y839483D01*
X962317Y839233D01*
X962400Y838942D01*
X962317Y838608D01*
X962067Y838317D01*
X961692Y838150D01*
X961275Y838108D01*
X960733Y838192D01*
X960442Y838317D01*
X960150Y838525D01*
X959942Y838817D01*
X959900Y839108D01*
X959983Y839400D01*
X960192Y839608D01*
G01X964000Y851200D02*
X960000D01*
Y843800D01*
G01X979500Y814455D02*
X977000D01*
Y815496D01*
X977125Y815830D01*
X977292Y816038D01*
X977625Y816121D01*
X977958Y816038D01*
X978167Y815788D01*
X978292Y815496D01*
Y814455D01*
G01Y815496D02*
X979500Y816121D01*
G01Y818388D02*
X977000D01*
X977500Y817888D01*
G01X979500D02*
Y818888D01*
G01X977000Y821488D02*
X977083Y821155D01*
X977292Y820905D01*
X977542Y820738D01*
X977875Y820613D01*
X978250Y820571D01*
X978625Y820613D01*
X978958Y820738D01*
X979208Y820905D01*
X979417Y821155D01*
X979500Y821488D01*
X979417Y821821D01*
X979208Y822071D01*
X978958Y822238D01*
X978625Y822363D01*
X978250Y822405D01*
X977875Y822363D01*
X977542Y822238D01*
X977292Y822071D01*
X977083Y821821D01*
X977000Y821488D01*
G01X979208Y823880D02*
X979417Y824171D01*
X979500Y824505D01*
X979417Y824838D01*
X979167Y825130D01*
X978792Y825338D01*
X978417Y825421D01*
X977958D01*
X977583Y825338D01*
X977250Y825130D01*
X977083Y824880D01*
X977000Y824588D01*
X977083Y824255D01*
X977250Y824005D01*
X977500Y823838D01*
X977833Y823755D01*
X978125Y823838D01*
X978417Y824046D01*
X978583Y824296D01*
X978625Y824588D01*
X978542Y824921D01*
X978333Y825171D01*
X977958Y825421D01*
G01X979570Y837128D02*
X975570D01*
Y829728D01*
G01X974000Y814455D02*
X971500D01*
Y815496D01*
X971625Y815830D01*
X971792Y816038D01*
X972125Y816121D01*
X972458Y816038D01*
X972667Y815788D01*
X972792Y815496D01*
Y814455D01*
G01Y815496D02*
X974000Y816121D01*
G01Y818388D02*
X971500D01*
X972000Y817888D01*
G01X974000D02*
Y818888D01*
G01Y821488D02*
X971500D01*
X972000Y820988D01*
G01X974000D02*
Y821988D01*
G01X971500Y824588D02*
X971583Y824255D01*
X971792Y824005D01*
X972042Y823838D01*
X972375Y823713D01*
X972750Y823671D01*
X973125Y823713D01*
X973458Y823838D01*
X973708Y824005D01*
X973917Y824255D01*
X974000Y824588D01*
X973917Y824921D01*
X973708Y825171D01*
X973458Y825338D01*
X973125Y825463D01*
X972750Y825505D01*
X972375Y825463D01*
X972042Y825338D01*
X971792Y825171D01*
X971583Y824921D01*
X971500Y824588D01*
G01X975070Y837128D02*
X971070D01*
Y829728D01*
G01X984500Y812517D02*
X982000D01*
Y813558D01*
X982125Y813892D01*
X982292Y814100D01*
X982625Y814183D01*
X982958Y814100D01*
X983167Y813850D01*
X983292Y813558D01*
Y812517D01*
G01Y813558D02*
X984500Y814183D01*
G01Y816450D02*
X982000D01*
X982500Y815950D01*
G01X984500D02*
Y816950D01*
G01Y819550D02*
X982000D01*
X982500Y819050D01*
G01X984500D02*
Y820050D01*
G01Y823150D02*
X982000D01*
X983792Y821608D01*
Y823692D01*
G01X985070Y835190D02*
X981070D01*
Y827790D01*
G01X1001500Y824517D02*
X999000D01*
Y825558D01*
X999125Y825892D01*
X999292Y826100D01*
X999625Y826183D01*
X999958Y826100D01*
X1000167Y825850D01*
X1000292Y825558D01*
Y824517D01*
G01Y825558D02*
X1001500Y826183D01*
G01Y828450D02*
X999000D01*
X999500Y827950D01*
G01X1001500D02*
Y828950D01*
G01Y831550D02*
X999000D01*
X999500Y831050D01*
G01X1001500D02*
Y832050D01*
G01Y834567D02*
X1000958Y834650D01*
X1000500Y834775D01*
X1000083Y834942D01*
X999625Y835150D01*
X999000Y835483D01*
Y833817D01*
G01X1007450Y847460D02*
X1003450D01*
Y840060D01*
G01X997500Y824517D02*
X995000D01*
Y825558D01*
X995125Y825892D01*
X995292Y826100D01*
X995625Y826183D01*
X995958Y826100D01*
X996167Y825850D01*
X996292Y825558D01*
Y824517D01*
G01Y825558D02*
X997500Y826183D01*
G01Y828450D02*
X995000D01*
X995500Y827950D01*
G01X997500D02*
Y828950D01*
G01Y831550D02*
X995000D01*
X995500Y831050D01*
G01X997500D02*
Y832050D01*
G01Y834650D02*
X997458Y834942D01*
X997333Y835275D01*
X997125Y835483D01*
X996833Y835567D01*
X996542Y835483D01*
X996292Y835233D01*
X996167Y834858D01*
Y834442D01*
X996083Y834192D01*
X995875Y833983D01*
X995583Y833900D01*
X995292Y834025D01*
X995083Y834317D01*
X995000Y834650D01*
X995083Y834983D01*
X995292Y835275D01*
X995583Y835400D01*
X995875Y835317D01*
X996083Y835108D01*
X996167Y834858D01*
Y834442D01*
X996292Y834067D01*
X996542Y833817D01*
X996833Y833733D01*
X997125Y833817D01*
X997333Y834025D01*
X997458Y834358D01*
X997500Y834650D01*
G01X1002950Y847460D02*
X998950D01*
Y840060D01*
G01X1039581Y853984D02*
Y857984D01*
X1032181D01*
G01X1012517Y833000D02*
Y835500D01*
X1013558D01*
X1013892Y835375D01*
X1014100Y835208D01*
X1014183Y834875D01*
X1014100Y834542D01*
X1013850Y834333D01*
X1013558Y834208D01*
X1012517D01*
G01X1013558D02*
X1014183Y833000D01*
G01X1016450D02*
Y835500D01*
X1015950Y835000D01*
G01Y833000D02*
X1016950D01*
G01X1018758Y835083D02*
X1019008Y835333D01*
X1019300Y835458D01*
X1019633Y835500D01*
X1020050Y835417D01*
X1020342Y835208D01*
X1020425Y834958D01*
X1020383Y834708D01*
X1020217Y834500D01*
X1019383Y834083D01*
X1019008Y833792D01*
X1018758Y833375D01*
X1018675Y833000D01*
X1020425D01*
G01X1021733Y833500D02*
X1021983Y833208D01*
X1022317Y833042D01*
X1022692Y833000D01*
X1023025Y833042D01*
X1023358Y833250D01*
X1023567Y833500D01*
X1023608Y833750D01*
X1023525Y834042D01*
X1023233Y834250D01*
X1022942Y834333D01*
X1022567D01*
G01X1022942D02*
X1023192Y834458D01*
X1023400Y834667D01*
X1023483Y834917D01*
X1023400Y835167D01*
X1023192Y835375D01*
X1022817Y835500D01*
X1022442Y835458D01*
X1022067Y835292D01*
G01X1025700Y840500D02*
Y844500D01*
X1018300D01*
G01X1031600Y859000D02*
X1027600D01*
Y851600D01*
G01X1039584Y849705D02*
Y853705D01*
X1032184D01*
G01X1031862Y847214D02*
Y851214D01*
X1024462D01*
G01X1040767Y823000D02*
Y825500D01*
X1041808D01*
X1042142Y825375D01*
X1042350Y825208D01*
X1042433Y824875D01*
X1042350Y824542D01*
X1042100Y824333D01*
X1041808Y824208D01*
X1040767D01*
G01X1041808D02*
X1042433Y823000D01*
G01X1044700D02*
Y825500D01*
X1044200Y825000D01*
G01Y823000D02*
X1045200D01*
G01X1046883Y823500D02*
X1047133Y823208D01*
X1047467Y823042D01*
X1047842Y823000D01*
X1048175Y823042D01*
X1048508Y823250D01*
X1048717Y823500D01*
X1048758Y823750D01*
X1048675Y824042D01*
X1048383Y824250D01*
X1048092Y824333D01*
X1047717D01*
G01X1048092D02*
X1048342Y824458D01*
X1048550Y824667D01*
X1048633Y824917D01*
X1048550Y825167D01*
X1048342Y825375D01*
X1047967Y825500D01*
X1047592Y825458D01*
X1047217Y825292D01*
G01X1052300Y826250D02*
Y822250D01*
X1059700D01*
G01X1040767Y812900D02*
Y815400D01*
X1041808D01*
X1042142Y815275D01*
X1042350Y815108D01*
X1042433Y814775D01*
X1042350Y814442D01*
X1042100Y814233D01*
X1041808Y814108D01*
X1040767D01*
G01X1041808D02*
X1042433Y812900D01*
G01X1044700D02*
Y815400D01*
X1044200Y814900D01*
G01Y812900D02*
X1045200D01*
G01X1047008Y814983D02*
X1047258Y815233D01*
X1047550Y815358D01*
X1047883Y815400D01*
X1048300Y815317D01*
X1048592Y815108D01*
X1048675Y814858D01*
X1048633Y814608D01*
X1048467Y814400D01*
X1047633Y813983D01*
X1047258Y813692D01*
X1047008Y813275D01*
X1046925Y812900D01*
X1048675D01*
G01X1052300Y816500D02*
Y812500D01*
X1059700D01*
G01X1041667Y836500D02*
Y839000D01*
X1042708D01*
X1043042Y838875D01*
X1043250Y838708D01*
X1043333Y838375D01*
X1043250Y838042D01*
X1043000Y837833D01*
X1042708Y837708D01*
X1041667D01*
G01X1042708D02*
X1043333Y836500D01*
G01X1045600D02*
Y839000D01*
X1045100Y838500D01*
G01Y836500D02*
X1046100D01*
G01X1048700D02*
Y839000D01*
X1048200Y838500D01*
G01Y836500D02*
X1049200D01*
G01X1052300Y839800D02*
Y835800D01*
X1059700D01*
G01X1040867Y827400D02*
Y829900D01*
X1041908D01*
X1042242Y829775D01*
X1042450Y829608D01*
X1042533Y829275D01*
X1042450Y828942D01*
X1042200Y828733D01*
X1041908Y828608D01*
X1040867D01*
G01X1041908D02*
X1042533Y827400D01*
G01X1044800D02*
Y829900D01*
X1044300Y829400D01*
G01Y827400D02*
X1045300D01*
G01X1047900Y829900D02*
X1047567Y829817D01*
X1047317Y829608D01*
X1047150Y829358D01*
X1047025Y829025D01*
X1046983Y828650D01*
X1047025Y828275D01*
X1047150Y827942D01*
X1047317Y827692D01*
X1047567Y827483D01*
X1047900Y827400D01*
X1048233Y827483D01*
X1048483Y827692D01*
X1048650Y827942D01*
X1048775Y828275D01*
X1048817Y828650D01*
X1048775Y829025D01*
X1048650Y829358D01*
X1048483Y829608D01*
X1048233Y829817D01*
X1047900Y829900D01*
G01X1052300Y830400D02*
Y826400D01*
X1059700D01*
G01X1011292Y823506D02*
Y826006D01*
X1012333D01*
X1012667Y825881D01*
X1012875Y825714D01*
X1012958Y825381D01*
X1012875Y825048D01*
X1012625Y824839D01*
X1012333Y824714D01*
X1011292D01*
G01X1012333D02*
X1012958Y823506D01*
G01X1015225D02*
Y826006D01*
X1014725Y825506D01*
G01Y823506D02*
X1015725D01*
G01X1017533Y825589D02*
X1017783Y825839D01*
X1018075Y825964D01*
X1018408Y826006D01*
X1018825Y825923D01*
X1019117Y825714D01*
X1019200Y825464D01*
X1019158Y825214D01*
X1018992Y825006D01*
X1018158Y824589D01*
X1017783Y824298D01*
X1017533Y823881D01*
X1017450Y823506D01*
X1019200D01*
G01X1020717Y823798D02*
X1021008Y823589D01*
X1021342Y823506D01*
X1021675Y823589D01*
X1021967Y823839D01*
X1022175Y824214D01*
X1022258Y824589D01*
Y825048D01*
X1022175Y825423D01*
X1021967Y825756D01*
X1021717Y825923D01*
X1021425Y826006D01*
X1021092Y825923D01*
X1020842Y825756D01*
X1020675Y825506D01*
X1020592Y825173D01*
X1020675Y824881D01*
X1020883Y824589D01*
X1021133Y824423D01*
X1021425Y824381D01*
X1021758Y824464D01*
X1022008Y824673D01*
X1022258Y825048D01*
G01X1023608Y823881D02*
X1023858Y823673D01*
X1024150Y823548D01*
X1024525Y823506D01*
X1024900Y823589D01*
X1025192Y823756D01*
X1025400Y824048D01*
X1025442Y824381D01*
X1025358Y824714D01*
X1025150Y824923D01*
X1024858Y825089D01*
X1024567Y825131D01*
X1024275Y825089D01*
X1023900Y824923D01*
X1024025Y826006D01*
X1025150D01*
G01X1024321Y832913D02*
Y828913D01*
X1031721D01*
G01X1024533Y818902D02*
Y821402D01*
X1025574D01*
X1025908Y821277D01*
X1026116Y821110D01*
X1026199Y820777D01*
X1026116Y820444D01*
X1025866Y820235D01*
X1025574Y820110D01*
X1024533D01*
G01X1025574D02*
X1026199Y818902D01*
G01X1028466D02*
Y821402D01*
X1027966Y820902D01*
G01Y818902D02*
X1028966D01*
G01X1030774Y820985D02*
X1031024Y821235D01*
X1031316Y821360D01*
X1031649Y821402D01*
X1032066Y821319D01*
X1032358Y821110D01*
X1032441Y820860D01*
X1032399Y820610D01*
X1032233Y820402D01*
X1031399Y819985D01*
X1031024Y819694D01*
X1030774Y819277D01*
X1030691Y818902D01*
X1032441D01*
G01X1033958Y819194D02*
X1034249Y818985D01*
X1034583Y818902D01*
X1034916Y818985D01*
X1035208Y819235D01*
X1035416Y819610D01*
X1035499Y819985D01*
Y820444D01*
X1035416Y820819D01*
X1035208Y821152D01*
X1034958Y821319D01*
X1034666Y821402D01*
X1034333Y821319D01*
X1034083Y821152D01*
X1033916Y820902D01*
X1033833Y820569D01*
X1033916Y820277D01*
X1034124Y819985D01*
X1034374Y819819D01*
X1034666Y819777D01*
X1034999Y819860D01*
X1035249Y820069D01*
X1035499Y820444D01*
G01X1038266Y818902D02*
Y821402D01*
X1036724Y819610D01*
X1038808D01*
G01X1035042Y823127D02*
Y827127D01*
X1027642D01*
G01X1004756Y831434D02*
X1004506Y831559D01*
X1004214Y831642D01*
X1003881D01*
X1003506Y831517D01*
X1003214Y831309D01*
X1003006Y831059D01*
X1002839Y830642D01*
X1002797Y830267D01*
X1002881Y829892D01*
X1003006Y829642D01*
X1003256Y829392D01*
X1003547Y829225D01*
X1003839Y829142D01*
X1004131D01*
X1004422Y829225D01*
X1004672Y829350D01*
X1004881Y829517D01*
G01X1006147Y831225D02*
X1006397Y831475D01*
X1006689Y831600D01*
X1007022Y831642D01*
X1007439Y831559D01*
X1007731Y831350D01*
X1007814Y831100D01*
X1007772Y830850D01*
X1007606Y830642D01*
X1006772Y830225D01*
X1006397Y829934D01*
X1006147Y829517D01*
X1006064Y829142D01*
X1007814D01*
G01X1010539D02*
Y831642D01*
X1008997Y829850D01*
X1011081D01*
G01X996000Y851983D02*
X997792D01*
X998167Y852150D01*
X998417Y852483D01*
X998500Y852900D01*
X998417Y853317D01*
X998167Y853650D01*
X997792Y853817D01*
X996000D01*
G01X998500Y856000D02*
X996000D01*
X996500Y855500D01*
G01X998500D02*
Y856500D01*
G01Y859600D02*
X996000D01*
X997792Y858058D01*
Y860142D01*
G01X1019900Y839500D02*
Y837000D01*
G01X1018942Y839500D02*
X1020858D01*
G01X1022167Y837000D02*
Y839500D01*
X1023167D01*
X1023500Y839375D01*
X1023750Y839083D01*
X1023833Y838750D01*
X1023750Y838417D01*
X1023542Y838167D01*
X1023167Y838042D01*
X1022167D01*
G01X1026100Y837000D02*
Y839500D01*
X1025600Y839000D01*
G01Y837000D02*
X1026600D01*
G01X993500Y840983D02*
X995292D01*
X995667Y841150D01*
X995917Y841483D01*
X996000Y841900D01*
X995917Y842317D01*
X995667Y842650D01*
X995292Y842817D01*
X993500D01*
G01X996000Y845000D02*
X993500D01*
X994000Y844500D01*
G01X996000D02*
Y845500D01*
G01X995500Y847183D02*
X995792Y847433D01*
X995958Y847767D01*
X996000Y848142D01*
X995958Y848475D01*
X995750Y848808D01*
X995500Y849017D01*
X995250Y849058D01*
X994958Y848975D01*
X994750Y848683D01*
X994667Y848392D01*
Y848017D01*
G01Y848392D02*
X994542Y848642D01*
X994333Y848850D01*
X994083Y848933D01*
X993833Y848850D01*
X993625Y848642D01*
X993500Y848267D01*
X993542Y847892D01*
X993708Y847517D01*
G01X992320Y853050D02*
X990220Y854850D01*
X992320Y857050D01*
G01X992420Y860650D02*
X973220D01*
Y849450D01*
X992420D01*
Y860650D01*
X992020D01*
G01X1025294Y803983D02*
Y801483D01*
G01X1024336Y803983D02*
X1026252D01*
G01X1029311Y803775D02*
X1029061Y803900D01*
X1028769Y803983D01*
X1028436D01*
X1028061Y803858D01*
X1027769Y803650D01*
X1027561Y803400D01*
X1027394Y802983D01*
X1027352Y802608D01*
X1027436Y802233D01*
X1027561Y801983D01*
X1027811Y801733D01*
X1028102Y801566D01*
X1028394Y801483D01*
X1028686D01*
X1028977Y801566D01*
X1029227Y801691D01*
X1029436Y801858D01*
G01X1030702Y803566D02*
X1030952Y803816D01*
X1031244Y803941D01*
X1031577Y803983D01*
X1031994Y803900D01*
X1032286Y803691D01*
X1032369Y803441D01*
X1032327Y803191D01*
X1032161Y802983D01*
X1031327Y802566D01*
X1030952Y802275D01*
X1030702Y801858D01*
X1030619Y801483D01*
X1032369D01*
G01X1014394Y763333D02*
Y794933D01*
X1019094Y799633D01*
X1037694D01*
X1042394Y794933D01*
Y763333D01*
X1014394D01*
G01X975317Y909292D02*
X975067Y909417D01*
X974775Y909500D01*
X974442D01*
X974067Y909375D01*
X973775Y909167D01*
X973567Y908917D01*
X973400Y908500D01*
X973358Y908125D01*
X973442Y907750D01*
X973567Y907500D01*
X973817Y907250D01*
X974108Y907083D01*
X974400Y907000D01*
X974692D01*
X974983Y907083D01*
X975233Y907208D01*
X975442Y907375D01*
G01X976708Y909083D02*
X976958Y909333D01*
X977250Y909458D01*
X977583Y909500D01*
X978000Y909417D01*
X978292Y909208D01*
X978375Y908958D01*
X978333Y908708D01*
X978167Y908500D01*
X977333Y908083D01*
X976958Y907792D01*
X976708Y907375D01*
X976625Y907000D01*
X978375D01*
G01X980600D02*
X980892Y907042D01*
X981225Y907167D01*
X981433Y907375D01*
X981517Y907667D01*
X981433Y907958D01*
X981183Y908208D01*
X980808Y908333D01*
X980392D01*
X980142Y908417D01*
X979933Y908625D01*
X979850Y908917D01*
X979975Y909208D01*
X980267Y909417D01*
X980600Y909500D01*
X980933Y909417D01*
X981225Y909208D01*
X981350Y908917D01*
X981267Y908625D01*
X981058Y908417D01*
X980808Y908333D01*
X980392D01*
X980017Y908208D01*
X979767Y907958D01*
X979683Y907667D01*
X979767Y907375D01*
X979975Y907167D01*
X980308Y907042D01*
X980600Y907000D01*
G01X961817Y908392D02*
X961567Y908517D01*
X961275Y908600D01*
X960942D01*
X960567Y908475D01*
X960275Y908267D01*
X960067Y908017D01*
X959900Y907600D01*
X959858Y907225D01*
X959942Y906850D01*
X960067Y906600D01*
X960317Y906350D01*
X960608Y906183D01*
X960900Y906100D01*
X961192D01*
X961483Y906183D01*
X961733Y906308D01*
X961942Y906475D01*
G01X963083Y906600D02*
X963333Y906308D01*
X963667Y906142D01*
X964042Y906100D01*
X964375Y906142D01*
X964708Y906350D01*
X964917Y906600D01*
X964958Y906850D01*
X964875Y907142D01*
X964583Y907350D01*
X964292Y907433D01*
X963917D01*
G01X964292D02*
X964542Y907558D01*
X964750Y907767D01*
X964833Y908017D01*
X964750Y908267D01*
X964542Y908475D01*
X964167Y908600D01*
X963792Y908558D01*
X963417Y908392D01*
G01X967100Y908600D02*
X966767Y908517D01*
X966517Y908308D01*
X966350Y908058D01*
X966225Y907725D01*
X966183Y907350D01*
X966225Y906975D01*
X966350Y906642D01*
X966517Y906392D01*
X966767Y906183D01*
X967100Y906100D01*
X967433Y906183D01*
X967683Y906392D01*
X967850Y906642D01*
X967975Y906975D01*
X968017Y907350D01*
X967975Y907725D01*
X967850Y908058D01*
X967683Y908308D01*
X967433Y908517D01*
X967100Y908600D01*
G01X988317Y909292D02*
X988067Y909417D01*
X987775Y909500D01*
X987442D01*
X987067Y909375D01*
X986775Y909167D01*
X986567Y908917D01*
X986400Y908500D01*
X986358Y908125D01*
X986442Y907750D01*
X986567Y907500D01*
X986817Y907250D01*
X987108Y907083D01*
X987400Y907000D01*
X987692D01*
X987983Y907083D01*
X988233Y907208D01*
X988442Y907375D01*
G01X989583Y907500D02*
X989833Y907208D01*
X990167Y907042D01*
X990542Y907000D01*
X990875Y907042D01*
X991208Y907250D01*
X991417Y907500D01*
X991458Y907750D01*
X991375Y908042D01*
X991083Y908250D01*
X990792Y908333D01*
X990417D01*
G01X990792D02*
X991042Y908458D01*
X991250Y908667D01*
X991333Y908917D01*
X991250Y909167D01*
X991042Y909375D01*
X990667Y909500D01*
X990292Y909458D01*
X989917Y909292D01*
G01X992892Y907292D02*
X993183Y907083D01*
X993517Y907000D01*
X993850Y907083D01*
X994142Y907333D01*
X994350Y907708D01*
X994433Y908083D01*
Y908542D01*
X994350Y908917D01*
X994142Y909250D01*
X993892Y909417D01*
X993600Y909500D01*
X993267Y909417D01*
X993017Y909250D01*
X992850Y909000D01*
X992767Y908667D01*
X992850Y908375D01*
X993058Y908083D01*
X993308Y907917D01*
X993600Y907875D01*
X993933Y907958D01*
X994183Y908167D01*
X994433Y908542D01*
G01X1025467Y908192D02*
X1025217Y908317D01*
X1024925Y908400D01*
X1024592D01*
X1024217Y908275D01*
X1023925Y908067D01*
X1023717Y907817D01*
X1023550Y907400D01*
X1023508Y907025D01*
X1023592Y906650D01*
X1023717Y906400D01*
X1023967Y906150D01*
X1024258Y905983D01*
X1024550Y905900D01*
X1024842D01*
X1025133Y905983D01*
X1025383Y906108D01*
X1025592Y906275D01*
G01X1028150Y905900D02*
Y908400D01*
X1026608Y906608D01*
X1028692D01*
G01X1030750Y908400D02*
X1030417Y908317D01*
X1030167Y908108D01*
X1030000Y907858D01*
X1029875Y907525D01*
X1029833Y907150D01*
X1029875Y906775D01*
X1030000Y906442D01*
X1030167Y906192D01*
X1030417Y905983D01*
X1030750Y905900D01*
X1031083Y905983D01*
X1031333Y906192D01*
X1031500Y906442D01*
X1031625Y906775D01*
X1031667Y907150D01*
X1031625Y907525D01*
X1031500Y907858D01*
X1031333Y908108D01*
X1031083Y908317D01*
X1030750Y908400D01*
G01X1026708Y891817D02*
X1026583Y891567D01*
X1026500Y891275D01*
Y890942D01*
X1026625Y890567D01*
X1026833Y890275D01*
X1027083Y890067D01*
X1027500Y889900D01*
X1027875Y889858D01*
X1028250Y889942D01*
X1028500Y890067D01*
X1028750Y890317D01*
X1028917Y890608D01*
X1029000Y890900D01*
Y891192D01*
X1028917Y891483D01*
X1028792Y891733D01*
X1028625Y891942D01*
G01Y893083D02*
X1028833Y893333D01*
X1028958Y893625D01*
X1029000Y894000D01*
X1028917Y894375D01*
X1028750Y894667D01*
X1028458Y894875D01*
X1028125Y894917D01*
X1027792Y894833D01*
X1027583Y894625D01*
X1027417Y894333D01*
X1027375Y894042D01*
X1027417Y893750D01*
X1027583Y893375D01*
X1026500Y893500D01*
Y894625D01*
G01X1028500Y896183D02*
X1028792Y896433D01*
X1028958Y896767D01*
X1029000Y897142D01*
X1028958Y897475D01*
X1028750Y897808D01*
X1028500Y898017D01*
X1028250Y898058D01*
X1027958Y897975D01*
X1027750Y897683D01*
X1027667Y897392D01*
Y897017D01*
G01Y897392D02*
X1027542Y897642D01*
X1027333Y897850D01*
X1027083Y897933D01*
X1026833Y897850D01*
X1026625Y897642D01*
X1026500Y897267D01*
X1026542Y896892D01*
X1026708Y896517D01*
G01X996000Y862317D02*
X993500D01*
Y863358D01*
X993625Y863692D01*
X993792Y863900D01*
X994125Y863983D01*
X994458Y863900D01*
X994667Y863650D01*
X994792Y863358D01*
Y862317D01*
G01Y863358D02*
X996000Y863983D01*
G01Y866250D02*
X993500D01*
X994000Y865750D01*
G01X996000D02*
Y866750D01*
G01X993500Y869350D02*
X993583Y869017D01*
X993792Y868767D01*
X994042Y868600D01*
X994375Y868475D01*
X994750Y868433D01*
X995125Y868475D01*
X995458Y868600D01*
X995708Y868767D01*
X995917Y869017D01*
X996000Y869350D01*
X995917Y869683D01*
X995708Y869933D01*
X995458Y870100D01*
X995125Y870225D01*
X994750Y870267D01*
X994375Y870225D01*
X994042Y870100D01*
X993792Y869933D01*
X993583Y869683D01*
X993500Y869350D01*
G01X994958Y871658D02*
X994667Y871950D01*
X994500Y872200D01*
X994417Y872533D01*
X994500Y872825D01*
X994667Y873033D01*
X994917Y873200D01*
X995208Y873242D01*
X995458Y873200D01*
X995708Y873033D01*
X995917Y872783D01*
X996000Y872492D01*
X995917Y872158D01*
X995667Y871867D01*
X995292Y871700D01*
X994875Y871658D01*
X994333Y871742D01*
X994042Y871867D01*
X993750Y872075D01*
X993542Y872367D01*
X993500Y872658D01*
X993583Y872950D01*
X993792Y873158D01*
G01X991942Y874100D02*
X995942D01*
Y881500D01*
G01X980700Y884817D02*
X978200D01*
Y885858D01*
X978325Y886192D01*
X978492Y886400D01*
X978825Y886483D01*
X979158Y886400D01*
X979367Y886150D01*
X979492Y885858D01*
Y884817D01*
G01Y885858D02*
X980700Y886483D01*
G01Y888750D02*
X978200D01*
X978700Y888250D01*
G01X980700D02*
Y889250D01*
G01X978200Y891850D02*
X978283Y891517D01*
X978492Y891267D01*
X978742Y891100D01*
X979075Y890975D01*
X979450Y890933D01*
X979825Y890975D01*
X980158Y891100D01*
X980408Y891267D01*
X980617Y891517D01*
X980700Y891850D01*
X980617Y892183D01*
X980408Y892433D01*
X980158Y892600D01*
X979825Y892725D01*
X979450Y892767D01*
X979075Y892725D01*
X978742Y892600D01*
X978492Y892433D01*
X978283Y892183D01*
X978200Y891850D01*
G01X980700Y894867D02*
X980158Y894950D01*
X979700Y895075D01*
X979283Y895242D01*
X978825Y895450D01*
X978200Y895783D01*
Y894117D01*
G01X987542Y881500D02*
X983542D01*
Y874100D01*
G01X972700Y886517D02*
X970200D01*
Y887558D01*
X970325Y887892D01*
X970492Y888100D01*
X970825Y888183D01*
X971158Y888100D01*
X971367Y887850D01*
X971492Y887558D01*
Y886517D01*
G01Y887558D02*
X972700Y888183D01*
G01Y890450D02*
X970200D01*
X970700Y889950D01*
G01X972700D02*
Y890950D01*
G01X970200Y893550D02*
X970283Y893217D01*
X970492Y892967D01*
X970742Y892800D01*
X971075Y892675D01*
X971450Y892633D01*
X971825Y892675D01*
X972158Y892800D01*
X972408Y892967D01*
X972617Y893217D01*
X972700Y893550D01*
X972617Y893883D01*
X972408Y894133D01*
X972158Y894300D01*
X971825Y894425D01*
X971450Y894467D01*
X971075Y894425D01*
X970742Y894300D01*
X970492Y894133D01*
X970283Y893883D01*
X970200Y893550D01*
G01X972700Y896650D02*
X972658Y896942D01*
X972533Y897275D01*
X972325Y897483D01*
X972033Y897567D01*
X971742Y897483D01*
X971492Y897233D01*
X971367Y896858D01*
Y896442D01*
X971283Y896192D01*
X971075Y895983D01*
X970783Y895900D01*
X970492Y896025D01*
X970283Y896317D01*
X970200Y896650D01*
X970283Y896983D01*
X970492Y897275D01*
X970783Y897400D01*
X971075Y897317D01*
X971283Y897108D01*
X971367Y896858D01*
Y896442D01*
X971492Y896067D01*
X971742Y895817D01*
X972033Y895733D01*
X972325Y895817D01*
X972533Y896025D01*
X972658Y896358D01*
X972700Y896650D01*
G01X974242Y875800D02*
X978242D01*
Y883200D01*
G01X984700Y884817D02*
X982200D01*
Y885858D01*
X982325Y886192D01*
X982492Y886400D01*
X982825Y886483D01*
X983158Y886400D01*
X983367Y886150D01*
X983492Y885858D01*
Y884817D01*
G01Y885858D02*
X984700Y886483D01*
G01Y888750D02*
X982200D01*
X982700Y888250D01*
G01X984700D02*
Y889250D01*
G01Y891850D02*
X982200D01*
X982700Y891350D01*
G01X984700D02*
Y892350D01*
G01Y894950D02*
X982200D01*
X982700Y894450D01*
G01X984700D02*
Y895450D01*
G01X991742Y881500D02*
X987742D01*
Y874100D01*
G01X976600Y886617D02*
X974100D01*
Y887658D01*
X974225Y887992D01*
X974392Y888200D01*
X974725Y888283D01*
X975058Y888200D01*
X975267Y887950D01*
X975392Y887658D01*
Y886617D01*
G01Y887658D02*
X976600Y888283D01*
G01Y890550D02*
X974100D01*
X974600Y890050D01*
G01X976600D02*
Y891050D01*
G01Y893650D02*
X974100D01*
X974600Y893150D01*
G01X976600D02*
Y894150D01*
G01X974517Y895958D02*
X974267Y896208D01*
X974142Y896500D01*
X974100Y896833D01*
X974183Y897250D01*
X974392Y897542D01*
X974642Y897625D01*
X974892Y897583D01*
X975100Y897417D01*
X975517Y896583D01*
X975808Y896208D01*
X976225Y895958D01*
X976600Y895875D01*
Y897625D01*
G01X978442Y874100D02*
X982442D01*
Y881500D01*
G01X968400Y888717D02*
X965900D01*
Y889758D01*
X966025Y890092D01*
X966192Y890300D01*
X966525Y890383D01*
X966858Y890300D01*
X967067Y890050D01*
X967192Y889758D01*
Y888717D01*
G01Y889758D02*
X968400Y890383D01*
G01Y892650D02*
X965900D01*
X966400Y892150D01*
G01X968400D02*
Y893150D01*
G01Y895750D02*
X965900D01*
X966400Y895250D01*
G01X968400D02*
Y896250D01*
G01X967900Y897933D02*
X968192Y898183D01*
X968358Y898517D01*
X968400Y898892D01*
X968358Y899225D01*
X968150Y899558D01*
X967900Y899767D01*
X967650Y899808D01*
X967358Y899725D01*
X967150Y899433D01*
X967067Y899142D01*
Y898767D01*
G01Y899142D02*
X966942Y899392D01*
X966733Y899600D01*
X966483Y899683D01*
X966233Y899600D01*
X966025Y899392D01*
X965900Y899017D01*
X965942Y898642D01*
X966108Y898267D01*
G01X974042Y883200D02*
X970042D01*
Y875800D01*
G01X973431Y911082D02*
Y913582D01*
X974472D01*
X974806Y913457D01*
X975014Y913290D01*
X975097Y912957D01*
X975014Y912624D01*
X974764Y912415D01*
X974472Y912290D01*
X973431D01*
G01X974472D02*
X975097Y911082D01*
G01X977364D02*
Y913582D01*
X976864Y913082D01*
G01Y911082D02*
X977864D01*
G01X980464D02*
Y913582D01*
X979964Y913082D01*
G01Y911082D02*
X980964D01*
G01X982772Y912124D02*
X983064Y912415D01*
X983314Y912582D01*
X983647Y912665D01*
X983939Y912582D01*
X984147Y912415D01*
X984314Y912165D01*
X984356Y911874D01*
X984314Y911624D01*
X984147Y911374D01*
X983897Y911165D01*
X983606Y911082D01*
X983272Y911165D01*
X982981Y911415D01*
X982814Y911790D01*
X982772Y912207D01*
X982856Y912749D01*
X982981Y913040D01*
X983189Y913332D01*
X983481Y913540D01*
X983772Y913582D01*
X984064Y913499D01*
X984272Y913290D01*
G01X1006007Y897075D02*
Y901075D01*
X998607D01*
G01X1038617Y864400D02*
Y866900D01*
X1039658D01*
X1039992Y866775D01*
X1040200Y866608D01*
X1040283Y866275D01*
X1040200Y865942D01*
X1039950Y865733D01*
X1039658Y865608D01*
X1038617D01*
G01X1039658D02*
X1040283Y864400D01*
G01X1042550D02*
Y866900D01*
X1042050Y866400D01*
G01Y864400D02*
X1043050D01*
G01X1045650D02*
Y866900D01*
X1045150Y866400D01*
G01Y864400D02*
X1046150D01*
G01X1048042Y864692D02*
X1048333Y864483D01*
X1048667Y864400D01*
X1049000Y864483D01*
X1049292Y864733D01*
X1049500Y865108D01*
X1049583Y865483D01*
Y865942D01*
X1049500Y866317D01*
X1049292Y866650D01*
X1049042Y866817D01*
X1048750Y866900D01*
X1048417Y866817D01*
X1048167Y866650D01*
X1048000Y866400D01*
X1047917Y866067D01*
X1048000Y865775D01*
X1048208Y865483D01*
X1048458Y865317D01*
X1048750Y865275D01*
X1049083Y865358D01*
X1049333Y865567D01*
X1049583Y865942D01*
G01X973431Y915082D02*
Y917582D01*
X974472D01*
X974806Y917457D01*
X975014Y917290D01*
X975097Y916957D01*
X975014Y916624D01*
X974764Y916415D01*
X974472Y916290D01*
X973431D01*
G01X974472D02*
X975097Y915082D01*
G01X977364D02*
Y917582D01*
X976864Y917082D01*
G01Y915082D02*
X977864D01*
G01X979672Y917165D02*
X979922Y917415D01*
X980214Y917540D01*
X980547Y917582D01*
X980964Y917499D01*
X981256Y917290D01*
X981339Y917040D01*
X981297Y916790D01*
X981131Y916582D01*
X980297Y916165D01*
X979922Y915874D01*
X979672Y915457D01*
X979589Y915082D01*
X981339D01*
G01X982772Y917165D02*
X983022Y917415D01*
X983314Y917540D01*
X983647Y917582D01*
X984064Y917499D01*
X984356Y917290D01*
X984439Y917040D01*
X984397Y916790D01*
X984231Y916582D01*
X983397Y916165D01*
X983022Y915874D01*
X982772Y915457D01*
X982689Y915082D01*
X984439D01*
G01X998607Y905075D02*
Y901075D01*
X1006007D01*
G01X1025278Y870939D02*
Y873439D01*
X1026319D01*
X1026653Y873314D01*
X1026861Y873147D01*
X1026944Y872814D01*
X1026861Y872481D01*
X1026611Y872272D01*
X1026319Y872147D01*
X1025278D01*
G01X1026319D02*
X1026944Y870939D01*
G01X1029211D02*
Y873439D01*
X1028711Y872939D01*
G01Y870939D02*
X1029711D01*
G01X1031519Y873022D02*
X1031769Y873272D01*
X1032061Y873397D01*
X1032394Y873439D01*
X1032811Y873356D01*
X1033103Y873147D01*
X1033186Y872897D01*
X1033144Y872647D01*
X1032978Y872439D01*
X1032144Y872022D01*
X1031769Y871731D01*
X1031519Y871314D01*
X1031436Y870939D01*
X1033186D01*
G01X1034619Y871981D02*
X1034911Y872272D01*
X1035161Y872439D01*
X1035494Y872522D01*
X1035786Y872439D01*
X1035994Y872272D01*
X1036161Y872022D01*
X1036203Y871731D01*
X1036161Y871481D01*
X1035994Y871231D01*
X1035744Y871022D01*
X1035453Y870939D01*
X1035119Y871022D01*
X1034828Y871272D01*
X1034661Y871647D01*
X1034619Y872064D01*
X1034703Y872606D01*
X1034828Y872897D01*
X1035036Y873189D01*
X1035328Y873397D01*
X1035619Y873439D01*
X1035911Y873356D01*
X1036119Y873147D01*
G01X960217Y910500D02*
Y913000D01*
X961258D01*
X961592Y912875D01*
X961800Y912708D01*
X961883Y912375D01*
X961800Y912042D01*
X961550Y911833D01*
X961258Y911708D01*
X960217D01*
G01X961258D02*
X961883Y910500D01*
G01X964150D02*
Y913000D01*
X963650Y912500D01*
G01Y910500D02*
X964650D01*
G01X966333Y911000D02*
X966583Y910708D01*
X966917Y910542D01*
X967292Y910500D01*
X967625Y910542D01*
X967958Y910750D01*
X968167Y911000D01*
X968208Y911250D01*
X968125Y911542D01*
X967833Y911750D01*
X967542Y911833D01*
X967167D01*
G01X967542D02*
X967792Y911958D01*
X968000Y912167D01*
X968083Y912417D01*
X968000Y912667D01*
X967792Y912875D01*
X967417Y913000D01*
X967042Y912958D01*
X966667Y912792D01*
G01X969558Y912583D02*
X969808Y912833D01*
X970100Y912958D01*
X970433Y913000D01*
X970850Y912917D01*
X971142Y912708D01*
X971225Y912458D01*
X971183Y912208D01*
X971017Y912000D01*
X970183Y911583D01*
X969808Y911292D01*
X969558Y910875D01*
X969475Y910500D01*
X971225D01*
G01X995597Y893065D02*
Y897065D01*
X988197D01*
G01X960117Y915400D02*
Y917900D01*
X961158D01*
X961492Y917775D01*
X961700Y917608D01*
X961783Y917275D01*
X961700Y916942D01*
X961450Y916733D01*
X961158Y916608D01*
X960117D01*
G01X961158D02*
X961783Y915400D01*
G01X964050D02*
Y917900D01*
X963550Y917400D01*
G01Y915400D02*
X964550D01*
G01X966233Y915900D02*
X966483Y915608D01*
X966817Y915442D01*
X967192Y915400D01*
X967525Y915442D01*
X967858Y915650D01*
X968067Y915900D01*
X968108Y916150D01*
X968025Y916442D01*
X967733Y916650D01*
X967442Y916733D01*
X967067D01*
G01X967442D02*
X967692Y916858D01*
X967900Y917067D01*
X967983Y917317D01*
X967900Y917567D01*
X967692Y917775D01*
X967317Y917900D01*
X966942Y917858D01*
X966567Y917692D01*
G01X969333Y915900D02*
X969583Y915608D01*
X969917Y915442D01*
X970292Y915400D01*
X970625Y915442D01*
X970958Y915650D01*
X971167Y915900D01*
X971208Y916150D01*
X971125Y916442D01*
X970833Y916650D01*
X970542Y916733D01*
X970167D01*
G01X970542D02*
X970792Y916858D01*
X971000Y917067D01*
X971083Y917317D01*
X971000Y917567D01*
X970792Y917775D01*
X970417Y917900D01*
X970042Y917858D01*
X969667Y917692D01*
G01X988197Y905465D02*
Y901465D01*
X995597D01*
G01X1038517Y860700D02*
Y863200D01*
X1039558D01*
X1039892Y863075D01*
X1040100Y862908D01*
X1040183Y862575D01*
X1040100Y862242D01*
X1039850Y862033D01*
X1039558Y861908D01*
X1038517D01*
G01X1039558D02*
X1040183Y860700D01*
G01X1042450D02*
Y863200D01*
X1041950Y862700D01*
G01Y860700D02*
X1042950D01*
G01X1044758Y861742D02*
X1045050Y862033D01*
X1045300Y862200D01*
X1045633Y862283D01*
X1045925Y862200D01*
X1046133Y862033D01*
X1046300Y861783D01*
X1046342Y861492D01*
X1046300Y861242D01*
X1046133Y860992D01*
X1045883Y860783D01*
X1045592Y860700D01*
X1045258Y860783D01*
X1044967Y861033D01*
X1044800Y861408D01*
X1044758Y861825D01*
X1044842Y862367D01*
X1044967Y862658D01*
X1045175Y862950D01*
X1045467Y863158D01*
X1045758Y863200D01*
X1046050Y863117D01*
X1046258Y862908D01*
G01X1047733Y861200D02*
X1047983Y860908D01*
X1048317Y860742D01*
X1048692Y860700D01*
X1049025Y860742D01*
X1049358Y860950D01*
X1049567Y861200D01*
X1049608Y861450D01*
X1049525Y861742D01*
X1049233Y861950D01*
X1048942Y862033D01*
X1048567D01*
G01X1048942D02*
X1049192Y862158D01*
X1049400Y862367D01*
X1049483Y862617D01*
X1049400Y862867D01*
X1049192Y863075D01*
X1048817Y863200D01*
X1048442Y863158D01*
X1048067Y862992D01*
G01X1025374Y866466D02*
Y868966D01*
X1026415D01*
X1026749Y868841D01*
X1026957Y868674D01*
X1027040Y868341D01*
X1026957Y868008D01*
X1026707Y867799D01*
X1026415Y867674D01*
X1025374D01*
G01X1026415D02*
X1027040Y866466D01*
G01X1029307D02*
Y868966D01*
X1028807Y868466D01*
G01Y866466D02*
X1029807D01*
G01X1031615Y867508D02*
X1031907Y867799D01*
X1032157Y867966D01*
X1032490Y868049D01*
X1032782Y867966D01*
X1032990Y867799D01*
X1033157Y867549D01*
X1033199Y867258D01*
X1033157Y867008D01*
X1032990Y866758D01*
X1032740Y866549D01*
X1032449Y866466D01*
X1032115Y866549D01*
X1031824Y866799D01*
X1031657Y867174D01*
X1031615Y867591D01*
X1031699Y868133D01*
X1031824Y868424D01*
X1032032Y868716D01*
X1032324Y868924D01*
X1032615Y868966D01*
X1032907Y868883D01*
X1033115Y868674D01*
G01X1036007Y866466D02*
Y868966D01*
X1034465Y867174D01*
X1036549D01*
G01X986379Y911082D02*
Y913582D01*
X987420D01*
X987754Y913457D01*
X987962Y913290D01*
X988045Y912957D01*
X987962Y912624D01*
X987712Y912415D01*
X987420Y912290D01*
X986379D01*
G01X987420D02*
X988045Y911082D01*
G01X990312D02*
Y913582D01*
X989812Y913082D01*
G01Y911082D02*
X990812D01*
G01X992620Y912124D02*
X992912Y912415D01*
X993162Y912582D01*
X993495Y912665D01*
X993787Y912582D01*
X993995Y912415D01*
X994162Y912165D01*
X994204Y911874D01*
X994162Y911624D01*
X993995Y911374D01*
X993745Y911165D01*
X993454Y911082D01*
X993120Y911165D01*
X992829Y911415D01*
X992662Y911790D01*
X992620Y912207D01*
X992704Y912749D01*
X992829Y913040D01*
X993037Y913332D01*
X993329Y913540D01*
X993620Y913582D01*
X993912Y913499D01*
X994120Y913290D01*
G01X995595Y911457D02*
X995845Y911249D01*
X996137Y911124D01*
X996512Y911082D01*
X996887Y911165D01*
X997179Y911332D01*
X997387Y911624D01*
X997429Y911957D01*
X997345Y912290D01*
X997137Y912499D01*
X996845Y912665D01*
X996554Y912707D01*
X996262Y912665D01*
X995887Y912499D01*
X996012Y913582D01*
X997137D01*
G01X1006081Y901075D02*
Y897075D01*
X1013481D01*
G01X986379Y915082D02*
Y917582D01*
X987420D01*
X987754Y917457D01*
X987962Y917290D01*
X988045Y916957D01*
X987962Y916624D01*
X987712Y916415D01*
X987420Y916290D01*
X986379D01*
G01X987420D02*
X988045Y915082D01*
G01X990312D02*
Y917582D01*
X989812Y917082D01*
G01Y915082D02*
X990812D01*
G01X992620Y916124D02*
X992912Y916415D01*
X993162Y916582D01*
X993495Y916665D01*
X993787Y916582D01*
X993995Y916415D01*
X994162Y916165D01*
X994204Y915874D01*
X994162Y915624D01*
X993995Y915374D01*
X993745Y915165D01*
X993454Y915082D01*
X993120Y915165D01*
X992829Y915415D01*
X992662Y915790D01*
X992620Y916207D01*
X992704Y916749D01*
X992829Y917040D01*
X993037Y917332D01*
X993329Y917540D01*
X993620Y917582D01*
X993912Y917499D01*
X994120Y917290D01*
G01X995720Y916124D02*
X996012Y916415D01*
X996262Y916582D01*
X996595Y916665D01*
X996887Y916582D01*
X997095Y916415D01*
X997262Y916165D01*
X997304Y915874D01*
X997262Y915624D01*
X997095Y915374D01*
X996845Y915165D01*
X996554Y915082D01*
X996220Y915165D01*
X995929Y915415D01*
X995762Y915790D01*
X995720Y916207D01*
X995804Y916749D01*
X995929Y917040D01*
X996137Y917332D01*
X996429Y917540D01*
X996720Y917582D01*
X997012Y917499D01*
X997220Y917290D01*
G01X1013481Y901075D02*
Y905075D01*
X1006081D01*
G01X1023895Y909862D02*
Y912362D01*
X1024936D01*
X1025270Y912237D01*
X1025478Y912070D01*
X1025561Y911737D01*
X1025478Y911404D01*
X1025228Y911195D01*
X1024936Y911070D01*
X1023895D01*
G01X1024936D02*
X1025561Y909862D01*
G01X1027828D02*
Y912362D01*
X1027328Y911862D01*
G01Y909862D02*
X1028328D01*
G01X1030136Y910904D02*
X1030428Y911195D01*
X1030678Y911362D01*
X1031011Y911445D01*
X1031303Y911362D01*
X1031511Y911195D01*
X1031678Y910945D01*
X1031720Y910654D01*
X1031678Y910404D01*
X1031511Y910154D01*
X1031261Y909945D01*
X1030970Y909862D01*
X1030636Y909945D01*
X1030345Y910195D01*
X1030178Y910570D01*
X1030136Y910987D01*
X1030220Y911529D01*
X1030345Y911820D01*
X1030553Y912112D01*
X1030845Y912320D01*
X1031136Y912362D01*
X1031428Y912279D01*
X1031636Y912070D01*
G01X1033945Y909862D02*
X1034028Y910404D01*
X1034153Y910862D01*
X1034320Y911279D01*
X1034528Y911737D01*
X1034861Y912362D01*
X1033195D01*
G01X1016339Y898965D02*
Y894965D01*
X1023739D01*
G01X1023895Y913862D02*
Y916362D01*
X1024936D01*
X1025270Y916237D01*
X1025478Y916070D01*
X1025561Y915737D01*
X1025478Y915404D01*
X1025228Y915195D01*
X1024936Y915070D01*
X1023895D01*
G01X1024936D02*
X1025561Y913862D01*
G01X1027828D02*
Y916362D01*
X1027328Y915862D01*
G01Y913862D02*
X1028328D01*
G01X1030136Y914904D02*
X1030428Y915195D01*
X1030678Y915362D01*
X1031011Y915445D01*
X1031303Y915362D01*
X1031511Y915195D01*
X1031678Y914945D01*
X1031720Y914654D01*
X1031678Y914404D01*
X1031511Y914154D01*
X1031261Y913945D01*
X1030970Y913862D01*
X1030636Y913945D01*
X1030345Y914195D01*
X1030178Y914570D01*
X1030136Y914987D01*
X1030220Y915529D01*
X1030345Y915820D01*
X1030553Y916112D01*
X1030845Y916320D01*
X1031136Y916362D01*
X1031428Y916279D01*
X1031636Y916070D01*
G01X1034028Y913862D02*
X1034320Y913904D01*
X1034653Y914029D01*
X1034861Y914237D01*
X1034945Y914529D01*
X1034861Y914820D01*
X1034611Y915070D01*
X1034236Y915195D01*
X1033820D01*
X1033570Y915279D01*
X1033361Y915487D01*
X1033278Y915779D01*
X1033403Y916070D01*
X1033695Y916279D01*
X1034028Y916362D01*
X1034361Y916279D01*
X1034653Y916070D01*
X1034778Y915779D01*
X1034695Y915487D01*
X1034486Y915279D01*
X1034236Y915195D01*
X1033820D01*
X1033445Y915070D01*
X1033195Y914820D01*
X1033111Y914529D01*
X1033195Y914237D01*
X1033403Y914029D01*
X1033736Y913904D01*
X1034028Y913862D01*
G01X1023739Y898965D02*
Y902965D01*
X1016339D01*
G01X1035500Y877017D02*
X1033000D01*
Y878058D01*
X1033125Y878392D01*
X1033292Y878600D01*
X1033625Y878683D01*
X1033958Y878600D01*
X1034167Y878350D01*
X1034292Y878058D01*
Y877017D01*
G01Y878058D02*
X1035500Y878683D01*
G01Y880950D02*
X1033000D01*
X1033500Y880450D01*
G01X1035500D02*
Y881450D01*
G01X1034458Y883258D02*
X1034167Y883550D01*
X1034000Y883800D01*
X1033917Y884133D01*
X1034000Y884425D01*
X1034167Y884633D01*
X1034417Y884800D01*
X1034708Y884842D01*
X1034958Y884800D01*
X1035208Y884633D01*
X1035417Y884383D01*
X1035500Y884092D01*
X1035417Y883758D01*
X1035167Y883467D01*
X1034792Y883300D01*
X1034375Y883258D01*
X1033833Y883342D01*
X1033542Y883467D01*
X1033250Y883675D01*
X1033042Y883967D01*
X1033000Y884258D01*
X1033083Y884550D01*
X1033292Y884758D01*
G01X1035208Y886442D02*
X1035417Y886733D01*
X1035500Y887067D01*
X1035417Y887400D01*
X1035167Y887692D01*
X1034792Y887900D01*
X1034417Y887983D01*
X1033958D01*
X1033583Y887900D01*
X1033250Y887692D01*
X1033083Y887442D01*
X1033000Y887150D01*
X1033083Y886817D01*
X1033250Y886567D01*
X1033500Y886400D01*
X1033833Y886317D01*
X1034125Y886400D01*
X1034417Y886608D01*
X1034583Y886858D01*
X1034625Y887150D01*
X1034542Y887483D01*
X1034333Y887733D01*
X1033958Y887983D01*
G01X1032515Y888681D02*
X1028515D01*
Y881281D01*
G01X1038500Y893017D02*
X1036000D01*
Y894058D01*
X1036125Y894392D01*
X1036292Y894600D01*
X1036625Y894683D01*
X1036958Y894600D01*
X1037167Y894350D01*
X1037292Y894058D01*
Y893017D01*
G01Y894058D02*
X1038500Y894683D01*
G01Y896950D02*
X1036000D01*
X1036500Y896450D01*
G01X1038500D02*
Y897450D01*
G01Y899967D02*
X1037958Y900050D01*
X1037500Y900175D01*
X1037083Y900342D01*
X1036625Y900550D01*
X1036000Y900883D01*
Y899217D01*
G01Y903150D02*
X1036083Y902817D01*
X1036292Y902567D01*
X1036542Y902400D01*
X1036875Y902275D01*
X1037250Y902233D01*
X1037625Y902275D01*
X1037958Y902400D01*
X1038208Y902567D01*
X1038417Y902817D01*
X1038500Y903150D01*
X1038417Y903483D01*
X1038208Y903733D01*
X1037958Y903900D01*
X1037625Y904025D01*
X1037250Y904067D01*
X1036875Y904025D01*
X1036542Y903900D01*
X1036292Y903733D01*
X1036083Y903483D01*
X1036000Y903150D01*
G01X1035315Y896281D02*
X1031315D01*
Y888881D01*
G01X1045000Y881617D02*
X1042500D01*
Y882658D01*
X1042625Y882992D01*
X1042792Y883200D01*
X1043125Y883283D01*
X1043458Y883200D01*
X1043667Y882950D01*
X1043792Y882658D01*
Y881617D01*
G01Y882658D02*
X1045000Y883283D01*
G01X1044500Y884633D02*
X1044792Y884883D01*
X1044958Y885217D01*
X1045000Y885592D01*
X1044958Y885925D01*
X1044750Y886258D01*
X1044500Y886467D01*
X1044250Y886508D01*
X1043958Y886425D01*
X1043750Y886133D01*
X1043667Y885842D01*
Y885467D01*
G01Y885842D02*
X1043542Y886092D01*
X1043333Y886300D01*
X1043083Y886383D01*
X1042833Y886300D01*
X1042625Y886092D01*
X1042500Y885717D01*
X1042542Y885342D01*
X1042708Y884967D01*
G01X1041500Y888700D02*
X1037500D01*
Y881300D01*
G01X1049000Y902117D02*
X1046500D01*
Y903158D01*
X1046625Y903492D01*
X1046792Y903700D01*
X1047125Y903783D01*
X1047458Y903700D01*
X1047667Y903450D01*
X1047792Y903158D01*
Y902117D01*
G01Y903158D02*
X1049000Y903783D01*
G01X1048708Y905342D02*
X1048917Y905633D01*
X1049000Y905967D01*
X1048917Y906300D01*
X1048667Y906592D01*
X1048292Y906800D01*
X1047917Y906883D01*
X1047458D01*
X1047083Y906800D01*
X1046750Y906592D01*
X1046583Y906342D01*
X1046500Y906050D01*
X1046583Y905717D01*
X1046750Y905467D01*
X1047000Y905300D01*
X1047333Y905217D01*
X1047625Y905300D01*
X1047917Y905508D01*
X1048083Y905758D01*
X1048125Y906050D01*
X1048042Y906383D01*
X1047833Y906633D01*
X1047458Y906883D01*
G01X1057500Y895700D02*
X1053500D01*
Y888300D01*
G01X1045000Y902117D02*
X1042500D01*
Y903158D01*
X1042625Y903492D01*
X1042792Y903700D01*
X1043125Y903783D01*
X1043458Y903700D01*
X1043667Y903450D01*
X1043792Y903158D01*
Y902117D01*
G01Y903158D02*
X1045000Y903783D01*
G01Y906050D02*
X1044958Y906342D01*
X1044833Y906675D01*
X1044625Y906883D01*
X1044333Y906967D01*
X1044042Y906883D01*
X1043792Y906633D01*
X1043667Y906258D01*
Y905842D01*
X1043583Y905592D01*
X1043375Y905383D01*
X1043083Y905300D01*
X1042792Y905425D01*
X1042583Y905717D01*
X1042500Y906050D01*
X1042583Y906383D01*
X1042792Y906675D01*
X1043083Y906800D01*
X1043375Y906717D01*
X1043583Y906508D01*
X1043667Y906258D01*
Y905842D01*
X1043792Y905467D01*
X1044042Y905217D01*
X1044333Y905133D01*
X1044625Y905217D01*
X1044833Y905425D01*
X1044958Y905758D01*
X1045000Y906050D01*
G01X1050000Y895700D02*
X1046000D01*
Y888300D01*
G01X999000Y920017D02*
X996500D01*
Y921058D01*
X996625Y921392D01*
X996792Y921600D01*
X997125Y921683D01*
X997458Y921600D01*
X997667Y921350D01*
X997792Y921058D01*
Y920017D01*
G01Y921058D02*
X999000Y921683D01*
G01X998625Y923033D02*
X998833Y923283D01*
X998958Y923575D01*
X999000Y923950D01*
X998917Y924325D01*
X998750Y924617D01*
X998458Y924825D01*
X998125Y924867D01*
X997792Y924783D01*
X997583Y924575D01*
X997417Y924283D01*
X997375Y923992D01*
X997417Y923700D01*
X997583Y923325D01*
X996500Y923450D01*
Y924575D01*
G01Y927050D02*
X996583Y926717D01*
X996792Y926467D01*
X997042Y926300D01*
X997375Y926175D01*
X997750Y926133D01*
X998125Y926175D01*
X998458Y926300D01*
X998708Y926467D01*
X998917Y926717D01*
X999000Y927050D01*
X998917Y927383D01*
X998708Y927633D01*
X998458Y927800D01*
X998125Y927925D01*
X997750Y927967D01*
X997375Y927925D01*
X997042Y927800D01*
X996792Y927633D01*
X996583Y927383D01*
X996500Y927050D01*
G01X996917Y929358D02*
X996667Y929608D01*
X996542Y929900D01*
X996500Y930233D01*
X996583Y930650D01*
X996792Y930942D01*
X997042Y931025D01*
X997292Y930983D01*
X997500Y930817D01*
X997917Y929983D01*
X998208Y929608D01*
X998625Y929358D01*
X999000Y929275D01*
Y931025D01*
G01X998500Y905300D02*
X1002500D01*
Y912700D01*
G01X1019517Y942000D02*
Y944500D01*
X1020558D01*
X1020892Y944375D01*
X1021100Y944208D01*
X1021183Y943875D01*
X1021100Y943542D01*
X1020850Y943333D01*
X1020558Y943208D01*
X1019517D01*
G01X1020558D02*
X1021183Y942000D01*
G01X1023950D02*
Y944500D01*
X1022408Y942708D01*
X1024492D01*
G01X1025842Y942292D02*
X1026133Y942083D01*
X1026467Y942000D01*
X1026800Y942083D01*
X1027092Y942333D01*
X1027300Y942708D01*
X1027383Y943083D01*
Y943542D01*
X1027300Y943917D01*
X1027092Y944250D01*
X1026842Y944417D01*
X1026550Y944500D01*
X1026217Y944417D01*
X1025967Y944250D01*
X1025800Y944000D01*
X1025717Y943667D01*
X1025800Y943375D01*
X1026008Y943083D01*
X1026258Y942917D01*
X1026550Y942875D01*
X1026883Y942958D01*
X1027133Y943167D01*
X1027383Y943542D01*
G01X1029567Y942000D02*
X1029650Y942542D01*
X1029775Y943000D01*
X1029942Y943417D01*
X1030150Y943875D01*
X1030483Y944500D01*
X1028817D01*
G01X1029474Y937306D02*
Y941306D01*
X1022074D01*
G01X1003000Y920517D02*
X1000500D01*
Y921558D01*
X1000625Y921892D01*
X1000792Y922100D01*
X1001125Y922183D01*
X1001458Y922100D01*
X1001667Y921850D01*
X1001792Y921558D01*
Y920517D01*
G01Y921558D02*
X1003000Y922183D01*
G01Y924950D02*
X1000500D01*
X1002292Y923408D01*
Y925492D01*
G01X1002708Y926842D02*
X1002917Y927133D01*
X1003000Y927467D01*
X1002917Y927800D01*
X1002667Y928092D01*
X1002292Y928300D01*
X1001917Y928383D01*
X1001458D01*
X1001083Y928300D01*
X1000750Y928092D01*
X1000583Y927842D01*
X1000500Y927550D01*
X1000583Y927217D01*
X1000750Y926967D01*
X1001000Y926800D01*
X1001333Y926717D01*
X1001625Y926800D01*
X1001917Y927008D01*
X1002083Y927258D01*
X1002125Y927550D01*
X1002042Y927883D01*
X1001833Y928133D01*
X1001458Y928383D01*
G01X1003000Y931150D02*
X1000500D01*
X1002292Y929608D01*
Y931692D01*
G01X1003500Y905300D02*
X1007500D01*
Y912700D01*
G01X965800Y865783D02*
X967592D01*
X967967Y865950D01*
X968217Y866283D01*
X968300Y866700D01*
X968217Y867117D01*
X967967Y867450D01*
X967592Y867617D01*
X965800D01*
G01X968300Y869800D02*
X965800D01*
X966300Y869300D01*
G01X968300D02*
Y870300D01*
G01X965800Y872900D02*
X965883Y872567D01*
X966092Y872317D01*
X966342Y872150D01*
X966675Y872025D01*
X967050Y871983D01*
X967425Y872025D01*
X967758Y872150D01*
X968008Y872317D01*
X968217Y872567D01*
X968300Y872900D01*
X968217Y873233D01*
X968008Y873483D01*
X967758Y873650D01*
X967425Y873775D01*
X967050Y873817D01*
X966675Y873775D01*
X966342Y873650D01*
X966092Y873483D01*
X965883Y873233D01*
X965800Y872900D01*
G01X964570Y879130D02*
Y865130D01*
G01X1001900Y867230D02*
X999700Y865030D01*
G01X1001900Y867230D02*
X999700Y869430D01*
G01Y874230D02*
Y860230D01*
G01X1021200D02*
X1000400D01*
G01X1021200Y874230D02*
Y860230D01*
G01X999700Y874230D02*
X1021200D01*
G01X1012900Y937500D02*
X1012567Y937542D01*
X1012275Y937708D01*
X1012025Y937958D01*
X1011858Y938250D01*
X1011775Y938583D01*
Y938917D01*
X1011858Y939250D01*
X1012025Y939542D01*
X1012275Y939792D01*
X1012567Y939958D01*
X1012900Y940000D01*
X1013233Y939958D01*
X1013525Y939792D01*
X1013775Y939542D01*
X1013942Y939250D01*
X1014025Y938917D01*
Y938583D01*
X1013942Y938250D01*
X1013775Y937958D01*
X1013525Y937708D01*
X1013233Y937542D01*
X1012900Y937500D01*
G01X1013233Y938167D02*
X1013733Y937500D01*
G01X1015208Y939583D02*
X1015458Y939833D01*
X1015750Y939958D01*
X1016083Y940000D01*
X1016500Y939917D01*
X1016792Y939708D01*
X1016875Y939458D01*
X1016833Y939208D01*
X1016667Y939000D01*
X1015833Y938583D01*
X1015458Y938292D01*
X1015208Y937875D01*
X1015125Y937500D01*
X1016875D01*
G01X1018183Y937875D02*
X1018433Y937667D01*
X1018725Y937542D01*
X1019100Y937500D01*
X1019475Y937583D01*
X1019767Y937750D01*
X1019975Y938042D01*
X1020017Y938375D01*
X1019933Y938708D01*
X1019725Y938917D01*
X1019433Y939083D01*
X1019142Y939125D01*
X1018850Y939083D01*
X1018475Y938917D01*
X1018600Y940000D01*
X1019725D01*
G01X1027757Y936250D02*
X1013757D01*
G01X1027757Y923250D02*
Y936250D01*
G01X1013757Y923250D02*
X1027757D01*
G01X1013757Y936250D02*
Y923250D01*
G01X1007500Y921400D02*
X1007458Y921067D01*
X1007292Y920775D01*
X1007042Y920525D01*
X1006750Y920358D01*
X1006417Y920275D01*
X1006083D01*
X1005750Y920358D01*
X1005458Y920525D01*
X1005208Y920775D01*
X1005042Y921067D01*
X1005000Y921400D01*
X1005042Y921733D01*
X1005208Y922025D01*
X1005458Y922275D01*
X1005750Y922442D01*
X1006083Y922525D01*
X1006417D01*
X1006750Y922442D01*
X1007042Y922275D01*
X1007292Y922025D01*
X1007458Y921733D01*
X1007500Y921400D01*
G01X1006833Y921733D02*
X1007500Y922233D01*
G01X1005417Y923708D02*
X1005167Y923958D01*
X1005042Y924250D01*
X1005000Y924583D01*
X1005083Y925000D01*
X1005292Y925292D01*
X1005542Y925375D01*
X1005792Y925333D01*
X1006000Y925167D01*
X1006417Y924333D01*
X1006708Y923958D01*
X1007125Y923708D01*
X1007500Y923625D01*
Y925375D01*
G01Y927600D02*
X1005000D01*
X1005500Y927100D01*
G01X1007500D02*
Y928100D01*
G01X1022500Y907500D02*
Y921500D01*
G01X1009500Y907500D02*
X1022500D01*
G01X1009500Y921500D02*
Y907500D01*
G01X1022500Y921500D02*
X1009500D01*
G01X1004967Y1111500D02*
Y1114000D01*
X1006008D01*
X1006342Y1113875D01*
X1006550Y1113708D01*
X1006633Y1113375D01*
X1006550Y1113042D01*
X1006300Y1112833D01*
X1006008Y1112708D01*
X1004967D01*
G01X1006008D02*
X1006633Y1111500D01*
G01X1008900D02*
Y1114000D01*
X1008400Y1113500D01*
G01Y1111500D02*
X1009400D01*
G01X1012000D02*
Y1114000D01*
X1011500Y1113500D01*
G01Y1111500D02*
X1012500D01*
G01X1015017D02*
X1015100Y1112042D01*
X1015225Y1112500D01*
X1015392Y1112917D01*
X1015600Y1113375D01*
X1015933Y1114000D01*
X1014267D01*
G01X1018200Y1111500D02*
X1018492Y1111542D01*
X1018825Y1111667D01*
X1019033Y1111875D01*
X1019117Y1112167D01*
X1019033Y1112458D01*
X1018783Y1112708D01*
X1018408Y1112833D01*
X1017992D01*
X1017742Y1112917D01*
X1017533Y1113125D01*
X1017450Y1113417D01*
X1017575Y1113708D01*
X1017867Y1113917D01*
X1018200Y1114000D01*
X1018533Y1113917D01*
X1018825Y1113708D01*
X1018950Y1113417D01*
X1018867Y1113125D01*
X1018658Y1112917D01*
X1018408Y1112833D01*
X1017992D01*
X1017617Y1112708D01*
X1017367Y1112458D01*
X1017283Y1112167D01*
X1017367Y1111875D01*
X1017575Y1111667D01*
X1017908Y1111542D01*
X1018200Y1111500D01*
G01X1005800Y1119500D02*
Y1115500D01*
X1013200D01*
G01X992208Y1113767D02*
X992083Y1113517D01*
X992000Y1113225D01*
Y1112892D01*
X992125Y1112517D01*
X992333Y1112225D01*
X992583Y1112017D01*
X993000Y1111850D01*
X993375Y1111808D01*
X993750Y1111892D01*
X994000Y1112017D01*
X994250Y1112267D01*
X994417Y1112558D01*
X994500Y1112850D01*
Y1113142D01*
X994417Y1113433D01*
X994292Y1113683D01*
X994125Y1113892D01*
G01X993458Y1115158D02*
X993167Y1115450D01*
X993000Y1115700D01*
X992917Y1116033D01*
X993000Y1116325D01*
X993167Y1116533D01*
X993417Y1116700D01*
X993708Y1116742D01*
X993958Y1116700D01*
X994208Y1116533D01*
X994417Y1116283D01*
X994500Y1115992D01*
X994417Y1115658D01*
X994167Y1115367D01*
X993792Y1115200D01*
X993375Y1115158D01*
X992833Y1115242D01*
X992542Y1115367D01*
X992250Y1115575D01*
X992042Y1115867D01*
X992000Y1116158D01*
X992083Y1116450D01*
X992292Y1116658D01*
G01X994500Y1119050D02*
X994458Y1119342D01*
X994333Y1119675D01*
X994125Y1119883D01*
X993833Y1119967D01*
X993542Y1119883D01*
X993292Y1119633D01*
X993167Y1119258D01*
Y1118842D01*
X993083Y1118592D01*
X992875Y1118383D01*
X992583Y1118300D01*
X992292Y1118425D01*
X992083Y1118717D01*
X992000Y1119050D01*
X992083Y1119383D01*
X992292Y1119675D01*
X992583Y1119800D01*
X992875Y1119717D01*
X993083Y1119508D01*
X993167Y1119258D01*
Y1118842D01*
X993292Y1118467D01*
X993542Y1118217D01*
X993833Y1118133D01*
X994125Y1118217D01*
X994333Y1118425D01*
X994458Y1118758D01*
X994500Y1119050D01*
G01X994208Y1121442D02*
X994417Y1121733D01*
X994500Y1122067D01*
X994417Y1122400D01*
X994167Y1122692D01*
X993792Y1122900D01*
X993417Y1122983D01*
X992958D01*
X992583Y1122900D01*
X992250Y1122692D01*
X992083Y1122442D01*
X992000Y1122150D01*
X992083Y1121817D01*
X992250Y1121567D01*
X992500Y1121400D01*
X992833Y1121317D01*
X993125Y1121400D01*
X993417Y1121608D01*
X993583Y1121858D01*
X993625Y1122150D01*
X993542Y1122483D01*
X993333Y1122733D01*
X992958Y1122983D01*
G01X1000967Y1133000D02*
Y1135500D01*
X1002008D01*
X1002342Y1135375D01*
X1002550Y1135208D01*
X1002633Y1134875D01*
X1002550Y1134542D01*
X1002300Y1134333D01*
X1002008Y1134208D01*
X1000967D01*
G01X1002008D02*
X1002633Y1133000D01*
G01X1004900D02*
Y1135500D01*
X1004400Y1135000D01*
G01Y1133000D02*
X1005400D01*
G01X1008000D02*
Y1135500D01*
X1007500Y1135000D01*
G01Y1133000D02*
X1008500D01*
G01X1011017D02*
X1011100Y1133542D01*
X1011225Y1134000D01*
X1011392Y1134417D01*
X1011600Y1134875D01*
X1011933Y1135500D01*
X1010267D01*
G01X1013283Y1133500D02*
X1013533Y1133208D01*
X1013867Y1133042D01*
X1014242Y1133000D01*
X1014575Y1133042D01*
X1014908Y1133250D01*
X1015117Y1133500D01*
X1015158Y1133750D01*
X1015075Y1134042D01*
X1014783Y1134250D01*
X1014492Y1134333D01*
X1014117D01*
G01X1014492D02*
X1014742Y1134458D01*
X1014950Y1134667D01*
X1015033Y1134917D01*
X1014950Y1135167D01*
X1014742Y1135375D01*
X1014367Y1135500D01*
X1013992Y1135458D01*
X1013617Y1135292D01*
G01X968767Y1190292D02*
X968517Y1190417D01*
X968225Y1190500D01*
X967892D01*
X967517Y1190375D01*
X967225Y1190167D01*
X967017Y1189917D01*
X966850Y1189500D01*
X966808Y1189125D01*
X966892Y1188750D01*
X967017Y1188500D01*
X967267Y1188250D01*
X967558Y1188083D01*
X967850Y1188000D01*
X968142D01*
X968433Y1188083D01*
X968683Y1188208D01*
X968892Y1188375D01*
G01X970158Y1189042D02*
X970450Y1189333D01*
X970700Y1189500D01*
X971033Y1189583D01*
X971325Y1189500D01*
X971533Y1189333D01*
X971700Y1189083D01*
X971742Y1188792D01*
X971700Y1188542D01*
X971533Y1188292D01*
X971283Y1188083D01*
X970992Y1188000D01*
X970658Y1188083D01*
X970367Y1188333D01*
X970200Y1188708D01*
X970158Y1189125D01*
X970242Y1189667D01*
X970367Y1189958D01*
X970575Y1190250D01*
X970867Y1190458D01*
X971158Y1190500D01*
X971450Y1190417D01*
X971658Y1190208D01*
G01X974050Y1188000D02*
Y1190500D01*
X973550Y1190000D01*
G01Y1188000D02*
X974550D01*
G01X976358Y1189042D02*
X976650Y1189333D01*
X976900Y1189500D01*
X977233Y1189583D01*
X977525Y1189500D01*
X977733Y1189333D01*
X977900Y1189083D01*
X977942Y1188792D01*
X977900Y1188542D01*
X977733Y1188292D01*
X977483Y1188083D01*
X977192Y1188000D01*
X976858Y1188083D01*
X976567Y1188333D01*
X976400Y1188708D01*
X976358Y1189125D01*
X976442Y1189667D01*
X976567Y1189958D01*
X976775Y1190250D01*
X977067Y1190458D01*
X977358Y1190500D01*
X977650Y1190417D01*
X977858Y1190208D01*
G01X985467Y1224000D02*
Y1226500D01*
X986508D01*
X986842Y1226375D01*
X987050Y1226208D01*
X987133Y1225875D01*
X987050Y1225542D01*
X986800Y1225333D01*
X986508Y1225208D01*
X985467D01*
G01X986508D02*
X987133Y1224000D01*
G01X989400D02*
Y1226500D01*
X988900Y1226000D01*
G01Y1224000D02*
X989900D01*
G01X992500Y1226500D02*
X992167Y1226417D01*
X991917Y1226208D01*
X991750Y1225958D01*
X991625Y1225625D01*
X991583Y1225250D01*
X991625Y1224875D01*
X991750Y1224542D01*
X991917Y1224292D01*
X992167Y1224083D01*
X992500Y1224000D01*
X992833Y1224083D01*
X993083Y1224292D01*
X993250Y1224542D01*
X993375Y1224875D01*
X993417Y1225250D01*
X993375Y1225625D01*
X993250Y1225958D01*
X993083Y1226208D01*
X992833Y1226417D01*
X992500Y1226500D01*
G01X995600Y1224000D02*
X995892Y1224042D01*
X996225Y1224167D01*
X996433Y1224375D01*
X996517Y1224667D01*
X996433Y1224958D01*
X996183Y1225208D01*
X995808Y1225333D01*
X995392D01*
X995142Y1225417D01*
X994933Y1225625D01*
X994850Y1225917D01*
X994975Y1226208D01*
X995267Y1226417D01*
X995600Y1226500D01*
X995933Y1226417D01*
X996225Y1226208D01*
X996350Y1225917D01*
X996267Y1225625D01*
X996058Y1225417D01*
X995808Y1225333D01*
X995392D01*
X995017Y1225208D01*
X994767Y1224958D01*
X994683Y1224667D01*
X994767Y1224375D01*
X994975Y1224167D01*
X995308Y1224042D01*
X995600Y1224000D01*
G01X997908Y1225042D02*
X998200Y1225333D01*
X998450Y1225500D01*
X998783Y1225583D01*
X999075Y1225500D01*
X999283Y1225333D01*
X999450Y1225083D01*
X999492Y1224792D01*
X999450Y1224542D01*
X999283Y1224292D01*
X999033Y1224083D01*
X998742Y1224000D01*
X998408Y1224083D01*
X998117Y1224333D01*
X997950Y1224708D01*
X997908Y1225125D01*
X997992Y1225667D01*
X998117Y1225958D01*
X998325Y1226250D01*
X998617Y1226458D01*
X998908Y1226500D01*
X999200Y1226417D01*
X999408Y1226208D01*
G01X981200Y1223000D02*
Y1227000D01*
X973800D01*
G01X985467Y1204000D02*
Y1206500D01*
X986508D01*
X986842Y1206375D01*
X987050Y1206208D01*
X987133Y1205875D01*
X987050Y1205542D01*
X986800Y1205333D01*
X986508Y1205208D01*
X985467D01*
G01X986508D02*
X987133Y1204000D01*
G01X989400D02*
Y1206500D01*
X988900Y1206000D01*
G01Y1204000D02*
X989900D01*
G01X992500Y1206500D02*
X992167Y1206417D01*
X991917Y1206208D01*
X991750Y1205958D01*
X991625Y1205625D01*
X991583Y1205250D01*
X991625Y1204875D01*
X991750Y1204542D01*
X991917Y1204292D01*
X992167Y1204083D01*
X992500Y1204000D01*
X992833Y1204083D01*
X993083Y1204292D01*
X993250Y1204542D01*
X993375Y1204875D01*
X993417Y1205250D01*
X993375Y1205625D01*
X993250Y1205958D01*
X993083Y1206208D01*
X992833Y1206417D01*
X992500Y1206500D01*
G01X995600Y1204000D02*
X995892Y1204042D01*
X996225Y1204167D01*
X996433Y1204375D01*
X996517Y1204667D01*
X996433Y1204958D01*
X996183Y1205208D01*
X995808Y1205333D01*
X995392D01*
X995142Y1205417D01*
X994933Y1205625D01*
X994850Y1205917D01*
X994975Y1206208D01*
X995267Y1206417D01*
X995600Y1206500D01*
X995933Y1206417D01*
X996225Y1206208D01*
X996350Y1205917D01*
X996267Y1205625D01*
X996058Y1205417D01*
X995808Y1205333D01*
X995392D01*
X995017Y1205208D01*
X994767Y1204958D01*
X994683Y1204667D01*
X994767Y1204375D01*
X994975Y1204167D01*
X995308Y1204042D01*
X995600Y1204000D01*
G01X998617D02*
X998700Y1204542D01*
X998825Y1205000D01*
X998992Y1205417D01*
X999200Y1205875D01*
X999533Y1206500D01*
X997867D01*
G01X981200Y1203000D02*
Y1207000D01*
X973800D01*
G01X985467Y1200000D02*
Y1202500D01*
X986508D01*
X986842Y1202375D01*
X987050Y1202208D01*
X987133Y1201875D01*
X987050Y1201542D01*
X986800Y1201333D01*
X986508Y1201208D01*
X985467D01*
G01X986508D02*
X987133Y1200000D01*
G01X989400D02*
Y1202500D01*
X988900Y1202000D01*
G01Y1200000D02*
X989900D01*
G01X992500Y1202500D02*
X992167Y1202417D01*
X991917Y1202208D01*
X991750Y1201958D01*
X991625Y1201625D01*
X991583Y1201250D01*
X991625Y1200875D01*
X991750Y1200542D01*
X991917Y1200292D01*
X992167Y1200083D01*
X992500Y1200000D01*
X992833Y1200083D01*
X993083Y1200292D01*
X993250Y1200542D01*
X993375Y1200875D01*
X993417Y1201250D01*
X993375Y1201625D01*
X993250Y1201958D01*
X993083Y1202208D01*
X992833Y1202417D01*
X992500Y1202500D01*
G01X995600Y1200000D02*
X995892Y1200042D01*
X996225Y1200167D01*
X996433Y1200375D01*
X996517Y1200667D01*
X996433Y1200958D01*
X996183Y1201208D01*
X995808Y1201333D01*
X995392D01*
X995142Y1201417D01*
X994933Y1201625D01*
X994850Y1201917D01*
X994975Y1202208D01*
X995267Y1202417D01*
X995600Y1202500D01*
X995933Y1202417D01*
X996225Y1202208D01*
X996350Y1201917D01*
X996267Y1201625D01*
X996058Y1201417D01*
X995808Y1201333D01*
X995392D01*
X995017Y1201208D01*
X994767Y1200958D01*
X994683Y1200667D01*
X994767Y1200375D01*
X994975Y1200167D01*
X995308Y1200042D01*
X995600Y1200000D01*
G01X998700D02*
X998992Y1200042D01*
X999325Y1200167D01*
X999533Y1200375D01*
X999617Y1200667D01*
X999533Y1200958D01*
X999283Y1201208D01*
X998908Y1201333D01*
X998492D01*
X998242Y1201417D01*
X998033Y1201625D01*
X997950Y1201917D01*
X998075Y1202208D01*
X998367Y1202417D01*
X998700Y1202500D01*
X999033Y1202417D01*
X999325Y1202208D01*
X999450Y1201917D01*
X999367Y1201625D01*
X999158Y1201417D01*
X998908Y1201333D01*
X998492D01*
X998117Y1201208D01*
X997867Y1200958D01*
X997783Y1200667D01*
X997867Y1200375D01*
X998075Y1200167D01*
X998408Y1200042D01*
X998700Y1200000D01*
G01X973800Y1203000D02*
Y1199000D01*
X981200D01*
G01X985467Y1196000D02*
Y1198500D01*
X986508D01*
X986842Y1198375D01*
X987050Y1198208D01*
X987133Y1197875D01*
X987050Y1197542D01*
X986800Y1197333D01*
X986508Y1197208D01*
X985467D01*
G01X986508D02*
X987133Y1196000D01*
G01X989400D02*
Y1198500D01*
X988900Y1198000D01*
G01Y1196000D02*
X989900D01*
G01X992500Y1198500D02*
X992167Y1198417D01*
X991917Y1198208D01*
X991750Y1197958D01*
X991625Y1197625D01*
X991583Y1197250D01*
X991625Y1196875D01*
X991750Y1196542D01*
X991917Y1196292D01*
X992167Y1196083D01*
X992500Y1196000D01*
X992833Y1196083D01*
X993083Y1196292D01*
X993250Y1196542D01*
X993375Y1196875D01*
X993417Y1197250D01*
X993375Y1197625D01*
X993250Y1197958D01*
X993083Y1198208D01*
X992833Y1198417D01*
X992500Y1198500D01*
G01X995600Y1196000D02*
X995892Y1196042D01*
X996225Y1196167D01*
X996433Y1196375D01*
X996517Y1196667D01*
X996433Y1196958D01*
X996183Y1197208D01*
X995808Y1197333D01*
X995392D01*
X995142Y1197417D01*
X994933Y1197625D01*
X994850Y1197917D01*
X994975Y1198208D01*
X995267Y1198417D01*
X995600Y1198500D01*
X995933Y1198417D01*
X996225Y1198208D01*
X996350Y1197917D01*
X996267Y1197625D01*
X996058Y1197417D01*
X995808Y1197333D01*
X995392D01*
X995017Y1197208D01*
X994767Y1196958D01*
X994683Y1196667D01*
X994767Y1196375D01*
X994975Y1196167D01*
X995308Y1196042D01*
X995600Y1196000D01*
G01X997992Y1196292D02*
X998283Y1196083D01*
X998617Y1196000D01*
X998950Y1196083D01*
X999242Y1196333D01*
X999450Y1196708D01*
X999533Y1197083D01*
Y1197542D01*
X999450Y1197917D01*
X999242Y1198250D01*
X998992Y1198417D01*
X998700Y1198500D01*
X998367Y1198417D01*
X998117Y1198250D01*
X997950Y1198000D01*
X997867Y1197667D01*
X997950Y1197375D01*
X998158Y1197083D01*
X998408Y1196917D01*
X998700Y1196875D01*
X999033Y1196958D01*
X999283Y1197167D01*
X999533Y1197542D01*
G01X973800Y1199000D02*
Y1195000D01*
X981200D01*
G01X985467Y1208000D02*
Y1210500D01*
X986508D01*
X986842Y1210375D01*
X987050Y1210208D01*
X987133Y1209875D01*
X987050Y1209542D01*
X986800Y1209333D01*
X986508Y1209208D01*
X985467D01*
G01X986508D02*
X987133Y1208000D01*
G01X989400D02*
Y1210500D01*
X988900Y1210000D01*
G01Y1208000D02*
X989900D01*
G01X992500Y1210500D02*
X992167Y1210417D01*
X991917Y1210208D01*
X991750Y1209958D01*
X991625Y1209625D01*
X991583Y1209250D01*
X991625Y1208875D01*
X991750Y1208542D01*
X991917Y1208292D01*
X992167Y1208083D01*
X992500Y1208000D01*
X992833Y1208083D01*
X993083Y1208292D01*
X993250Y1208542D01*
X993375Y1208875D01*
X993417Y1209250D01*
X993375Y1209625D01*
X993250Y1209958D01*
X993083Y1210208D01*
X992833Y1210417D01*
X992500Y1210500D01*
G01X994892Y1208292D02*
X995183Y1208083D01*
X995517Y1208000D01*
X995850Y1208083D01*
X996142Y1208333D01*
X996350Y1208708D01*
X996433Y1209083D01*
Y1209542D01*
X996350Y1209917D01*
X996142Y1210250D01*
X995892Y1210417D01*
X995600Y1210500D01*
X995267Y1210417D01*
X995017Y1210250D01*
X994850Y1210000D01*
X994767Y1209667D01*
X994850Y1209375D01*
X995058Y1209083D01*
X995308Y1208917D01*
X995600Y1208875D01*
X995933Y1208958D01*
X996183Y1209167D01*
X996433Y1209542D01*
G01X998700Y1210500D02*
X998367Y1210417D01*
X998117Y1210208D01*
X997950Y1209958D01*
X997825Y1209625D01*
X997783Y1209250D01*
X997825Y1208875D01*
X997950Y1208542D01*
X998117Y1208292D01*
X998367Y1208083D01*
X998700Y1208000D01*
X999033Y1208083D01*
X999283Y1208292D01*
X999450Y1208542D01*
X999575Y1208875D01*
X999617Y1209250D01*
X999575Y1209625D01*
X999450Y1209958D01*
X999283Y1210208D01*
X999033Y1210417D01*
X998700Y1210500D01*
G01X973800Y1211000D02*
Y1207000D01*
X981200D01*
G01X985467Y1216000D02*
Y1218500D01*
X986508D01*
X986842Y1218375D01*
X987050Y1218208D01*
X987133Y1217875D01*
X987050Y1217542D01*
X986800Y1217333D01*
X986508Y1217208D01*
X985467D01*
G01X986508D02*
X987133Y1216000D01*
G01X989400D02*
Y1218500D01*
X988900Y1218000D01*
G01Y1216000D02*
X989900D01*
G01X992500Y1218500D02*
X992167Y1218417D01*
X991917Y1218208D01*
X991750Y1217958D01*
X991625Y1217625D01*
X991583Y1217250D01*
X991625Y1216875D01*
X991750Y1216542D01*
X991917Y1216292D01*
X992167Y1216083D01*
X992500Y1216000D01*
X992833Y1216083D01*
X993083Y1216292D01*
X993250Y1216542D01*
X993375Y1216875D01*
X993417Y1217250D01*
X993375Y1217625D01*
X993250Y1217958D01*
X993083Y1218208D01*
X992833Y1218417D01*
X992500Y1218500D01*
G01X994892Y1216292D02*
X995183Y1216083D01*
X995517Y1216000D01*
X995850Y1216083D01*
X996142Y1216333D01*
X996350Y1216708D01*
X996433Y1217083D01*
Y1217542D01*
X996350Y1217917D01*
X996142Y1218250D01*
X995892Y1218417D01*
X995600Y1218500D01*
X995267Y1218417D01*
X995017Y1218250D01*
X994850Y1218000D01*
X994767Y1217667D01*
X994850Y1217375D01*
X995058Y1217083D01*
X995308Y1216917D01*
X995600Y1216875D01*
X995933Y1216958D01*
X996183Y1217167D01*
X996433Y1217542D01*
G01X998700Y1216000D02*
Y1218500D01*
X998200Y1218000D01*
G01Y1216000D02*
X999200D01*
G01X973800Y1219000D02*
Y1215000D01*
X981200D01*
G01X968500Y1235967D02*
X966000D01*
Y1237008D01*
X966125Y1237342D01*
X966292Y1237550D01*
X966625Y1237633D01*
X966958Y1237550D01*
X967167Y1237300D01*
X967292Y1237008D01*
Y1235967D01*
G01Y1237008D02*
X968500Y1237633D01*
G01Y1239900D02*
X966000D01*
X966500Y1239400D01*
G01X968500D02*
Y1240400D01*
G01X966000Y1243000D02*
X966083Y1242667D01*
X966292Y1242417D01*
X966542Y1242250D01*
X966875Y1242125D01*
X967250Y1242083D01*
X967625Y1242125D01*
X967958Y1242250D01*
X968208Y1242417D01*
X968417Y1242667D01*
X968500Y1243000D01*
X968417Y1243333D01*
X968208Y1243583D01*
X967958Y1243750D01*
X967625Y1243875D01*
X967250Y1243917D01*
X966875Y1243875D01*
X966542Y1243750D01*
X966292Y1243583D01*
X966083Y1243333D01*
X966000Y1243000D01*
G01X968208Y1245392D02*
X968417Y1245683D01*
X968500Y1246017D01*
X968417Y1246350D01*
X968167Y1246642D01*
X967792Y1246850D01*
X967417Y1246933D01*
X966958D01*
X966583Y1246850D01*
X966250Y1246642D01*
X966083Y1246392D01*
X966000Y1246100D01*
X966083Y1245767D01*
X966250Y1245517D01*
X966500Y1245350D01*
X966833Y1245267D01*
X967125Y1245350D01*
X967417Y1245558D01*
X967583Y1245808D01*
X967625Y1246100D01*
X967542Y1246433D01*
X967333Y1246683D01*
X966958Y1246933D01*
G01X968500Y1249700D02*
X966000D01*
X967792Y1248158D01*
Y1250242D01*
G01X969500Y1231700D02*
X965500D01*
Y1224300D01*
G01X964500Y1235967D02*
X962000D01*
Y1237008D01*
X962125Y1237342D01*
X962292Y1237550D01*
X962625Y1237633D01*
X962958Y1237550D01*
X963167Y1237300D01*
X963292Y1237008D01*
Y1235967D01*
G01Y1237008D02*
X964500Y1237633D01*
G01Y1239900D02*
X962000D01*
X962500Y1239400D01*
G01X964500D02*
Y1240400D01*
G01X962000Y1243000D02*
X962083Y1242667D01*
X962292Y1242417D01*
X962542Y1242250D01*
X962875Y1242125D01*
X963250Y1242083D01*
X963625Y1242125D01*
X963958Y1242250D01*
X964208Y1242417D01*
X964417Y1242667D01*
X964500Y1243000D01*
X964417Y1243333D01*
X964208Y1243583D01*
X963958Y1243750D01*
X963625Y1243875D01*
X963250Y1243917D01*
X962875Y1243875D01*
X962542Y1243750D01*
X962292Y1243583D01*
X962083Y1243333D01*
X962000Y1243000D01*
G01X964208Y1245392D02*
X964417Y1245683D01*
X964500Y1246017D01*
X964417Y1246350D01*
X964167Y1246642D01*
X963792Y1246850D01*
X963417Y1246933D01*
X962958D01*
X962583Y1246850D01*
X962250Y1246642D01*
X962083Y1246392D01*
X962000Y1246100D01*
X962083Y1245767D01*
X962250Y1245517D01*
X962500Y1245350D01*
X962833Y1245267D01*
X963125Y1245350D01*
X963417Y1245558D01*
X963583Y1245808D01*
X963625Y1246100D01*
X963542Y1246433D01*
X963333Y1246683D01*
X962958Y1246933D01*
G01X964125Y1248283D02*
X964333Y1248533D01*
X964458Y1248825D01*
X964500Y1249200D01*
X964417Y1249575D01*
X964250Y1249867D01*
X963958Y1250075D01*
X963625Y1250117D01*
X963292Y1250033D01*
X963083Y1249825D01*
X962917Y1249533D01*
X962875Y1249242D01*
X962917Y1248950D01*
X963083Y1248575D01*
X962000Y1248700D01*
Y1249825D01*
G01X965500Y1231700D02*
X961500D01*
Y1224300D01*
G01X985467Y1220000D02*
Y1222500D01*
X986508D01*
X986842Y1222375D01*
X987050Y1222208D01*
X987133Y1221875D01*
X987050Y1221542D01*
X986800Y1221333D01*
X986508Y1221208D01*
X985467D01*
G01X986508D02*
X987133Y1220000D01*
G01X989400D02*
Y1222500D01*
X988900Y1222000D01*
G01Y1220000D02*
X989900D01*
G01X992500D02*
Y1222500D01*
X992000Y1222000D01*
G01Y1220000D02*
X993000D01*
G01X995600D02*
X995892Y1220042D01*
X996225Y1220167D01*
X996433Y1220375D01*
X996517Y1220667D01*
X996433Y1220958D01*
X996183Y1221208D01*
X995808Y1221333D01*
X995392D01*
X995142Y1221417D01*
X994933Y1221625D01*
X994850Y1221917D01*
X994975Y1222208D01*
X995267Y1222417D01*
X995600Y1222500D01*
X995933Y1222417D01*
X996225Y1222208D01*
X996350Y1221917D01*
X996267Y1221625D01*
X996058Y1221417D01*
X995808Y1221333D01*
X995392D01*
X995017Y1221208D01*
X994767Y1220958D01*
X994683Y1220667D01*
X994767Y1220375D01*
X994975Y1220167D01*
X995308Y1220042D01*
X995600Y1220000D01*
G01X997783Y1220375D02*
X998033Y1220167D01*
X998325Y1220042D01*
X998700Y1220000D01*
X999075Y1220083D01*
X999367Y1220250D01*
X999575Y1220542D01*
X999617Y1220875D01*
X999533Y1221208D01*
X999325Y1221417D01*
X999033Y1221583D01*
X998742Y1221625D01*
X998450Y1221583D01*
X998075Y1221417D01*
X998200Y1222500D01*
X999325D01*
G01X981200Y1219000D02*
Y1223000D01*
X973800D01*
G01X985467Y1212000D02*
Y1214500D01*
X986508D01*
X986842Y1214375D01*
X987050Y1214208D01*
X987133Y1213875D01*
X987050Y1213542D01*
X986800Y1213333D01*
X986508Y1213208D01*
X985467D01*
G01X986508D02*
X987133Y1212000D01*
G01X989400D02*
Y1214500D01*
X988900Y1214000D01*
G01Y1212000D02*
X989900D01*
G01X992500D02*
Y1214500D01*
X992000Y1214000D01*
G01Y1212000D02*
X993000D01*
G01X994808Y1213042D02*
X995100Y1213333D01*
X995350Y1213500D01*
X995683Y1213583D01*
X995975Y1213500D01*
X996183Y1213333D01*
X996350Y1213083D01*
X996392Y1212792D01*
X996350Y1212542D01*
X996183Y1212292D01*
X995933Y1212083D01*
X995642Y1212000D01*
X995308Y1212083D01*
X995017Y1212333D01*
X994850Y1212708D01*
X994808Y1213125D01*
X994892Y1213667D01*
X995017Y1213958D01*
X995225Y1214250D01*
X995517Y1214458D01*
X995808Y1214500D01*
X996100Y1214417D01*
X996308Y1214208D01*
G01X998617Y1212000D02*
X998700Y1212542D01*
X998825Y1213000D01*
X998992Y1213417D01*
X999200Y1213875D01*
X999533Y1214500D01*
X997867D01*
G01X981200Y1211000D02*
Y1215000D01*
X973800D01*
G01X967950Y1207500D02*
X969950D01*
G01X960200Y1196550D02*
Y1193550D01*
G01X963850Y1195650D02*
X968850D01*
Y1200650D01*
G01X1028250Y1302900D02*
X1027917Y1302942D01*
X1027625Y1303108D01*
X1027375Y1303358D01*
X1027208Y1303650D01*
X1027125Y1303983D01*
Y1304317D01*
X1027208Y1304650D01*
X1027375Y1304942D01*
X1027625Y1305192D01*
X1027917Y1305358D01*
X1028250Y1305400D01*
X1028583Y1305358D01*
X1028875Y1305192D01*
X1029125Y1304942D01*
X1029292Y1304650D01*
X1029375Y1304317D01*
Y1303983D01*
X1029292Y1303650D01*
X1029125Y1303358D01*
X1028875Y1303108D01*
X1028583Y1302942D01*
X1028250Y1302900D01*
G01X1028583Y1303567D02*
X1029083Y1302900D01*
G01X1030558Y1304983D02*
X1030808Y1305233D01*
X1031100Y1305358D01*
X1031433Y1305400D01*
X1031850Y1305317D01*
X1032142Y1305108D01*
X1032225Y1304858D01*
X1032183Y1304608D01*
X1032017Y1304400D01*
X1031183Y1303983D01*
X1030808Y1303692D01*
X1030558Y1303275D01*
X1030475Y1302900D01*
X1032225D01*
G01X1034450Y1305400D02*
X1034117Y1305317D01*
X1033867Y1305108D01*
X1033700Y1304858D01*
X1033575Y1304525D01*
X1033533Y1304150D01*
X1033575Y1303775D01*
X1033700Y1303442D01*
X1033867Y1303192D01*
X1034117Y1302983D01*
X1034450Y1302900D01*
X1034783Y1302983D01*
X1035033Y1303192D01*
X1035200Y1303442D01*
X1035325Y1303775D01*
X1035367Y1304150D01*
X1035325Y1304525D01*
X1035200Y1304858D01*
X1035033Y1305108D01*
X1034783Y1305317D01*
X1034450Y1305400D01*
G01X1036633Y1303400D02*
X1036883Y1303108D01*
X1037217Y1302942D01*
X1037592Y1302900D01*
X1037925Y1302942D01*
X1038258Y1303150D01*
X1038467Y1303400D01*
X1038508Y1303650D01*
X1038425Y1303942D01*
X1038133Y1304150D01*
X1037842Y1304233D01*
X1037467D01*
G01X1037842D02*
X1038092Y1304358D01*
X1038300Y1304567D01*
X1038383Y1304817D01*
X1038300Y1305067D01*
X1038092Y1305275D01*
X1037717Y1305400D01*
X1037342Y1305358D01*
X1036967Y1305192D01*
G01X1032118Y1308589D02*
X1002118D01*
Y1331389D01*
X1032118D01*
Y1308589D01*
G01X1039068Y1331489D02*
X1044268D01*
G01X1039068Y1324489D02*
X1046868D01*
G01X1039068Y1331489D02*
Y1324489D01*
G01X1052468Y1331489D02*
X1043768D01*
G01X1052468Y1324489D02*
Y1331489D01*
G01X1046068Y1324489D02*
X1052468D01*
G01X967008Y1398967D02*
X966883Y1398717D01*
X966800Y1398425D01*
Y1398092D01*
X966925Y1397717D01*
X967133Y1397425D01*
X967383Y1397217D01*
X967800Y1397050D01*
X968175Y1397008D01*
X968550Y1397092D01*
X968800Y1397217D01*
X969050Y1397467D01*
X969217Y1397758D01*
X969300Y1398050D01*
Y1398342D01*
X969217Y1398633D01*
X969092Y1398883D01*
X968925Y1399092D01*
G01Y1400233D02*
X969133Y1400483D01*
X969258Y1400775D01*
X969300Y1401150D01*
X969217Y1401525D01*
X969050Y1401817D01*
X968758Y1402025D01*
X968425Y1402067D01*
X968092Y1401983D01*
X967883Y1401775D01*
X967717Y1401483D01*
X967675Y1401192D01*
X967717Y1400900D01*
X967883Y1400525D01*
X966800Y1400650D01*
Y1401775D01*
G01X968925Y1403333D02*
X969133Y1403583D01*
X969258Y1403875D01*
X969300Y1404250D01*
X969217Y1404625D01*
X969050Y1404917D01*
X968758Y1405125D01*
X968425Y1405167D01*
X968092Y1405083D01*
X967883Y1404875D01*
X967717Y1404583D01*
X967675Y1404292D01*
X967717Y1404000D01*
X967883Y1403625D01*
X966800Y1403750D01*
Y1404875D01*
G01X969300Y1407267D02*
X968758Y1407350D01*
X968300Y1407475D01*
X967883Y1407642D01*
X967425Y1407850D01*
X966800Y1408183D01*
Y1406517D01*
G01X1009708Y1402267D02*
X1009583Y1402017D01*
X1009500Y1401725D01*
Y1401392D01*
X1009625Y1401017D01*
X1009833Y1400725D01*
X1010083Y1400517D01*
X1010500Y1400350D01*
X1010875Y1400308D01*
X1011250Y1400392D01*
X1011500Y1400517D01*
X1011750Y1400767D01*
X1011917Y1401058D01*
X1012000Y1401350D01*
Y1401642D01*
X1011917Y1401933D01*
X1011792Y1402183D01*
X1011625Y1402392D01*
G01Y1403533D02*
X1011833Y1403783D01*
X1011958Y1404075D01*
X1012000Y1404450D01*
X1011917Y1404825D01*
X1011750Y1405117D01*
X1011458Y1405325D01*
X1011125Y1405367D01*
X1010792Y1405283D01*
X1010583Y1405075D01*
X1010417Y1404783D01*
X1010375Y1404492D01*
X1010417Y1404200D01*
X1010583Y1403825D01*
X1009500Y1403950D01*
Y1405075D01*
G01X1011625Y1406633D02*
X1011833Y1406883D01*
X1011958Y1407175D01*
X1012000Y1407550D01*
X1011917Y1407925D01*
X1011750Y1408217D01*
X1011458Y1408425D01*
X1011125Y1408467D01*
X1010792Y1408383D01*
X1010583Y1408175D01*
X1010417Y1407883D01*
X1010375Y1407592D01*
X1010417Y1407300D01*
X1010583Y1406925D01*
X1009500Y1407050D01*
Y1408175D01*
G01X1012000Y1411150D02*
X1009500D01*
X1011292Y1409608D01*
Y1411692D01*
G01X1052208Y1425767D02*
X1052083Y1425517D01*
X1052000Y1425225D01*
Y1424892D01*
X1052125Y1424517D01*
X1052333Y1424225D01*
X1052583Y1424017D01*
X1053000Y1423850D01*
X1053375Y1423808D01*
X1053750Y1423892D01*
X1054000Y1424017D01*
X1054250Y1424267D01*
X1054417Y1424558D01*
X1054500Y1424850D01*
Y1425142D01*
X1054417Y1425433D01*
X1054292Y1425683D01*
X1054125Y1425892D01*
G01X1054500Y1427950D02*
X1052000D01*
X1052500Y1427450D01*
G01X1054500D02*
Y1428450D01*
G01X1052000Y1431050D02*
X1052083Y1430717D01*
X1052292Y1430467D01*
X1052542Y1430300D01*
X1052875Y1430175D01*
X1053250Y1430133D01*
X1053625Y1430175D01*
X1053958Y1430300D01*
X1054208Y1430467D01*
X1054417Y1430717D01*
X1054500Y1431050D01*
X1054417Y1431383D01*
X1054208Y1431633D01*
X1053958Y1431800D01*
X1053625Y1431925D01*
X1053250Y1431967D01*
X1052875Y1431925D01*
X1052542Y1431800D01*
X1052292Y1431633D01*
X1052083Y1431383D01*
X1052000Y1431050D01*
G01X1054125Y1433233D02*
X1054333Y1433483D01*
X1054458Y1433775D01*
X1054500Y1434150D01*
X1054417Y1434525D01*
X1054250Y1434817D01*
X1053958Y1435025D01*
X1053625Y1435067D01*
X1053292Y1434983D01*
X1053083Y1434775D01*
X1052917Y1434483D01*
X1052875Y1434192D01*
X1052917Y1433900D01*
X1053083Y1433525D01*
X1052000Y1433650D01*
Y1434775D01*
G01X994743Y1419899D02*
Y1415899D01*
X1002143D01*
G01X981143Y1416699D02*
Y1420699D01*
X973743D01*
G01X986743Y1419899D02*
Y1415899D01*
X994143D01*
G01X1013567Y1417100D02*
Y1419600D01*
X1014608D01*
X1014942Y1419475D01*
X1015150Y1419308D01*
X1015233Y1418975D01*
X1015150Y1418642D01*
X1014900Y1418433D01*
X1014608Y1418308D01*
X1013567D01*
G01X1014608D02*
X1015233Y1417100D01*
G01X1017500D02*
Y1419600D01*
X1017000Y1419100D01*
G01Y1417100D02*
X1018000D01*
G01X1020600Y1419600D02*
X1020267Y1419517D01*
X1020017Y1419308D01*
X1019850Y1419058D01*
X1019725Y1418725D01*
X1019683Y1418350D01*
X1019725Y1417975D01*
X1019850Y1417642D01*
X1020017Y1417392D01*
X1020267Y1417183D01*
X1020600Y1417100D01*
X1020933Y1417183D01*
X1021183Y1417392D01*
X1021350Y1417642D01*
X1021475Y1417975D01*
X1021517Y1418350D01*
X1021475Y1418725D01*
X1021350Y1419058D01*
X1021183Y1419308D01*
X1020933Y1419517D01*
X1020600Y1419600D01*
G01X1022783Y1417600D02*
X1023033Y1417308D01*
X1023367Y1417142D01*
X1023742Y1417100D01*
X1024075Y1417142D01*
X1024408Y1417350D01*
X1024617Y1417600D01*
X1024658Y1417850D01*
X1024575Y1418142D01*
X1024283Y1418350D01*
X1023992Y1418433D01*
X1023617D01*
G01X1023992D02*
X1024242Y1418558D01*
X1024450Y1418767D01*
X1024533Y1419017D01*
X1024450Y1419267D01*
X1024242Y1419475D01*
X1023867Y1419600D01*
X1023492Y1419558D01*
X1023117Y1419392D01*
G01X1027300Y1417100D02*
Y1419600D01*
X1025758Y1417808D01*
X1027842D01*
G01X1016000Y1400967D02*
X1013500D01*
Y1402008D01*
X1013625Y1402342D01*
X1013792Y1402550D01*
X1014125Y1402633D01*
X1014458Y1402550D01*
X1014667Y1402300D01*
X1014792Y1402008D01*
Y1400967D01*
G01Y1402008D02*
X1016000Y1402633D01*
G01Y1404900D02*
X1013500D01*
X1014000Y1404400D01*
G01X1016000D02*
Y1405400D01*
G01X1013500Y1408000D02*
X1013583Y1407667D01*
X1013792Y1407417D01*
X1014042Y1407250D01*
X1014375Y1407125D01*
X1014750Y1407083D01*
X1015125Y1407125D01*
X1015458Y1407250D01*
X1015708Y1407417D01*
X1015917Y1407667D01*
X1016000Y1408000D01*
X1015917Y1408333D01*
X1015708Y1408583D01*
X1015458Y1408750D01*
X1015125Y1408875D01*
X1014750Y1408917D01*
X1014375Y1408875D01*
X1014042Y1408750D01*
X1013792Y1408583D01*
X1013583Y1408333D01*
X1013500Y1408000D01*
G01X1013917Y1410308D02*
X1013667Y1410558D01*
X1013542Y1410850D01*
X1013500Y1411183D01*
X1013583Y1411600D01*
X1013792Y1411892D01*
X1014042Y1411975D01*
X1014292Y1411933D01*
X1014500Y1411767D01*
X1014917Y1410933D01*
X1015208Y1410558D01*
X1015625Y1410308D01*
X1016000Y1410225D01*
Y1411975D01*
G01X1015708Y1413492D02*
X1015917Y1413783D01*
X1016000Y1414117D01*
X1015917Y1414450D01*
X1015667Y1414742D01*
X1015292Y1414950D01*
X1014917Y1415033D01*
X1014458D01*
X1014083Y1414950D01*
X1013750Y1414742D01*
X1013583Y1414492D01*
X1013500Y1414200D01*
X1013583Y1413867D01*
X1013750Y1413617D01*
X1014000Y1413450D01*
X1014333Y1413367D01*
X1014625Y1413450D01*
X1014917Y1413658D01*
X1015083Y1413908D01*
X1015125Y1414200D01*
X1015042Y1414533D01*
X1014833Y1414783D01*
X1014458Y1415033D01*
G01X1012943Y1422599D02*
X1008943D01*
Y1415199D01*
G01X1017967Y1413000D02*
Y1415500D01*
X1019008D01*
X1019342Y1415375D01*
X1019550Y1415208D01*
X1019633Y1414875D01*
X1019550Y1414542D01*
X1019300Y1414333D01*
X1019008Y1414208D01*
X1017967D01*
G01X1019008D02*
X1019633Y1413000D01*
G01X1021900D02*
Y1415500D01*
X1021400Y1415000D01*
G01Y1413000D02*
X1022400D01*
G01X1025000Y1415500D02*
X1024667Y1415417D01*
X1024417Y1415208D01*
X1024250Y1414958D01*
X1024125Y1414625D01*
X1024083Y1414250D01*
X1024125Y1413875D01*
X1024250Y1413542D01*
X1024417Y1413292D01*
X1024667Y1413083D01*
X1025000Y1413000D01*
X1025333Y1413083D01*
X1025583Y1413292D01*
X1025750Y1413542D01*
X1025875Y1413875D01*
X1025917Y1414250D01*
X1025875Y1414625D01*
X1025750Y1414958D01*
X1025583Y1415208D01*
X1025333Y1415417D01*
X1025000Y1415500D01*
G01X1027183Y1413500D02*
X1027433Y1413208D01*
X1027767Y1413042D01*
X1028142Y1413000D01*
X1028475Y1413042D01*
X1028808Y1413250D01*
X1029017Y1413500D01*
X1029058Y1413750D01*
X1028975Y1414042D01*
X1028683Y1414250D01*
X1028392Y1414333D01*
X1028017D01*
G01X1028392D02*
X1028642Y1414458D01*
X1028850Y1414667D01*
X1028933Y1414917D01*
X1028850Y1415167D01*
X1028642Y1415375D01*
X1028267Y1415500D01*
X1027892Y1415458D01*
X1027517Y1415292D01*
G01X1031200Y1415500D02*
X1030867Y1415417D01*
X1030617Y1415208D01*
X1030450Y1414958D01*
X1030325Y1414625D01*
X1030283Y1414250D01*
X1030325Y1413875D01*
X1030450Y1413542D01*
X1030617Y1413292D01*
X1030867Y1413083D01*
X1031200Y1413000D01*
X1031533Y1413083D01*
X1031783Y1413292D01*
X1031950Y1413542D01*
X1032075Y1413875D01*
X1032117Y1414250D01*
X1032075Y1414625D01*
X1031950Y1414958D01*
X1031783Y1415208D01*
X1031533Y1415417D01*
X1031200Y1415500D01*
G01X1018743Y1428399D02*
Y1424399D01*
X1026143D01*
G01X981443Y1416599D02*
X977443D01*
Y1409199D01*
G01X990443Y1415599D02*
X986443D01*
Y1408199D01*
G01X998443Y1415599D02*
X994443D01*
Y1408199D01*
G01X961238Y1412118D02*
X965238D01*
Y1419518D01*
G01Y1430018D02*
X961238D01*
Y1422618D01*
G01X1020867Y1397892D02*
X1020617Y1398017D01*
X1020325Y1398100D01*
X1019992D01*
X1019617Y1397975D01*
X1019325Y1397767D01*
X1019117Y1397517D01*
X1018950Y1397100D01*
X1018908Y1396725D01*
X1018992Y1396350D01*
X1019117Y1396100D01*
X1019367Y1395850D01*
X1019658Y1395683D01*
X1019950Y1395600D01*
X1020242D01*
X1020533Y1395683D01*
X1020783Y1395808D01*
X1020992Y1395975D01*
G01X1022133D02*
X1022383Y1395767D01*
X1022675Y1395642D01*
X1023050Y1395600D01*
X1023425Y1395683D01*
X1023717Y1395850D01*
X1023925Y1396142D01*
X1023967Y1396475D01*
X1023883Y1396808D01*
X1023675Y1397017D01*
X1023383Y1397183D01*
X1023092Y1397225D01*
X1022800Y1397183D01*
X1022425Y1397017D01*
X1022550Y1398100D01*
X1023675D01*
G01X1025358Y1396642D02*
X1025650Y1396933D01*
X1025900Y1397100D01*
X1026233Y1397183D01*
X1026525Y1397100D01*
X1026733Y1396933D01*
X1026900Y1396683D01*
X1026942Y1396392D01*
X1026900Y1396142D01*
X1026733Y1395892D01*
X1026483Y1395683D01*
X1026192Y1395600D01*
X1025858Y1395683D01*
X1025567Y1395933D01*
X1025400Y1396308D01*
X1025358Y1396725D01*
X1025442Y1397267D01*
X1025567Y1397558D01*
X1025775Y1397850D01*
X1026067Y1398058D01*
X1026358Y1398100D01*
X1026650Y1398017D01*
X1026858Y1397808D01*
G01X1028458Y1396642D02*
X1028750Y1396933D01*
X1029000Y1397100D01*
X1029333Y1397183D01*
X1029625Y1397100D01*
X1029833Y1396933D01*
X1030000Y1396683D01*
X1030042Y1396392D01*
X1030000Y1396142D01*
X1029833Y1395892D01*
X1029583Y1395683D01*
X1029292Y1395600D01*
X1028958Y1395683D01*
X1028667Y1395933D01*
X1028500Y1396308D01*
X1028458Y1396725D01*
X1028542Y1397267D01*
X1028667Y1397558D01*
X1028875Y1397850D01*
X1029167Y1398058D01*
X1029458Y1398100D01*
X1029750Y1398017D01*
X1029958Y1397808D01*
G01X970900Y1401557D02*
Y1404057D01*
X971941D01*
X972275Y1403932D01*
X972483Y1403765D01*
X972566Y1403432D01*
X972483Y1403099D01*
X972233Y1402890D01*
X971941Y1402765D01*
X970900D01*
G01X971941D02*
X972566Y1401557D01*
G01X974833D02*
Y1404057D01*
X974333Y1403557D01*
G01Y1401557D02*
X975333D01*
G01X977933Y1404057D02*
X977600Y1403974D01*
X977350Y1403765D01*
X977183Y1403515D01*
X977058Y1403182D01*
X977016Y1402807D01*
X977058Y1402432D01*
X977183Y1402099D01*
X977350Y1401849D01*
X977600Y1401640D01*
X977933Y1401557D01*
X978266Y1401640D01*
X978516Y1401849D01*
X978683Y1402099D01*
X978808Y1402432D01*
X978850Y1402807D01*
X978808Y1403182D01*
X978683Y1403515D01*
X978516Y1403765D01*
X978266Y1403974D01*
X977933Y1404057D01*
G01X980116Y1402057D02*
X980366Y1401765D01*
X980700Y1401599D01*
X981075Y1401557D01*
X981408Y1401599D01*
X981741Y1401807D01*
X981950Y1402057D01*
X981991Y1402307D01*
X981908Y1402599D01*
X981616Y1402807D01*
X981325Y1402890D01*
X980950D01*
G01X981325D02*
X981575Y1403015D01*
X981783Y1403224D01*
X981866Y1403474D01*
X981783Y1403724D01*
X981575Y1403932D01*
X981200Y1404057D01*
X980825Y1404015D01*
X980450Y1403849D01*
G01X984133Y1401557D02*
X984425Y1401599D01*
X984758Y1401724D01*
X984966Y1401932D01*
X985050Y1402224D01*
X984966Y1402515D01*
X984716Y1402765D01*
X984341Y1402890D01*
X983925D01*
X983675Y1402974D01*
X983466Y1403182D01*
X983383Y1403474D01*
X983508Y1403765D01*
X983800Y1403974D01*
X984133Y1404057D01*
X984466Y1403974D01*
X984758Y1403765D01*
X984883Y1403474D01*
X984800Y1403182D01*
X984591Y1402974D01*
X984341Y1402890D01*
X983925D01*
X983550Y1402765D01*
X983300Y1402515D01*
X983216Y1402224D01*
X983300Y1401932D01*
X983508Y1401724D01*
X983841Y1401599D01*
X984133Y1401557D01*
G01X970900Y1397557D02*
Y1400057D01*
X971941D01*
X972275Y1399932D01*
X972483Y1399765D01*
X972566Y1399432D01*
X972483Y1399099D01*
X972233Y1398890D01*
X971941Y1398765D01*
X970900D01*
G01X971941D02*
X972566Y1397557D01*
G01X974833D02*
Y1400057D01*
X974333Y1399557D01*
G01Y1397557D02*
X975333D01*
G01X977933Y1400057D02*
X977600Y1399974D01*
X977350Y1399765D01*
X977183Y1399515D01*
X977058Y1399182D01*
X977016Y1398807D01*
X977058Y1398432D01*
X977183Y1398099D01*
X977350Y1397849D01*
X977600Y1397640D01*
X977933Y1397557D01*
X978266Y1397640D01*
X978516Y1397849D01*
X978683Y1398099D01*
X978808Y1398432D01*
X978850Y1398807D01*
X978808Y1399182D01*
X978683Y1399515D01*
X978516Y1399765D01*
X978266Y1399974D01*
X977933Y1400057D01*
G01X980116Y1398057D02*
X980366Y1397765D01*
X980700Y1397599D01*
X981075Y1397557D01*
X981408Y1397599D01*
X981741Y1397807D01*
X981950Y1398057D01*
X981991Y1398307D01*
X981908Y1398599D01*
X981616Y1398807D01*
X981325Y1398890D01*
X980950D01*
G01X981325D02*
X981575Y1399015D01*
X981783Y1399224D01*
X981866Y1399474D01*
X981783Y1399724D01*
X981575Y1399932D01*
X981200Y1400057D01*
X980825Y1400015D01*
X980450Y1399849D01*
G01X983216Y1397932D02*
X983466Y1397724D01*
X983758Y1397599D01*
X984133Y1397557D01*
X984508Y1397640D01*
X984800Y1397807D01*
X985008Y1398099D01*
X985050Y1398432D01*
X984966Y1398765D01*
X984758Y1398974D01*
X984466Y1399140D01*
X984175Y1399182D01*
X983883Y1399140D01*
X983508Y1398974D01*
X983633Y1400057D01*
X984758D01*
G01X1028067Y1420200D02*
Y1422700D01*
X1029108D01*
X1029442Y1422575D01*
X1029650Y1422408D01*
X1029733Y1422075D01*
X1029650Y1421742D01*
X1029400Y1421533D01*
X1029108Y1421408D01*
X1028067D01*
G01X1029108D02*
X1029733Y1420200D01*
G01X1032000D02*
Y1422700D01*
X1031500Y1422200D01*
G01Y1420200D02*
X1032500D01*
G01X1035100Y1422700D02*
X1034767Y1422617D01*
X1034517Y1422408D01*
X1034350Y1422158D01*
X1034225Y1421825D01*
X1034183Y1421450D01*
X1034225Y1421075D01*
X1034350Y1420742D01*
X1034517Y1420492D01*
X1034767Y1420283D01*
X1035100Y1420200D01*
X1035433Y1420283D01*
X1035683Y1420492D01*
X1035850Y1420742D01*
X1035975Y1421075D01*
X1036017Y1421450D01*
X1035975Y1421825D01*
X1035850Y1422158D01*
X1035683Y1422408D01*
X1035433Y1422617D01*
X1035100Y1422700D01*
G01X1037283Y1420700D02*
X1037533Y1420408D01*
X1037867Y1420242D01*
X1038242Y1420200D01*
X1038575Y1420242D01*
X1038908Y1420450D01*
X1039117Y1420700D01*
X1039158Y1420950D01*
X1039075Y1421242D01*
X1038783Y1421450D01*
X1038492Y1421533D01*
X1038117D01*
G01X1038492D02*
X1038742Y1421658D01*
X1038950Y1421867D01*
X1039033Y1422117D01*
X1038950Y1422367D01*
X1038742Y1422575D01*
X1038367Y1422700D01*
X1037992Y1422658D01*
X1037617Y1422492D01*
G01X1040383Y1420700D02*
X1040633Y1420408D01*
X1040967Y1420242D01*
X1041342Y1420200D01*
X1041675Y1420242D01*
X1042008Y1420450D01*
X1042217Y1420700D01*
X1042258Y1420950D01*
X1042175Y1421242D01*
X1041883Y1421450D01*
X1041592Y1421533D01*
X1041217D01*
G01X1041592D02*
X1041842Y1421658D01*
X1042050Y1421867D01*
X1042133Y1422117D01*
X1042050Y1422367D01*
X1041842Y1422575D01*
X1041467Y1422700D01*
X1041092Y1422658D01*
X1040717Y1422492D01*
G01X998430Y1426449D02*
Y1428449D01*
G01X1011293Y1432549D02*
Y1427549D01*
X1006293D01*
G01X1004250Y1395800D02*
X1003917Y1395842D01*
X1003625Y1396008D01*
X1003375Y1396258D01*
X1003208Y1396550D01*
X1003125Y1396883D01*
Y1397217D01*
X1003208Y1397550D01*
X1003375Y1397842D01*
X1003625Y1398092D01*
X1003917Y1398258D01*
X1004250Y1398300D01*
X1004583Y1398258D01*
X1004875Y1398092D01*
X1005125Y1397842D01*
X1005292Y1397550D01*
X1005375Y1397217D01*
Y1396883D01*
X1005292Y1396550D01*
X1005125Y1396258D01*
X1004875Y1396008D01*
X1004583Y1395842D01*
X1004250Y1395800D01*
G01X1004583Y1396467D02*
X1005083Y1395800D01*
G01X1006558Y1397883D02*
X1006808Y1398133D01*
X1007100Y1398258D01*
X1007433Y1398300D01*
X1007850Y1398217D01*
X1008142Y1398008D01*
X1008225Y1397758D01*
X1008183Y1397508D01*
X1008017Y1397300D01*
X1007183Y1396883D01*
X1006808Y1396592D01*
X1006558Y1396175D01*
X1006475Y1395800D01*
X1008225D01*
G01X1010450Y1398300D02*
X1010117Y1398217D01*
X1009867Y1398008D01*
X1009700Y1397758D01*
X1009575Y1397425D01*
X1009533Y1397050D01*
X1009575Y1396675D01*
X1009700Y1396342D01*
X1009867Y1396092D01*
X1010117Y1395883D01*
X1010450Y1395800D01*
X1010783Y1395883D01*
X1011033Y1396092D01*
X1011200Y1396342D01*
X1011325Y1396675D01*
X1011367Y1397050D01*
X1011325Y1397425D01*
X1011200Y1397758D01*
X1011033Y1398008D01*
X1010783Y1398217D01*
X1010450Y1398300D01*
G01X1013550Y1395800D02*
Y1398300D01*
X1013050Y1397800D01*
G01Y1395800D02*
X1014050D01*
G01X1032118Y1364189D02*
X1002118D01*
Y1386989D01*
X1032118D01*
Y1364189D01*
G01X1053900Y1334950D02*
X1053858Y1334617D01*
X1053692Y1334325D01*
X1053442Y1334075D01*
X1053150Y1333908D01*
X1052817Y1333825D01*
X1052483D01*
X1052150Y1333908D01*
X1051858Y1334075D01*
X1051608Y1334325D01*
X1051442Y1334617D01*
X1051400Y1334950D01*
X1051442Y1335283D01*
X1051608Y1335575D01*
X1051858Y1335825D01*
X1052150Y1335992D01*
X1052483Y1336075D01*
X1052817D01*
X1053150Y1335992D01*
X1053442Y1335825D01*
X1053692Y1335575D01*
X1053858Y1335283D01*
X1053900Y1334950D01*
G01X1053233Y1335283D02*
X1053900Y1335783D01*
G01X1051817Y1337258D02*
X1051567Y1337508D01*
X1051442Y1337800D01*
X1051400Y1338133D01*
X1051483Y1338550D01*
X1051692Y1338842D01*
X1051942Y1338925D01*
X1052192Y1338883D01*
X1052400Y1338717D01*
X1052817Y1337883D01*
X1053108Y1337508D01*
X1053525Y1337258D01*
X1053900Y1337175D01*
Y1338925D01*
G01X1051400Y1341150D02*
X1051483Y1340817D01*
X1051692Y1340567D01*
X1051942Y1340400D01*
X1052275Y1340275D01*
X1052650Y1340233D01*
X1053025Y1340275D01*
X1053358Y1340400D01*
X1053608Y1340567D01*
X1053817Y1340817D01*
X1053900Y1341150D01*
X1053817Y1341483D01*
X1053608Y1341733D01*
X1053358Y1341900D01*
X1053025Y1342025D01*
X1052650Y1342067D01*
X1052275Y1342025D01*
X1051942Y1341900D01*
X1051692Y1341733D01*
X1051483Y1341483D01*
X1051400Y1341150D01*
G01X1051817Y1343458D02*
X1051567Y1343708D01*
X1051442Y1344000D01*
X1051400Y1344333D01*
X1051483Y1344750D01*
X1051692Y1345042D01*
X1051942Y1345125D01*
X1052192Y1345083D01*
X1052400Y1344917D01*
X1052817Y1344083D01*
X1053108Y1343708D01*
X1053525Y1343458D01*
X1053900Y1343375D01*
Y1345125D01*
G01X1032118Y1336389D02*
X1002118D01*
Y1359189D01*
X1032118D01*
Y1336389D01*
G01X1050800Y1423100D02*
Y1433900D01*
G01X1043200Y1423100D02*
X1050800D01*
G01X1043200Y1433900D02*
Y1423100D01*
G01X1052318Y1388089D02*
X1047118D01*
G01X1052318Y1395089D02*
X1044518D01*
G01X1052318Y1388089D02*
Y1395089D01*
G01X1038918Y1388089D02*
X1047618D01*
G01X1038918Y1395089D02*
Y1388089D01*
G01X1045318Y1395089D02*
X1038918D01*
G01Y1402889D02*
X1044118D01*
G01X1038918Y1395889D02*
X1046718D01*
G01X1038918Y1402889D02*
Y1395889D01*
G01X1052318Y1402889D02*
X1043618D01*
G01X1052318Y1395889D02*
Y1402889D01*
G01X1045918Y1395889D02*
X1052318D01*
G01X1054800Y1361367D02*
X1052300D01*
Y1362408D01*
X1052425Y1362742D01*
X1052592Y1362950D01*
X1052925Y1363033D01*
X1053258Y1362950D01*
X1053467Y1362700D01*
X1053592Y1362408D01*
Y1361367D01*
G01Y1362408D02*
X1054800Y1363033D01*
G01Y1365300D02*
X1052300D01*
X1052800Y1364800D01*
G01X1054800D02*
Y1365800D01*
G01X1052300Y1368400D02*
X1052383Y1368067D01*
X1052592Y1367817D01*
X1052842Y1367650D01*
X1053175Y1367525D01*
X1053550Y1367483D01*
X1053925Y1367525D01*
X1054258Y1367650D01*
X1054508Y1367817D01*
X1054717Y1368067D01*
X1054800Y1368400D01*
X1054717Y1368733D01*
X1054508Y1368983D01*
X1054258Y1369150D01*
X1053925Y1369275D01*
X1053550Y1369317D01*
X1053175Y1369275D01*
X1052842Y1369150D01*
X1052592Y1368983D01*
X1052383Y1368733D01*
X1052300Y1368400D01*
G01X1054425Y1370583D02*
X1054633Y1370833D01*
X1054758Y1371125D01*
X1054800Y1371500D01*
X1054717Y1371875D01*
X1054550Y1372167D01*
X1054258Y1372375D01*
X1053925Y1372417D01*
X1053592Y1372333D01*
X1053383Y1372125D01*
X1053217Y1371833D01*
X1053175Y1371542D01*
X1053217Y1371250D01*
X1053383Y1370875D01*
X1052300Y1371000D01*
Y1372125D01*
G01X1054300Y1373683D02*
X1054592Y1373933D01*
X1054758Y1374267D01*
X1054800Y1374642D01*
X1054758Y1374975D01*
X1054550Y1375308D01*
X1054300Y1375517D01*
X1054050Y1375558D01*
X1053758Y1375475D01*
X1053550Y1375183D01*
X1053467Y1374892D01*
Y1374517D01*
G01Y1374892D02*
X1053342Y1375142D01*
X1053133Y1375350D01*
X1052883Y1375433D01*
X1052633Y1375350D01*
X1052425Y1375142D01*
X1052300Y1374767D01*
X1052342Y1374392D01*
X1052508Y1374017D01*
G01X1039068Y1359289D02*
X1044268D01*
G01X1039068Y1352289D02*
X1046868D01*
G01X1039068Y1359289D02*
Y1352289D01*
G01X1052468Y1359289D02*
X1043768D01*
G01X1052468Y1352289D02*
Y1359289D01*
G01X1046068Y1352289D02*
X1052468D01*
G01X1039068Y1387089D02*
X1044268D01*
G01X1039068Y1380089D02*
X1046868D01*
G01X1039068Y1387089D02*
Y1380089D01*
G01X1052468Y1387089D02*
X1043768D01*
G01X1052468Y1380089D02*
Y1387089D01*
G01X1046068Y1380089D02*
X1052468D01*
G01X1028683Y1405900D02*
Y1408400D01*
X1029517D01*
X1029850Y1408275D01*
X1030100Y1408108D01*
X1030308Y1407858D01*
X1030475Y1407567D01*
X1030517Y1407150D01*
X1030475Y1406733D01*
X1030308Y1406442D01*
X1030100Y1406192D01*
X1029850Y1406025D01*
X1029517Y1405900D01*
X1028683D01*
G01X1031783Y1406275D02*
X1032033Y1406067D01*
X1032325Y1405942D01*
X1032700Y1405900D01*
X1033075Y1405983D01*
X1033367Y1406150D01*
X1033575Y1406442D01*
X1033617Y1406775D01*
X1033533Y1407108D01*
X1033325Y1407317D01*
X1033033Y1407483D01*
X1032742Y1407525D01*
X1032450Y1407483D01*
X1032075Y1407317D01*
X1032200Y1408400D01*
X1033325D01*
G01X1035800Y1405900D02*
Y1408400D01*
X1035300Y1407900D01*
G01Y1405900D02*
X1036300D01*
G01X1053500Y1407000D02*
X1037400D01*
G01X1053500Y1414000D02*
Y1407000D01*
G01X1037400Y1414000D02*
X1053500D01*
G01X1037400Y1407000D02*
Y1414000D01*
G01X970367Y1362500D02*
Y1365000D01*
X971408D01*
X971742Y1364875D01*
X971950Y1364708D01*
X972033Y1364375D01*
X971950Y1364042D01*
X971700Y1363833D01*
X971408Y1363708D01*
X970367D01*
G01X971408D02*
X972033Y1362500D01*
G01X974300D02*
Y1365000D01*
X973800Y1364500D01*
G01Y1362500D02*
X974800D01*
G01X977400Y1365000D02*
X977067Y1364917D01*
X976817Y1364708D01*
X976650Y1364458D01*
X976525Y1364125D01*
X976483Y1363750D01*
X976525Y1363375D01*
X976650Y1363042D01*
X976817Y1362792D01*
X977067Y1362583D01*
X977400Y1362500D01*
X977733Y1362583D01*
X977983Y1362792D01*
X978150Y1363042D01*
X978275Y1363375D01*
X978317Y1363750D01*
X978275Y1364125D01*
X978150Y1364458D01*
X977983Y1364708D01*
X977733Y1364917D01*
X977400Y1365000D01*
G01X981000Y1362500D02*
Y1365000D01*
X979458Y1363208D01*
X981542D01*
G01X983517Y1362500D02*
X983600Y1363042D01*
X983725Y1363500D01*
X983892Y1363917D01*
X984100Y1364375D01*
X984433Y1365000D01*
X982767D01*
G01X966720Y1476185D02*
X966595Y1475935D01*
X966512Y1475643D01*
Y1475310D01*
X966637Y1474935D01*
X966845Y1474643D01*
X967095Y1474435D01*
X967512Y1474268D01*
X967887Y1474226D01*
X968262Y1474310D01*
X968512Y1474435D01*
X968762Y1474685D01*
X968929Y1474976D01*
X969012Y1475268D01*
Y1475560D01*
X968929Y1475851D01*
X968804Y1476101D01*
X968637Y1476310D01*
G01Y1477451D02*
X968845Y1477701D01*
X968970Y1477993D01*
X969012Y1478368D01*
X968929Y1478743D01*
X968762Y1479035D01*
X968470Y1479243D01*
X968137Y1479285D01*
X967804Y1479201D01*
X967595Y1478993D01*
X967429Y1478701D01*
X967387Y1478410D01*
X967429Y1478118D01*
X967595Y1477743D01*
X966512Y1477868D01*
Y1478993D01*
G01X968637Y1480551D02*
X968845Y1480801D01*
X968970Y1481093D01*
X969012Y1481468D01*
X968929Y1481843D01*
X968762Y1482135D01*
X968470Y1482343D01*
X968137Y1482385D01*
X967804Y1482301D01*
X967595Y1482093D01*
X967429Y1481801D01*
X967387Y1481510D01*
X967429Y1481218D01*
X967595Y1480843D01*
X966512Y1480968D01*
Y1482093D01*
G01X968512Y1483651D02*
X968804Y1483901D01*
X968970Y1484235D01*
X969012Y1484610D01*
X968970Y1484943D01*
X968762Y1485276D01*
X968512Y1485485D01*
X968262Y1485526D01*
X967970Y1485443D01*
X967762Y1485151D01*
X967679Y1484860D01*
Y1484485D01*
G01Y1484860D02*
X967554Y1485110D01*
X967345Y1485318D01*
X967095Y1485401D01*
X966845Y1485318D01*
X966637Y1485110D01*
X966512Y1484735D01*
X966554Y1484360D01*
X966720Y1483985D01*
G01X984742Y1475779D02*
X984617Y1475529D01*
X984534Y1475237D01*
Y1474904D01*
X984659Y1474529D01*
X984867Y1474237D01*
X985117Y1474029D01*
X985534Y1473862D01*
X985909Y1473820D01*
X986284Y1473904D01*
X986534Y1474029D01*
X986784Y1474279D01*
X986951Y1474570D01*
X987034Y1474862D01*
Y1475154D01*
X986951Y1475445D01*
X986826Y1475695D01*
X986659Y1475904D01*
G01Y1477045D02*
X986867Y1477295D01*
X986992Y1477587D01*
X987034Y1477962D01*
X986951Y1478337D01*
X986784Y1478629D01*
X986492Y1478837D01*
X986159Y1478879D01*
X985826Y1478795D01*
X985617Y1478587D01*
X985451Y1478295D01*
X985409Y1478004D01*
X985451Y1477712D01*
X985617Y1477337D01*
X984534Y1477462D01*
Y1478587D01*
G01X986659Y1480145D02*
X986867Y1480395D01*
X986992Y1480687D01*
X987034Y1481062D01*
X986951Y1481437D01*
X986784Y1481729D01*
X986492Y1481937D01*
X986159Y1481979D01*
X985826Y1481895D01*
X985617Y1481687D01*
X985451Y1481395D01*
X985409Y1481104D01*
X985451Y1480812D01*
X985617Y1480437D01*
X984534Y1480562D01*
Y1481687D01*
G01X985992Y1483370D02*
X985701Y1483662D01*
X985534Y1483912D01*
X985451Y1484245D01*
X985534Y1484537D01*
X985701Y1484745D01*
X985951Y1484912D01*
X986242Y1484954D01*
X986492Y1484912D01*
X986742Y1484745D01*
X986951Y1484495D01*
X987034Y1484204D01*
X986951Y1483870D01*
X986701Y1483579D01*
X986326Y1483412D01*
X985909Y1483370D01*
X985367Y1483454D01*
X985076Y1483579D01*
X984784Y1483787D01*
X984576Y1484079D01*
X984534Y1484370D01*
X984617Y1484662D01*
X984826Y1484870D01*
G01X974008Y1463167D02*
X973883Y1462917D01*
X973800Y1462625D01*
Y1462292D01*
X973925Y1461917D01*
X974133Y1461625D01*
X974383Y1461417D01*
X974800Y1461250D01*
X975175Y1461208D01*
X975550Y1461292D01*
X975800Y1461417D01*
X976050Y1461667D01*
X976217Y1461958D01*
X976300Y1462250D01*
Y1462542D01*
X976217Y1462833D01*
X976092Y1463083D01*
X975925Y1463292D01*
G01Y1464433D02*
X976133Y1464683D01*
X976258Y1464975D01*
X976300Y1465350D01*
X976217Y1465725D01*
X976050Y1466017D01*
X975758Y1466225D01*
X975425Y1466267D01*
X975092Y1466183D01*
X974883Y1465975D01*
X974717Y1465683D01*
X974675Y1465392D01*
X974717Y1465100D01*
X974883Y1464725D01*
X973800Y1464850D01*
Y1465975D01*
G01X976300Y1468367D02*
X975758Y1468450D01*
X975300Y1468575D01*
X974883Y1468742D01*
X974425Y1468950D01*
X973800Y1469283D01*
Y1467617D01*
G01Y1471550D02*
X973883Y1471217D01*
X974092Y1470967D01*
X974342Y1470800D01*
X974675Y1470675D01*
X975050Y1470633D01*
X975425Y1470675D01*
X975758Y1470800D01*
X976008Y1470967D01*
X976217Y1471217D01*
X976300Y1471550D01*
X976217Y1471883D01*
X976008Y1472133D01*
X975758Y1472300D01*
X975425Y1472425D01*
X975050Y1472467D01*
X974675Y1472425D01*
X974342Y1472300D01*
X974092Y1472133D01*
X973883Y1471883D01*
X973800Y1471550D01*
G01X983034Y1474029D02*
X980534D01*
Y1475070D01*
X980659Y1475404D01*
X980826Y1475612D01*
X981159Y1475695D01*
X981492Y1475612D01*
X981701Y1475362D01*
X981826Y1475070D01*
Y1474029D01*
G01Y1475070D02*
X983034Y1475695D01*
G01Y1477962D02*
X980534D01*
X981034Y1477462D01*
G01X983034D02*
Y1478462D01*
G01X980534Y1481062D02*
X980617Y1480729D01*
X980826Y1480479D01*
X981076Y1480312D01*
X981409Y1480187D01*
X981784Y1480145D01*
X982159Y1480187D01*
X982492Y1480312D01*
X982742Y1480479D01*
X982951Y1480729D01*
X983034Y1481062D01*
X982951Y1481395D01*
X982742Y1481645D01*
X982492Y1481812D01*
X982159Y1481937D01*
X981784Y1481979D01*
X981409Y1481937D01*
X981076Y1481812D01*
X980826Y1481645D01*
X980617Y1481395D01*
X980534Y1481062D01*
G01X982534Y1483245D02*
X982826Y1483495D01*
X982992Y1483829D01*
X983034Y1484204D01*
X982992Y1484537D01*
X982784Y1484870D01*
X982534Y1485079D01*
X982284Y1485120D01*
X981992Y1485037D01*
X981784Y1484745D01*
X981701Y1484454D01*
Y1484079D01*
G01Y1484454D02*
X981576Y1484704D01*
X981367Y1484912D01*
X981117Y1484995D01*
X980867Y1484912D01*
X980659Y1484704D01*
X980534Y1484329D01*
X980576Y1483954D01*
X980742Y1483579D01*
G01X982742Y1486554D02*
X982951Y1486845D01*
X983034Y1487179D01*
X982951Y1487512D01*
X982701Y1487804D01*
X982326Y1488012D01*
X981951Y1488095D01*
X981492D01*
X981117Y1488012D01*
X980784Y1487804D01*
X980617Y1487554D01*
X980534Y1487262D01*
X980617Y1486929D01*
X980784Y1486679D01*
X981034Y1486512D01*
X981367Y1486429D01*
X981659Y1486512D01*
X981951Y1486720D01*
X982117Y1486970D01*
X982159Y1487262D01*
X982076Y1487595D01*
X981867Y1487845D01*
X981492Y1488095D01*
G01X996325Y1462234D02*
X1000325D01*
Y1469634D01*
G01X995034Y1474029D02*
X992534D01*
Y1475070D01*
X992659Y1475404D01*
X992826Y1475612D01*
X993159Y1475695D01*
X993492Y1475612D01*
X993701Y1475362D01*
X993826Y1475070D01*
Y1474029D01*
G01Y1475070D02*
X995034Y1475695D01*
G01Y1477962D02*
X992534D01*
X993034Y1477462D01*
G01X995034D02*
Y1478462D01*
G01X992534Y1481062D02*
X992617Y1480729D01*
X992826Y1480479D01*
X993076Y1480312D01*
X993409Y1480187D01*
X993784Y1480145D01*
X994159Y1480187D01*
X994492Y1480312D01*
X994742Y1480479D01*
X994951Y1480729D01*
X995034Y1481062D01*
X994951Y1481395D01*
X994742Y1481645D01*
X994492Y1481812D01*
X994159Y1481937D01*
X993784Y1481979D01*
X993409Y1481937D01*
X993076Y1481812D01*
X992826Y1481645D01*
X992617Y1481395D01*
X992534Y1481062D01*
G01X995034Y1484662D02*
X992534D01*
X994326Y1483120D01*
Y1485204D01*
G01X992534Y1487262D02*
X992617Y1486929D01*
X992826Y1486679D01*
X993076Y1486512D01*
X993409Y1486387D01*
X993784Y1486345D01*
X994159Y1486387D01*
X994492Y1486512D01*
X994742Y1486679D01*
X994951Y1486929D01*
X995034Y1487262D01*
X994951Y1487595D01*
X994742Y1487845D01*
X994492Y1488012D01*
X994159Y1488137D01*
X993784Y1488179D01*
X993409Y1488137D01*
X993076Y1488012D01*
X992826Y1487845D01*
X992617Y1487595D01*
X992534Y1487262D01*
G01X1011618Y1462165D02*
X1015618D01*
Y1469565D01*
G01X999034Y1474029D02*
X996534D01*
Y1475070D01*
X996659Y1475404D01*
X996826Y1475612D01*
X997159Y1475695D01*
X997492Y1475612D01*
X997701Y1475362D01*
X997826Y1475070D01*
Y1474029D01*
G01Y1475070D02*
X999034Y1475695D01*
G01Y1477962D02*
X996534D01*
X997034Y1477462D01*
G01X999034D02*
Y1478462D01*
G01X996534Y1481062D02*
X996617Y1480729D01*
X996826Y1480479D01*
X997076Y1480312D01*
X997409Y1480187D01*
X997784Y1480145D01*
X998159Y1480187D01*
X998492Y1480312D01*
X998742Y1480479D01*
X998951Y1480729D01*
X999034Y1481062D01*
X998951Y1481395D01*
X998742Y1481645D01*
X998492Y1481812D01*
X998159Y1481937D01*
X997784Y1481979D01*
X997409Y1481937D01*
X997076Y1481812D01*
X996826Y1481645D01*
X996617Y1481395D01*
X996534Y1481062D01*
G01X998534Y1483245D02*
X998826Y1483495D01*
X998992Y1483829D01*
X999034Y1484204D01*
X998992Y1484537D01*
X998784Y1484870D01*
X998534Y1485079D01*
X998284Y1485120D01*
X997992Y1485037D01*
X997784Y1484745D01*
X997701Y1484454D01*
Y1484079D01*
G01Y1484454D02*
X997576Y1484704D01*
X997367Y1484912D01*
X997117Y1484995D01*
X996867Y1484912D01*
X996659Y1484704D01*
X996534Y1484329D01*
X996576Y1483954D01*
X996742Y1483579D01*
G01X999034Y1487179D02*
X998492Y1487262D01*
X998034Y1487387D01*
X997617Y1487554D01*
X997159Y1487762D01*
X996534Y1488095D01*
Y1486429D01*
G01X1019618Y1469565D02*
X1015618D01*
Y1462165D01*
G01X979034Y1474029D02*
X976534D01*
Y1475070D01*
X976659Y1475404D01*
X976826Y1475612D01*
X977159Y1475695D01*
X977492Y1475612D01*
X977701Y1475362D01*
X977826Y1475070D01*
Y1474029D01*
G01Y1475070D02*
X979034Y1475695D01*
G01Y1477962D02*
X976534D01*
X977034Y1477462D01*
G01X979034D02*
Y1478462D01*
G01X976534Y1481062D02*
X976617Y1480729D01*
X976826Y1480479D01*
X977076Y1480312D01*
X977409Y1480187D01*
X977784Y1480145D01*
X978159Y1480187D01*
X978492Y1480312D01*
X978742Y1480479D01*
X978951Y1480729D01*
X979034Y1481062D01*
X978951Y1481395D01*
X978742Y1481645D01*
X978492Y1481812D01*
X978159Y1481937D01*
X977784Y1481979D01*
X977409Y1481937D01*
X977076Y1481812D01*
X976826Y1481645D01*
X976617Y1481395D01*
X976534Y1481062D01*
G01X978534Y1483245D02*
X978826Y1483495D01*
X978992Y1483829D01*
X979034Y1484204D01*
X978992Y1484537D01*
X978784Y1484870D01*
X978534Y1485079D01*
X978284Y1485120D01*
X977992Y1485037D01*
X977784Y1484745D01*
X977701Y1484454D01*
Y1484079D01*
G01Y1484454D02*
X977576Y1484704D01*
X977367Y1484912D01*
X977117Y1484995D01*
X976867Y1484912D01*
X976659Y1484704D01*
X976534Y1484329D01*
X976576Y1483954D01*
X976742Y1483579D01*
G01X977992Y1486470D02*
X977701Y1486762D01*
X977534Y1487012D01*
X977451Y1487345D01*
X977534Y1487637D01*
X977701Y1487845D01*
X977951Y1488012D01*
X978242Y1488054D01*
X978492Y1488012D01*
X978742Y1487845D01*
X978951Y1487595D01*
X979034Y1487304D01*
X978951Y1486970D01*
X978701Y1486679D01*
X978326Y1486512D01*
X977909Y1486470D01*
X977367Y1486554D01*
X977076Y1486679D01*
X976784Y1486887D01*
X976576Y1487179D01*
X976534Y1487470D01*
X976617Y1487762D01*
X976826Y1487970D01*
G01X996271Y1469617D02*
X992271D01*
Y1462217D01*
G01X1015743Y1433399D02*
Y1429399D01*
X1023143D01*
G01X1003034Y1474029D02*
X1000534D01*
Y1475070D01*
X1000659Y1475404D01*
X1000826Y1475612D01*
X1001159Y1475695D01*
X1001492Y1475612D01*
X1001701Y1475362D01*
X1001826Y1475070D01*
Y1474029D01*
G01Y1475070D02*
X1003034Y1475695D01*
G01Y1477962D02*
X1000534D01*
X1001034Y1477462D01*
G01X1003034D02*
Y1478462D01*
G01X1000534Y1481062D02*
X1000617Y1480729D01*
X1000826Y1480479D01*
X1001076Y1480312D01*
X1001409Y1480187D01*
X1001784Y1480145D01*
X1002159Y1480187D01*
X1002492Y1480312D01*
X1002742Y1480479D01*
X1002951Y1480729D01*
X1003034Y1481062D01*
X1002951Y1481395D01*
X1002742Y1481645D01*
X1002492Y1481812D01*
X1002159Y1481937D01*
X1001784Y1481979D01*
X1001409Y1481937D01*
X1001076Y1481812D01*
X1000826Y1481645D01*
X1000617Y1481395D01*
X1000534Y1481062D01*
G01X1002534Y1483245D02*
X1002826Y1483495D01*
X1002992Y1483829D01*
X1003034Y1484204D01*
X1002992Y1484537D01*
X1002784Y1484870D01*
X1002534Y1485079D01*
X1002284Y1485120D01*
X1001992Y1485037D01*
X1001784Y1484745D01*
X1001701Y1484454D01*
Y1484079D01*
G01Y1484454D02*
X1001576Y1484704D01*
X1001367Y1484912D01*
X1001117Y1484995D01*
X1000867Y1484912D01*
X1000659Y1484704D01*
X1000534Y1484329D01*
X1000576Y1483954D01*
X1000742Y1483579D01*
G01X1003034Y1487262D02*
X1000534D01*
X1001034Y1486762D01*
G01X1003034D02*
Y1487762D01*
G01X1023618Y1469565D02*
X1019618D01*
Y1462165D01*
G01X1031467Y1451500D02*
Y1454000D01*
X1032508D01*
X1032842Y1453875D01*
X1033050Y1453708D01*
X1033133Y1453375D01*
X1033050Y1453042D01*
X1032800Y1452833D01*
X1032508Y1452708D01*
X1031467D01*
G01X1032508D02*
X1033133Y1451500D01*
G01X1035400D02*
Y1454000D01*
X1034900Y1453500D01*
G01Y1451500D02*
X1035900D01*
G01X1038500Y1454000D02*
X1038167Y1453917D01*
X1037917Y1453708D01*
X1037750Y1453458D01*
X1037625Y1453125D01*
X1037583Y1452750D01*
X1037625Y1452375D01*
X1037750Y1452042D01*
X1037917Y1451792D01*
X1038167Y1451583D01*
X1038500Y1451500D01*
X1038833Y1451583D01*
X1039083Y1451792D01*
X1039250Y1452042D01*
X1039375Y1452375D01*
X1039417Y1452750D01*
X1039375Y1453125D01*
X1039250Y1453458D01*
X1039083Y1453708D01*
X1038833Y1453917D01*
X1038500Y1454000D01*
G01X1040808Y1453583D02*
X1041058Y1453833D01*
X1041350Y1453958D01*
X1041683Y1454000D01*
X1042100Y1453917D01*
X1042392Y1453708D01*
X1042475Y1453458D01*
X1042433Y1453208D01*
X1042267Y1453000D01*
X1041433Y1452583D01*
X1041058Y1452292D01*
X1040808Y1451875D01*
X1040725Y1451500D01*
X1042475D01*
G01X1044700D02*
X1044992Y1451542D01*
X1045325Y1451667D01*
X1045533Y1451875D01*
X1045617Y1452167D01*
X1045533Y1452458D01*
X1045283Y1452708D01*
X1044908Y1452833D01*
X1044492D01*
X1044242Y1452917D01*
X1044033Y1453125D01*
X1043950Y1453417D01*
X1044075Y1453708D01*
X1044367Y1453917D01*
X1044700Y1454000D01*
X1045033Y1453917D01*
X1045325Y1453708D01*
X1045450Y1453417D01*
X1045367Y1453125D01*
X1045158Y1452917D01*
X1044908Y1452833D01*
X1044492D01*
X1044117Y1452708D01*
X1043867Y1452458D01*
X1043783Y1452167D01*
X1043867Y1451875D01*
X1044075Y1451667D01*
X1044408Y1451542D01*
X1044700Y1451500D01*
G01X1021743Y1453399D02*
Y1449399D01*
X1029143D01*
G01X1030967Y1457500D02*
Y1460000D01*
X1032008D01*
X1032342Y1459875D01*
X1032550Y1459708D01*
X1032633Y1459375D01*
X1032550Y1459042D01*
X1032300Y1458833D01*
X1032008Y1458708D01*
X1030967D01*
G01X1032008D02*
X1032633Y1457500D01*
G01X1034900D02*
Y1460000D01*
X1034400Y1459500D01*
G01Y1457500D02*
X1035400D01*
G01X1038000Y1460000D02*
X1037667Y1459917D01*
X1037417Y1459708D01*
X1037250Y1459458D01*
X1037125Y1459125D01*
X1037083Y1458750D01*
X1037125Y1458375D01*
X1037250Y1458042D01*
X1037417Y1457792D01*
X1037667Y1457583D01*
X1038000Y1457500D01*
X1038333Y1457583D01*
X1038583Y1457792D01*
X1038750Y1458042D01*
X1038875Y1458375D01*
X1038917Y1458750D01*
X1038875Y1459125D01*
X1038750Y1459458D01*
X1038583Y1459708D01*
X1038333Y1459917D01*
X1038000Y1460000D01*
G01X1040308Y1459583D02*
X1040558Y1459833D01*
X1040850Y1459958D01*
X1041183Y1460000D01*
X1041600Y1459917D01*
X1041892Y1459708D01*
X1041975Y1459458D01*
X1041933Y1459208D01*
X1041767Y1459000D01*
X1040933Y1458583D01*
X1040558Y1458292D01*
X1040308Y1457875D01*
X1040225Y1457500D01*
X1041975D01*
G01X1044117D02*
X1044200Y1458042D01*
X1044325Y1458500D01*
X1044492Y1458917D01*
X1044700Y1459375D01*
X1045033Y1460000D01*
X1043367D01*
G01X1021743Y1457899D02*
Y1453899D01*
X1029143D01*
G01X1041606Y1442949D02*
X1045606D01*
Y1450349D01*
G01X1053642Y1441766D02*
X1051142D01*
Y1442807D01*
X1051267Y1443141D01*
X1051434Y1443349D01*
X1051767Y1443432D01*
X1052100Y1443349D01*
X1052309Y1443099D01*
X1052434Y1442807D01*
Y1441766D01*
G01Y1442807D02*
X1053642Y1443432D01*
G01X1051559Y1444907D02*
X1051309Y1445157D01*
X1051184Y1445449D01*
X1051142Y1445782D01*
X1051225Y1446199D01*
X1051434Y1446491D01*
X1051684Y1446574D01*
X1051934Y1446532D01*
X1052142Y1446366D01*
X1052559Y1445532D01*
X1052850Y1445157D01*
X1053267Y1444907D01*
X1053642Y1444824D01*
Y1446574D01*
G01X1040303Y1450349D02*
X1036303D01*
Y1442949D01*
G01X1028817Y1508414D02*
Y1510914D01*
X1029858D01*
X1030192Y1510789D01*
X1030400Y1510622D01*
X1030483Y1510289D01*
X1030400Y1509956D01*
X1030150Y1509747D01*
X1029858Y1509622D01*
X1028817D01*
G01X1029858D02*
X1030483Y1508414D01*
G01X1032750D02*
Y1510914D01*
X1032250Y1510414D01*
G01Y1508414D02*
X1033250D01*
G01X1035850Y1510914D02*
X1035517Y1510831D01*
X1035267Y1510622D01*
X1035100Y1510372D01*
X1034975Y1510039D01*
X1034933Y1509664D01*
X1034975Y1509289D01*
X1035100Y1508956D01*
X1035267Y1508706D01*
X1035517Y1508497D01*
X1035850Y1508414D01*
X1036183Y1508497D01*
X1036433Y1508706D01*
X1036600Y1508956D01*
X1036725Y1509289D01*
X1036767Y1509664D01*
X1036725Y1510039D01*
X1036600Y1510372D01*
X1036433Y1510622D01*
X1036183Y1510831D01*
X1035850Y1510914D01*
G01X1038158Y1509456D02*
X1038450Y1509747D01*
X1038700Y1509914D01*
X1039033Y1509997D01*
X1039325Y1509914D01*
X1039533Y1509747D01*
X1039700Y1509497D01*
X1039742Y1509206D01*
X1039700Y1508956D01*
X1039533Y1508706D01*
X1039283Y1508497D01*
X1038992Y1508414D01*
X1038658Y1508497D01*
X1038367Y1508747D01*
X1038200Y1509122D01*
X1038158Y1509539D01*
X1038242Y1510081D01*
X1038367Y1510372D01*
X1038575Y1510664D01*
X1038867Y1510872D01*
X1039158Y1510914D01*
X1039450Y1510831D01*
X1039658Y1510622D01*
G01X1041342Y1508706D02*
X1041633Y1508497D01*
X1041967Y1508414D01*
X1042300Y1508497D01*
X1042592Y1508747D01*
X1042800Y1509122D01*
X1042883Y1509497D01*
Y1509956D01*
X1042800Y1510331D01*
X1042592Y1510664D01*
X1042342Y1510831D01*
X1042050Y1510914D01*
X1041717Y1510831D01*
X1041467Y1510664D01*
X1041300Y1510414D01*
X1041217Y1510081D01*
X1041300Y1509789D01*
X1041508Y1509497D01*
X1041758Y1509331D01*
X1042050Y1509289D01*
X1042383Y1509372D01*
X1042633Y1509581D01*
X1042883Y1509956D01*
G01X1039550Y1494914D02*
Y1498914D01*
X1032150D01*
G01X1013017Y1506114D02*
Y1508614D01*
X1014058D01*
X1014392Y1508489D01*
X1014600Y1508322D01*
X1014683Y1507989D01*
X1014600Y1507656D01*
X1014350Y1507447D01*
X1014058Y1507322D01*
X1013017D01*
G01X1014058D02*
X1014683Y1506114D01*
G01X1016950D02*
Y1508614D01*
X1016450Y1508114D01*
G01Y1506114D02*
X1017450D01*
G01X1020050Y1508614D02*
X1019717Y1508531D01*
X1019467Y1508322D01*
X1019300Y1508072D01*
X1019175Y1507739D01*
X1019133Y1507364D01*
X1019175Y1506989D01*
X1019300Y1506656D01*
X1019467Y1506406D01*
X1019717Y1506197D01*
X1020050Y1506114D01*
X1020383Y1506197D01*
X1020633Y1506406D01*
X1020800Y1506656D01*
X1020925Y1506989D01*
X1020967Y1507364D01*
X1020925Y1507739D01*
X1020800Y1508072D01*
X1020633Y1508322D01*
X1020383Y1508531D01*
X1020050Y1508614D01*
G01X1022358Y1507156D02*
X1022650Y1507447D01*
X1022900Y1507614D01*
X1023233Y1507697D01*
X1023525Y1507614D01*
X1023733Y1507447D01*
X1023900Y1507197D01*
X1023942Y1506906D01*
X1023900Y1506656D01*
X1023733Y1506406D01*
X1023483Y1506197D01*
X1023192Y1506114D01*
X1022858Y1506197D01*
X1022567Y1506447D01*
X1022400Y1506822D01*
X1022358Y1507239D01*
X1022442Y1507781D01*
X1022567Y1508072D01*
X1022775Y1508364D01*
X1023067Y1508572D01*
X1023358Y1508614D01*
X1023650Y1508531D01*
X1023858Y1508322D01*
G01X1026750Y1506114D02*
Y1508614D01*
X1025208Y1506822D01*
X1027292D01*
G01X1018550Y1498814D02*
Y1494814D01*
X1025950D01*
G01X1053500Y1455367D02*
X1051000D01*
Y1456408D01*
X1051125Y1456742D01*
X1051292Y1456950D01*
X1051625Y1457033D01*
X1051958Y1456950D01*
X1052167Y1456700D01*
X1052292Y1456408D01*
Y1455367D01*
G01Y1456408D02*
X1053500Y1457033D01*
G01Y1459300D02*
X1051000D01*
X1051500Y1458800D01*
G01X1053500D02*
Y1459800D01*
G01X1051000Y1462400D02*
X1051083Y1462067D01*
X1051292Y1461817D01*
X1051542Y1461650D01*
X1051875Y1461525D01*
X1052250Y1461483D01*
X1052625Y1461525D01*
X1052958Y1461650D01*
X1053208Y1461817D01*
X1053417Y1462067D01*
X1053500Y1462400D01*
X1053417Y1462733D01*
X1053208Y1462983D01*
X1052958Y1463150D01*
X1052625Y1463275D01*
X1052250Y1463317D01*
X1051875Y1463275D01*
X1051542Y1463150D01*
X1051292Y1462983D01*
X1051083Y1462733D01*
X1051000Y1462400D01*
G01X1052458Y1464708D02*
X1052167Y1465000D01*
X1052000Y1465250D01*
X1051917Y1465583D01*
X1052000Y1465875D01*
X1052167Y1466083D01*
X1052417Y1466250D01*
X1052708Y1466292D01*
X1052958Y1466250D01*
X1053208Y1466083D01*
X1053417Y1465833D01*
X1053500Y1465542D01*
X1053417Y1465208D01*
X1053167Y1464917D01*
X1052792Y1464750D01*
X1052375Y1464708D01*
X1051833Y1464792D01*
X1051542Y1464917D01*
X1051250Y1465125D01*
X1051042Y1465417D01*
X1051000Y1465708D01*
X1051083Y1466000D01*
X1051292Y1466208D01*
G01X1053000Y1467683D02*
X1053292Y1467933D01*
X1053458Y1468267D01*
X1053500Y1468642D01*
X1053458Y1468975D01*
X1053250Y1469308D01*
X1053000Y1469517D01*
X1052750Y1469558D01*
X1052458Y1469475D01*
X1052250Y1469183D01*
X1052167Y1468892D01*
Y1468517D01*
G01Y1468892D02*
X1052042Y1469142D01*
X1051833Y1469350D01*
X1051583Y1469433D01*
X1051333Y1469350D01*
X1051125Y1469142D01*
X1051000Y1468767D01*
X1051042Y1468392D01*
X1051208Y1468017D01*
G01X1042663Y1469841D02*
X1038663D01*
Y1462441D01*
G01X1045217Y1508714D02*
Y1511214D01*
X1046258D01*
X1046592Y1511089D01*
X1046800Y1510922D01*
X1046883Y1510589D01*
X1046800Y1510256D01*
X1046550Y1510047D01*
X1046258Y1509922D01*
X1045217D01*
G01X1046258D02*
X1046883Y1508714D01*
G01X1049150D02*
Y1511214D01*
X1048650Y1510714D01*
G01Y1508714D02*
X1049650D01*
G01X1052250Y1511214D02*
X1051917Y1511131D01*
X1051667Y1510922D01*
X1051500Y1510672D01*
X1051375Y1510339D01*
X1051333Y1509964D01*
X1051375Y1509589D01*
X1051500Y1509256D01*
X1051667Y1509006D01*
X1051917Y1508797D01*
X1052250Y1508714D01*
X1052583Y1508797D01*
X1052833Y1509006D01*
X1053000Y1509256D01*
X1053125Y1509589D01*
X1053167Y1509964D01*
X1053125Y1510339D01*
X1053000Y1510672D01*
X1052833Y1510922D01*
X1052583Y1511131D01*
X1052250Y1511214D01*
G01X1055267Y1508714D02*
X1055350Y1509256D01*
X1055475Y1509714D01*
X1055642Y1510131D01*
X1055850Y1510589D01*
X1056183Y1511214D01*
X1054517D01*
G01X1058450D02*
X1058117Y1511131D01*
X1057867Y1510922D01*
X1057700Y1510672D01*
X1057575Y1510339D01*
X1057533Y1509964D01*
X1057575Y1509589D01*
X1057700Y1509256D01*
X1057867Y1509006D01*
X1058117Y1508797D01*
X1058450Y1508714D01*
X1058783Y1508797D01*
X1059033Y1509006D01*
X1059200Y1509256D01*
X1059325Y1509589D01*
X1059367Y1509964D01*
X1059325Y1510339D01*
X1059200Y1510672D01*
X1059033Y1510922D01*
X1058783Y1511131D01*
X1058450Y1511214D01*
G01X1039850Y1498914D02*
Y1494914D01*
X1047250D01*
G01X1013017Y1502114D02*
Y1504614D01*
X1014058D01*
X1014392Y1504489D01*
X1014600Y1504322D01*
X1014683Y1503989D01*
X1014600Y1503656D01*
X1014350Y1503447D01*
X1014058Y1503322D01*
X1013017D01*
G01X1014058D02*
X1014683Y1502114D01*
G01X1016950D02*
Y1504614D01*
X1016450Y1504114D01*
G01Y1502114D02*
X1017450D01*
G01X1020050Y1504614D02*
X1019717Y1504531D01*
X1019467Y1504322D01*
X1019300Y1504072D01*
X1019175Y1503739D01*
X1019133Y1503364D01*
X1019175Y1502989D01*
X1019300Y1502656D01*
X1019467Y1502406D01*
X1019717Y1502197D01*
X1020050Y1502114D01*
X1020383Y1502197D01*
X1020633Y1502406D01*
X1020800Y1502656D01*
X1020925Y1502989D01*
X1020967Y1503364D01*
X1020925Y1503739D01*
X1020800Y1504072D01*
X1020633Y1504322D01*
X1020383Y1504531D01*
X1020050Y1504614D01*
G01X1022358Y1503156D02*
X1022650Y1503447D01*
X1022900Y1503614D01*
X1023233Y1503697D01*
X1023525Y1503614D01*
X1023733Y1503447D01*
X1023900Y1503197D01*
X1023942Y1502906D01*
X1023900Y1502656D01*
X1023733Y1502406D01*
X1023483Y1502197D01*
X1023192Y1502114D01*
X1022858Y1502197D01*
X1022567Y1502447D01*
X1022400Y1502822D01*
X1022358Y1503239D01*
X1022442Y1503781D01*
X1022567Y1504072D01*
X1022775Y1504364D01*
X1023067Y1504572D01*
X1023358Y1504614D01*
X1023650Y1504531D01*
X1023858Y1504322D01*
G01X1026167Y1502114D02*
X1026250Y1502656D01*
X1026375Y1503114D01*
X1026542Y1503531D01*
X1026750Y1503989D01*
X1027083Y1504614D01*
X1025417D01*
G01X1025950Y1490814D02*
Y1494814D01*
X1018550D01*
G01X1045217Y1504614D02*
Y1507114D01*
X1046258D01*
X1046592Y1506989D01*
X1046800Y1506822D01*
X1046883Y1506489D01*
X1046800Y1506156D01*
X1046550Y1505947D01*
X1046258Y1505822D01*
X1045217D01*
G01X1046258D02*
X1046883Y1504614D01*
G01X1049150D02*
Y1507114D01*
X1048650Y1506614D01*
G01Y1504614D02*
X1049650D01*
G01X1052250Y1507114D02*
X1051917Y1507031D01*
X1051667Y1506822D01*
X1051500Y1506572D01*
X1051375Y1506239D01*
X1051333Y1505864D01*
X1051375Y1505489D01*
X1051500Y1505156D01*
X1051667Y1504906D01*
X1051917Y1504697D01*
X1052250Y1504614D01*
X1052583Y1504697D01*
X1052833Y1504906D01*
X1053000Y1505156D01*
X1053125Y1505489D01*
X1053167Y1505864D01*
X1053125Y1506239D01*
X1053000Y1506572D01*
X1052833Y1506822D01*
X1052583Y1507031D01*
X1052250Y1507114D01*
G01X1054558Y1505656D02*
X1054850Y1505947D01*
X1055100Y1506114D01*
X1055433Y1506197D01*
X1055725Y1506114D01*
X1055933Y1505947D01*
X1056100Y1505697D01*
X1056142Y1505406D01*
X1056100Y1505156D01*
X1055933Y1504906D01*
X1055683Y1504697D01*
X1055392Y1504614D01*
X1055058Y1504697D01*
X1054767Y1504947D01*
X1054600Y1505322D01*
X1054558Y1505739D01*
X1054642Y1506281D01*
X1054767Y1506572D01*
X1054975Y1506864D01*
X1055267Y1507072D01*
X1055558Y1507114D01*
X1055850Y1507031D01*
X1056058Y1506822D01*
G01X1057658Y1505656D02*
X1057950Y1505947D01*
X1058200Y1506114D01*
X1058533Y1506197D01*
X1058825Y1506114D01*
X1059033Y1505947D01*
X1059200Y1505697D01*
X1059242Y1505406D01*
X1059200Y1505156D01*
X1059033Y1504906D01*
X1058783Y1504697D01*
X1058492Y1504614D01*
X1058158Y1504697D01*
X1057867Y1504947D01*
X1057700Y1505322D01*
X1057658Y1505739D01*
X1057742Y1506281D01*
X1057867Y1506572D01*
X1058075Y1506864D01*
X1058367Y1507072D01*
X1058658Y1507114D01*
X1058950Y1507031D01*
X1059158Y1506822D01*
G01X1047250Y1490814D02*
Y1494814D01*
X1039850D01*
G01X1028967Y1504500D02*
Y1507000D01*
X1030008D01*
X1030342Y1506875D01*
X1030550Y1506708D01*
X1030633Y1506375D01*
X1030550Y1506042D01*
X1030300Y1505833D01*
X1030008Y1505708D01*
X1028967D01*
G01X1030008D02*
X1030633Y1504500D01*
G01X1032900D02*
Y1507000D01*
X1032400Y1506500D01*
G01Y1504500D02*
X1033400D01*
G01X1036000Y1507000D02*
X1035667Y1506917D01*
X1035417Y1506708D01*
X1035250Y1506458D01*
X1035125Y1506125D01*
X1035083Y1505750D01*
X1035125Y1505375D01*
X1035250Y1505042D01*
X1035417Y1504792D01*
X1035667Y1504583D01*
X1036000Y1504500D01*
X1036333Y1504583D01*
X1036583Y1504792D01*
X1036750Y1505042D01*
X1036875Y1505375D01*
X1036917Y1505750D01*
X1036875Y1506125D01*
X1036750Y1506458D01*
X1036583Y1506708D01*
X1036333Y1506917D01*
X1036000Y1507000D01*
G01X1038308Y1505542D02*
X1038600Y1505833D01*
X1038850Y1506000D01*
X1039183Y1506083D01*
X1039475Y1506000D01*
X1039683Y1505833D01*
X1039850Y1505583D01*
X1039892Y1505292D01*
X1039850Y1505042D01*
X1039683Y1504792D01*
X1039433Y1504583D01*
X1039142Y1504500D01*
X1038808Y1504583D01*
X1038517Y1504833D01*
X1038350Y1505208D01*
X1038308Y1505625D01*
X1038392Y1506167D01*
X1038517Y1506458D01*
X1038725Y1506750D01*
X1039017Y1506958D01*
X1039308Y1507000D01*
X1039600Y1506917D01*
X1039808Y1506708D01*
G01X1042200Y1504500D02*
X1042492Y1504542D01*
X1042825Y1504667D01*
X1043033Y1504875D01*
X1043117Y1505167D01*
X1043033Y1505458D01*
X1042783Y1505708D01*
X1042408Y1505833D01*
X1041992D01*
X1041742Y1505917D01*
X1041533Y1506125D01*
X1041450Y1506417D01*
X1041575Y1506708D01*
X1041867Y1506917D01*
X1042200Y1507000D01*
X1042533Y1506917D01*
X1042825Y1506708D01*
X1042950Y1506417D01*
X1042867Y1506125D01*
X1042658Y1505917D01*
X1042408Y1505833D01*
X1041992D01*
X1041617Y1505708D01*
X1041367Y1505458D01*
X1041283Y1505167D01*
X1041367Y1504875D01*
X1041575Y1504667D01*
X1041908Y1504542D01*
X1042200Y1504500D01*
G01X1039550Y1490814D02*
Y1494814D01*
X1032150D01*
G01X1040017Y1473981D02*
Y1476481D01*
X1041058D01*
X1041392Y1476356D01*
X1041600Y1476189D01*
X1041683Y1475856D01*
X1041600Y1475523D01*
X1041350Y1475314D01*
X1041058Y1475189D01*
X1040017D01*
G01X1041058D02*
X1041683Y1473981D01*
G01X1043950D02*
Y1476481D01*
X1043450Y1475981D01*
G01Y1473981D02*
X1044450D01*
G01X1047050Y1476481D02*
X1046717Y1476398D01*
X1046467Y1476189D01*
X1046300Y1475939D01*
X1046175Y1475606D01*
X1046133Y1475231D01*
X1046175Y1474856D01*
X1046300Y1474523D01*
X1046467Y1474273D01*
X1046717Y1474064D01*
X1047050Y1473981D01*
X1047383Y1474064D01*
X1047633Y1474273D01*
X1047800Y1474523D01*
X1047925Y1474856D01*
X1047967Y1475231D01*
X1047925Y1475606D01*
X1047800Y1475939D01*
X1047633Y1476189D01*
X1047383Y1476398D01*
X1047050Y1476481D01*
G01X1049358Y1475023D02*
X1049650Y1475314D01*
X1049900Y1475481D01*
X1050233Y1475564D01*
X1050525Y1475481D01*
X1050733Y1475314D01*
X1050900Y1475064D01*
X1050942Y1474773D01*
X1050900Y1474523D01*
X1050733Y1474273D01*
X1050483Y1474064D01*
X1050192Y1473981D01*
X1049858Y1474064D01*
X1049567Y1474314D01*
X1049400Y1474689D01*
X1049358Y1475106D01*
X1049442Y1475648D01*
X1049567Y1475939D01*
X1049775Y1476231D01*
X1050067Y1476439D01*
X1050358Y1476481D01*
X1050650Y1476398D01*
X1050858Y1476189D01*
G01X1052458Y1476064D02*
X1052708Y1476314D01*
X1053000Y1476439D01*
X1053333Y1476481D01*
X1053750Y1476398D01*
X1054042Y1476189D01*
X1054125Y1475939D01*
X1054083Y1475689D01*
X1053917Y1475481D01*
X1053083Y1475064D01*
X1052708Y1474773D01*
X1052458Y1474356D01*
X1052375Y1473981D01*
X1054125D01*
G01X988742Y1475779D02*
X988617Y1475529D01*
X988534Y1475237D01*
Y1474904D01*
X988659Y1474529D01*
X988867Y1474237D01*
X989117Y1474029D01*
X989534Y1473862D01*
X989909Y1473820D01*
X990284Y1473904D01*
X990534Y1474029D01*
X990784Y1474279D01*
X990951Y1474570D01*
X991034Y1474862D01*
Y1475154D01*
X990951Y1475445D01*
X990826Y1475695D01*
X990659Y1475904D01*
G01Y1477045D02*
X990867Y1477295D01*
X990992Y1477587D01*
X991034Y1477962D01*
X990951Y1478337D01*
X990784Y1478629D01*
X990492Y1478837D01*
X990159Y1478879D01*
X989826Y1478795D01*
X989617Y1478587D01*
X989451Y1478295D01*
X989409Y1478004D01*
X989451Y1477712D01*
X989617Y1477337D01*
X988534Y1477462D01*
Y1478587D01*
G01X990659Y1480145D02*
X990867Y1480395D01*
X990992Y1480687D01*
X991034Y1481062D01*
X990951Y1481437D01*
X990784Y1481729D01*
X990492Y1481937D01*
X990159Y1481979D01*
X989826Y1481895D01*
X989617Y1481687D01*
X989451Y1481395D01*
X989409Y1481104D01*
X989451Y1480812D01*
X989617Y1480437D01*
X988534Y1480562D01*
Y1481687D01*
G01X991034Y1484162D02*
X990992Y1484454D01*
X990867Y1484787D01*
X990659Y1484995D01*
X990367Y1485079D01*
X990076Y1484995D01*
X989826Y1484745D01*
X989701Y1484370D01*
Y1483954D01*
X989617Y1483704D01*
X989409Y1483495D01*
X989117Y1483412D01*
X988826Y1483537D01*
X988617Y1483829D01*
X988534Y1484162D01*
X988617Y1484495D01*
X988826Y1484787D01*
X989117Y1484912D01*
X989409Y1484829D01*
X989617Y1484620D01*
X989701Y1484370D01*
Y1483954D01*
X989826Y1483579D01*
X990076Y1483329D01*
X990367Y1483245D01*
X990659Y1483329D01*
X990867Y1483537D01*
X990992Y1483870D01*
X991034Y1484162D01*
G01X960516Y1442772D02*
Y1455772D01*
G01X1008704Y1485440D02*
X1008371Y1485482D01*
X1008079Y1485648D01*
X1007829Y1485898D01*
X1007662Y1486190D01*
X1007579Y1486523D01*
Y1486857D01*
X1007662Y1487190D01*
X1007829Y1487482D01*
X1008079Y1487732D01*
X1008371Y1487898D01*
X1008704Y1487940D01*
X1009037Y1487898D01*
X1009329Y1487732D01*
X1009579Y1487482D01*
X1009746Y1487190D01*
X1009829Y1486857D01*
Y1486523D01*
X1009746Y1486190D01*
X1009579Y1485898D01*
X1009329Y1485648D01*
X1009037Y1485482D01*
X1008704Y1485440D01*
G01X1009037Y1486107D02*
X1009537Y1485440D01*
G01X1011012Y1487523D02*
X1011262Y1487773D01*
X1011554Y1487898D01*
X1011887Y1487940D01*
X1012304Y1487857D01*
X1012596Y1487648D01*
X1012679Y1487398D01*
X1012637Y1487148D01*
X1012471Y1486940D01*
X1011637Y1486523D01*
X1011262Y1486232D01*
X1011012Y1485815D01*
X1010929Y1485440D01*
X1012679D01*
G01X1014904D02*
Y1487940D01*
X1014404Y1487440D01*
G01Y1485440D02*
X1015404D01*
G01X1018004Y1487940D02*
X1017671Y1487857D01*
X1017421Y1487648D01*
X1017254Y1487398D01*
X1017129Y1487065D01*
X1017087Y1486690D01*
X1017129Y1486315D01*
X1017254Y1485982D01*
X1017421Y1485732D01*
X1017671Y1485523D01*
X1018004Y1485440D01*
X1018337Y1485523D01*
X1018587Y1485732D01*
X1018754Y1485982D01*
X1018879Y1486315D01*
X1018921Y1486690D01*
X1018879Y1487065D01*
X1018754Y1487398D01*
X1018587Y1487648D01*
X1018337Y1487857D01*
X1018004Y1487940D01*
G01X1034550Y1476314D02*
Y1490314D01*
G01X1021550Y1476314D02*
X1034550D01*
G01X1021550Y1490314D02*
Y1476314D01*
G01X1034550Y1490314D02*
X1021550D01*
G01X967243Y1433899D02*
Y1429899D01*
X974643D01*
G01X973012Y1474435D02*
X970512D01*
Y1475476D01*
X970637Y1475810D01*
X970804Y1476018D01*
X971137Y1476101D01*
X971470Y1476018D01*
X971679Y1475768D01*
X971804Y1475476D01*
Y1474435D01*
G01Y1475476D02*
X973012Y1476101D01*
G01Y1478368D02*
X970512D01*
X971012Y1477868D01*
G01X973012D02*
Y1478868D01*
G01X970512Y1481468D02*
X970595Y1481135D01*
X970804Y1480885D01*
X971054Y1480718D01*
X971387Y1480593D01*
X971762Y1480551D01*
X972137Y1480593D01*
X972470Y1480718D01*
X972720Y1480885D01*
X972929Y1481135D01*
X973012Y1481468D01*
X972929Y1481801D01*
X972720Y1482051D01*
X972470Y1482218D01*
X972137Y1482343D01*
X971762Y1482385D01*
X971387Y1482343D01*
X971054Y1482218D01*
X970804Y1482051D01*
X970595Y1481801D01*
X970512Y1481468D01*
G01X970929Y1483776D02*
X970679Y1484026D01*
X970554Y1484318D01*
X970512Y1484651D01*
X970595Y1485068D01*
X970804Y1485360D01*
X971054Y1485443D01*
X971304Y1485401D01*
X971512Y1485235D01*
X971929Y1484401D01*
X972220Y1484026D01*
X972637Y1483776D01*
X973012Y1483693D01*
Y1485443D01*
G01Y1488168D02*
X970512D01*
X972304Y1486626D01*
Y1488710D01*
G01X973438Y1448208D02*
X977438D01*
Y1455608D01*
G01X963143Y1447399D02*
Y1443399D01*
X970543D01*
G01X963143D02*
Y1439399D01*
X970543D01*
G01X1001926Y1459899D02*
Y1458107D01*
X1002093Y1457732D01*
X1002426Y1457482D01*
X1002843Y1457399D01*
X1003260Y1457482D01*
X1003593Y1457732D01*
X1003760Y1458107D01*
Y1459899D01*
G01X1005151Y1459482D02*
X1005401Y1459732D01*
X1005693Y1459857D01*
X1006026Y1459899D01*
X1006443Y1459816D01*
X1006735Y1459607D01*
X1006818Y1459357D01*
X1006776Y1459107D01*
X1006610Y1458899D01*
X1005776Y1458482D01*
X1005401Y1458191D01*
X1005151Y1457774D01*
X1005068Y1457399D01*
X1006818D01*
G01X1008251Y1459482D02*
X1008501Y1459732D01*
X1008793Y1459857D01*
X1009126Y1459899D01*
X1009543Y1459816D01*
X1009835Y1459607D01*
X1009918Y1459357D01*
X1009876Y1459107D01*
X1009710Y1458899D01*
X1008876Y1458482D01*
X1008501Y1458191D01*
X1008251Y1457774D01*
X1008168Y1457399D01*
X1009918D01*
G01X998430Y1457349D02*
Y1454349D01*
G01X1013393Y1436479D02*
X1010393D01*
G01X981493Y1438447D02*
X984493D01*
G01X982493Y1448287D02*
X984493D01*
G01X1012393Y1446319D02*
X1010393D01*
G01X983593Y1450249D02*
Y1455249D01*
X988593D01*
G01X1011293Y1450249D02*
Y1455249D01*
X1006293D01*
G01X1049500Y1460050D02*
X1049458Y1459717D01*
X1049292Y1459425D01*
X1049042Y1459175D01*
X1048750Y1459008D01*
X1048417Y1458925D01*
X1048083D01*
X1047750Y1459008D01*
X1047458Y1459175D01*
X1047208Y1459425D01*
X1047042Y1459717D01*
X1047000Y1460050D01*
X1047042Y1460383D01*
X1047208Y1460675D01*
X1047458Y1460925D01*
X1047750Y1461092D01*
X1048083Y1461175D01*
X1048417D01*
X1048750Y1461092D01*
X1049042Y1460925D01*
X1049292Y1460675D01*
X1049458Y1460383D01*
X1049500Y1460050D01*
G01X1048833Y1460383D02*
X1049500Y1460883D01*
G01X1047417Y1462358D02*
X1047167Y1462608D01*
X1047042Y1462900D01*
X1047000Y1463233D01*
X1047083Y1463650D01*
X1047292Y1463942D01*
X1047542Y1464025D01*
X1047792Y1463983D01*
X1048000Y1463817D01*
X1048417Y1462983D01*
X1048708Y1462608D01*
X1049125Y1462358D01*
X1049500Y1462275D01*
Y1464025D01*
G01X1047000Y1466250D02*
X1047083Y1465917D01*
X1047292Y1465667D01*
X1047542Y1465500D01*
X1047875Y1465375D01*
X1048250Y1465333D01*
X1048625Y1465375D01*
X1048958Y1465500D01*
X1049208Y1465667D01*
X1049417Y1465917D01*
X1049500Y1466250D01*
X1049417Y1466583D01*
X1049208Y1466833D01*
X1048958Y1467000D01*
X1048625Y1467125D01*
X1048250Y1467167D01*
X1047875Y1467125D01*
X1047542Y1467000D01*
X1047292Y1466833D01*
X1047083Y1466583D01*
X1047000Y1466250D01*
G01X1049208Y1468642D02*
X1049417Y1468933D01*
X1049500Y1469267D01*
X1049417Y1469600D01*
X1049167Y1469892D01*
X1048792Y1470100D01*
X1048417Y1470183D01*
X1047958D01*
X1047583Y1470100D01*
X1047250Y1469892D01*
X1047083Y1469642D01*
X1047000Y1469350D01*
X1047083Y1469017D01*
X1047250Y1468767D01*
X1047500Y1468600D01*
X1047833Y1468517D01*
X1048125Y1468600D01*
X1048417Y1468808D01*
X1048583Y1469058D01*
X1048625Y1469350D01*
X1048542Y1469683D01*
X1048333Y1469933D01*
X1047958Y1470183D01*
G01X1037663Y1461141D02*
Y1475141D01*
G01X1024663Y1461141D02*
X1037663D01*
G01X1024663Y1475141D02*
Y1461141D01*
G01X1037663Y1475141D02*
X1024663D01*
G01X1046943Y1441932D02*
X1048735D01*
X1049110Y1442099D01*
X1049360Y1442432D01*
X1049443Y1442849D01*
X1049360Y1443266D01*
X1049110Y1443599D01*
X1048735Y1443766D01*
X1046943D01*
G01X1049443Y1445949D02*
X1046943D01*
X1047443Y1445449D01*
G01X1049443D02*
Y1446449D01*
G01X1022443Y1434699D02*
Y1448099D01*
G01X1032443Y1434699D02*
X1022443D01*
G01X1032443Y1448099D02*
Y1434699D01*
G01X1022443Y1448099D02*
X1032443D01*
G01X1054850Y1470500D02*
X1054517Y1470542D01*
X1054225Y1470708D01*
X1053975Y1470958D01*
X1053808Y1471250D01*
X1053725Y1471583D01*
Y1471917D01*
X1053808Y1472250D01*
X1053975Y1472542D01*
X1054225Y1472792D01*
X1054517Y1472958D01*
X1054850Y1473000D01*
X1055183Y1472958D01*
X1055475Y1472792D01*
X1055725Y1472542D01*
X1055892Y1472250D01*
X1055975Y1471917D01*
Y1471583D01*
X1055892Y1471250D01*
X1055725Y1470958D01*
X1055475Y1470708D01*
X1055183Y1470542D01*
X1054850Y1470500D01*
G01X1055183Y1471167D02*
X1055683Y1470500D01*
G01X1057158Y1472583D02*
X1057408Y1472833D01*
X1057700Y1472958D01*
X1058033Y1473000D01*
X1058450Y1472917D01*
X1058742Y1472708D01*
X1058825Y1472458D01*
X1058783Y1472208D01*
X1058617Y1472000D01*
X1057783Y1471583D01*
X1057408Y1471292D01*
X1057158Y1470875D01*
X1057075Y1470500D01*
X1058825D01*
G01X1061050Y1473000D02*
X1060717Y1472917D01*
X1060467Y1472708D01*
X1060300Y1472458D01*
X1060175Y1472125D01*
X1060133Y1471750D01*
X1060175Y1471375D01*
X1060300Y1471042D01*
X1060467Y1470792D01*
X1060717Y1470583D01*
X1061050Y1470500D01*
X1061383Y1470583D01*
X1061633Y1470792D01*
X1061800Y1471042D01*
X1061925Y1471375D01*
X1061967Y1471750D01*
X1061925Y1472125D01*
X1061800Y1472458D01*
X1061633Y1472708D01*
X1061383Y1472917D01*
X1061050Y1473000D01*
G01X1064150Y1470500D02*
X1064442Y1470542D01*
X1064775Y1470667D01*
X1064983Y1470875D01*
X1065067Y1471167D01*
X1064983Y1471458D01*
X1064733Y1471708D01*
X1064358Y1471833D01*
X1063942D01*
X1063692Y1471917D01*
X1063483Y1472125D01*
X1063400Y1472417D01*
X1063525Y1472708D01*
X1063817Y1472917D01*
X1064150Y1473000D01*
X1064483Y1472917D01*
X1064775Y1472708D01*
X1064900Y1472417D01*
X1064817Y1472125D01*
X1064608Y1471917D01*
X1064358Y1471833D01*
X1063942D01*
X1063567Y1471708D01*
X1063317Y1471458D01*
X1063233Y1471167D01*
X1063317Y1470875D01*
X1063525Y1470667D01*
X1063858Y1470542D01*
X1064150Y1470500D01*
G01X1050800Y1433900D02*
X1043200D01*
G01X1076227Y2824D02*
X1076694Y3290D01*
X1077094Y3557D01*
X1077627Y3690D01*
X1078094Y3557D01*
X1078427Y3290D01*
X1078694Y2890D01*
X1078761Y2424D01*
X1078694Y2024D01*
X1078427Y1624D01*
X1078027Y1290D01*
X1077561Y1157D01*
X1077027Y1290D01*
X1076561Y1690D01*
X1076294Y2290D01*
X1076227Y2957D01*
X1076361Y3824D01*
X1076561Y4290D01*
X1076894Y4757D01*
X1077361Y5090D01*
X1077827Y5157D01*
X1078294Y5024D01*
X1078627Y4690D01*
G01X1073747Y370090D02*
Y388090D01*
G01X1062547Y370090D02*
X1073747D01*
G01X1110400Y435500D02*
Y433000D01*
G01X1109442Y435500D02*
X1111358D01*
G01X1114417Y435292D02*
X1114167Y435417D01*
X1113875Y435500D01*
X1113542D01*
X1113167Y435375D01*
X1112875Y435167D01*
X1112667Y434917D01*
X1112500Y434500D01*
X1112458Y434125D01*
X1112542Y433750D01*
X1112667Y433500D01*
X1112917Y433250D01*
X1113208Y433083D01*
X1113500Y433000D01*
X1113792D01*
X1114083Y433083D01*
X1114333Y433208D01*
X1114542Y433375D01*
G01X1115683Y433500D02*
X1115933Y433208D01*
X1116267Y433042D01*
X1116642Y433000D01*
X1116975Y433042D01*
X1117308Y433250D01*
X1117517Y433500D01*
X1117558Y433750D01*
X1117475Y434042D01*
X1117183Y434250D01*
X1116892Y434333D01*
X1116517D01*
G01X1116892D02*
X1117142Y434458D01*
X1117350Y434667D01*
X1117433Y434917D01*
X1117350Y435167D01*
X1117142Y435375D01*
X1116767Y435500D01*
X1116392Y435458D01*
X1116017Y435292D01*
G01X1098677Y394822D02*
Y426422D01*
X1103377Y431122D01*
X1121977D01*
X1126677Y426422D01*
Y394822D01*
X1098677D01*
G01X1073747Y388090D02*
X1062547D01*
G01X1136365Y558162D02*
X1140365D01*
Y556562D01*
X1140165Y556029D01*
X1139698Y555629D01*
X1139165Y555496D01*
X1138632Y555629D01*
X1138232Y555962D01*
X1138032Y556562D01*
Y558162D01*
G01X1136365Y553162D02*
X1139032D01*
G01X1138498D02*
X1138765Y552829D01*
X1138965Y552496D01*
X1139032Y552029D01*
X1138965Y551696D01*
X1138765Y551296D01*
G01X1138165Y548629D02*
Y546496D01*
X1138632Y546696D01*
X1138898Y547029D01*
X1139032Y547496D01*
X1138965Y547962D01*
X1138765Y548362D01*
X1138298Y548629D01*
X1137898Y548762D01*
X1137498D01*
X1137098Y548629D01*
X1136698Y548296D01*
X1136432Y547896D01*
X1136365Y547429D01*
X1136498Y546962D01*
X1136898Y546496D01*
G01X1136832Y544029D02*
X1136565Y543696D01*
X1136365Y543229D01*
Y542829D01*
X1136498Y542429D01*
X1136698Y542162D01*
X1136965Y542029D01*
X1137365Y542096D01*
X1137565Y542362D01*
X1137965Y543562D01*
X1138432Y543829D01*
X1138765Y543696D01*
X1138965Y543429D01*
X1139032Y543029D01*
X1138965Y542629D01*
X1138765Y542229D01*
G01X1136832Y539429D02*
X1136565Y539096D01*
X1136365Y538629D01*
Y538229D01*
X1136498Y537829D01*
X1136698Y537562D01*
X1136965Y537429D01*
X1137365Y537496D01*
X1137565Y537762D01*
X1137965Y538962D01*
X1138432Y539229D01*
X1138765Y539096D01*
X1138965Y538829D01*
X1139032Y538429D01*
X1138965Y538029D01*
X1138765Y537629D01*
G01X1136365Y530496D02*
X1140365D01*
Y527962D01*
G01X1138432Y528896D02*
Y530496D01*
G01X1139032Y524629D02*
X1136365D01*
G01X1140098D02*
X1140165Y524762D01*
X1140298D01*
X1140365Y524629D01*
X1140298Y524496D01*
X1140165D01*
X1140098Y524629D01*
G01X1140365Y520029D02*
X1136365D01*
G01X1139032Y520962D02*
Y519096D01*
G01X1143515Y565263D02*
Y569463D01*
G01X1082015Y577163D02*
X1143515D01*
Y569463D01*
X1141215D01*
Y565263D01*
X1143515D01*
Y510263D01*
X1082015D01*
Y577163D01*
G01X1110517Y627000D02*
Y629500D01*
X1111558D01*
X1111892Y629375D01*
X1112100Y629208D01*
X1112183Y628875D01*
X1112100Y628542D01*
X1111850Y628333D01*
X1111558Y628208D01*
X1110517D01*
G01X1111558D02*
X1112183Y627000D01*
G01X1114950D02*
Y629500D01*
X1113408Y627708D01*
X1115492D01*
G01X1116842Y627292D02*
X1117133Y627083D01*
X1117467Y627000D01*
X1117800Y627083D01*
X1118092Y627333D01*
X1118300Y627708D01*
X1118383Y628083D01*
Y628542D01*
X1118300Y628917D01*
X1118092Y629250D01*
X1117842Y629417D01*
X1117550Y629500D01*
X1117217Y629417D01*
X1116967Y629250D01*
X1116800Y629000D01*
X1116717Y628667D01*
X1116800Y628375D01*
X1117008Y628083D01*
X1117258Y627917D01*
X1117550Y627875D01*
X1117883Y627958D01*
X1118133Y628167D01*
X1118383Y628542D01*
G01X1120650Y629500D02*
X1120317Y629417D01*
X1120067Y629208D01*
X1119900Y628958D01*
X1119775Y628625D01*
X1119733Y628250D01*
X1119775Y627875D01*
X1119900Y627542D01*
X1120067Y627292D01*
X1120317Y627083D01*
X1120650Y627000D01*
X1120983Y627083D01*
X1121233Y627292D01*
X1121400Y627542D01*
X1121525Y627875D01*
X1121567Y628250D01*
X1121525Y628625D01*
X1121400Y628958D01*
X1121233Y629208D01*
X1120983Y629417D01*
X1120650Y629500D01*
G01X1117825Y623943D02*
X1113825D01*
Y616543D01*
G01X1105967Y582500D02*
Y585000D01*
X1106967D01*
X1107300Y584875D01*
X1107550Y584583D01*
X1107633Y584250D01*
X1107550Y583917D01*
X1107342Y583667D01*
X1106967Y583542D01*
X1105967D01*
G01X1110817Y584792D02*
X1110567Y584917D01*
X1110275Y585000D01*
X1109942D01*
X1109567Y584875D01*
X1109275Y584667D01*
X1109067Y584417D01*
X1108900Y584000D01*
X1108858Y583625D01*
X1108942Y583250D01*
X1109067Y583000D01*
X1109317Y582750D01*
X1109608Y582583D01*
X1109900Y582500D01*
X1110192D01*
X1110483Y582583D01*
X1110733Y582708D01*
X1110942Y582875D01*
G01X1112500Y585000D02*
X1113500D01*
G01X1113000D02*
Y582500D01*
G01X1112500D02*
X1113500D01*
G01X1116933D02*
X1115267D01*
Y585000D01*
X1116933D01*
G01X1116267Y583792D02*
X1115267D01*
G01X1119200Y582500D02*
Y585000D01*
X1118700Y584500D01*
G01Y582500D02*
X1119700D01*
G01X1150834Y745787D02*
X1149667Y746954D01*
X1149000Y747954D01*
X1148667Y749287D01*
X1149000Y750454D01*
X1149667Y751287D01*
X1150667Y751954D01*
X1151833Y752121D01*
X1152833Y751954D01*
X1153834Y751287D01*
X1154667Y750287D01*
X1155000Y749121D01*
X1154667Y747787D01*
X1153667Y746621D01*
X1152167Y745954D01*
X1150500Y745787D01*
X1148334Y746121D01*
X1147167Y746621D01*
X1146000Y747454D01*
X1145167Y748621D01*
X1145000Y749787D01*
X1145333Y750954D01*
X1146167Y751787D01*
G01X1150834Y704787D02*
X1149667Y705954D01*
X1149000Y706954D01*
X1148667Y708287D01*
X1149000Y709454D01*
X1149667Y710287D01*
X1150667Y710954D01*
X1151833Y711121D01*
X1152833Y710954D01*
X1153834Y710287D01*
X1154667Y709287D01*
X1155000Y708121D01*
X1154667Y706787D01*
X1153667Y705621D01*
X1152167Y704954D01*
X1150500Y704787D01*
X1148334Y705121D01*
X1147167Y705621D01*
X1146000Y706454D01*
X1145167Y707621D01*
X1145000Y708787D01*
X1145333Y709954D01*
X1146167Y710787D01*
G01X1075334Y745787D02*
X1074167Y746954D01*
X1073500Y747954D01*
X1073167Y749287D01*
X1073500Y750454D01*
X1074167Y751287D01*
X1075167Y751954D01*
X1076333Y752121D01*
X1077333Y751954D01*
X1078334Y751287D01*
X1079167Y750287D01*
X1079500Y749121D01*
X1079167Y747787D01*
X1078167Y746621D01*
X1076667Y745954D01*
X1075000Y745787D01*
X1072834Y746121D01*
X1071667Y746621D01*
X1070500Y747454D01*
X1069667Y748621D01*
X1069500Y749787D01*
X1069833Y750954D01*
X1070667Y751787D01*
G01X1075334Y704787D02*
X1074167Y705954D01*
X1073500Y706954D01*
X1073167Y708287D01*
X1073500Y709454D01*
X1074167Y710287D01*
X1075167Y710954D01*
X1076333Y711121D01*
X1077333Y710954D01*
X1078334Y710287D01*
X1079167Y709287D01*
X1079500Y708121D01*
X1079167Y706787D01*
X1078167Y705621D01*
X1076667Y704954D01*
X1075000Y704787D01*
X1072834Y705121D01*
X1071667Y705621D01*
X1070500Y706454D01*
X1069667Y707621D01*
X1069500Y708787D01*
X1069833Y709954D01*
X1070667Y710787D01*
G01X1140715Y938242D02*
Y934242D01*
X1143515D01*
Y682292D01*
X1082015D01*
Y947392D01*
G01X1155000Y857454D02*
X1154833Y858621D01*
X1154333Y859954D01*
X1153500Y860787D01*
X1152333Y861121D01*
X1151167Y860787D01*
X1150167Y859787D01*
X1149667Y858287D01*
Y856621D01*
X1149333Y855621D01*
X1148500Y854787D01*
X1147333Y854454D01*
X1146167Y854954D01*
X1145333Y856120D01*
X1145000Y857454D01*
X1145333Y858787D01*
X1146167Y859954D01*
X1147333Y860454D01*
X1148500Y860121D01*
X1149333Y859287D01*
X1149667Y858287D01*
Y856621D01*
X1150167Y855121D01*
X1151167Y854121D01*
X1152333Y853787D01*
X1153500Y854121D01*
X1154333Y854954D01*
X1154833Y856287D01*
X1155000Y857454D01*
G01Y802954D02*
X1154833Y804121D01*
X1154333Y805454D01*
X1153500Y806287D01*
X1152333Y806621D01*
X1151167Y806287D01*
X1150167Y805287D01*
X1149667Y803787D01*
Y802121D01*
X1149333Y801121D01*
X1148500Y800287D01*
X1147333Y799954D01*
X1146167Y800454D01*
X1145333Y801620D01*
X1145000Y802954D01*
X1145333Y804287D01*
X1146167Y805454D01*
X1147333Y805954D01*
X1148500Y805621D01*
X1149333Y804787D01*
X1149667Y803787D01*
Y802121D01*
X1150167Y800621D01*
X1151167Y799621D01*
X1152333Y799287D01*
X1153500Y799621D01*
X1154333Y800454D01*
X1154833Y801787D01*
X1155000Y802954D01*
G01X1079500Y857454D02*
X1079333Y858621D01*
X1078833Y859954D01*
X1078000Y860787D01*
X1076833Y861121D01*
X1075667Y860787D01*
X1074667Y859787D01*
X1074167Y858287D01*
Y856621D01*
X1073833Y855621D01*
X1073000Y854787D01*
X1071833Y854454D01*
X1070667Y854954D01*
X1069833Y856120D01*
X1069500Y857454D01*
X1069833Y858787D01*
X1070667Y859954D01*
X1071833Y860454D01*
X1073000Y860121D01*
X1073833Y859287D01*
X1074167Y858287D01*
Y856621D01*
X1074667Y855121D01*
X1075667Y854121D01*
X1076833Y853787D01*
X1078000Y854121D01*
X1078833Y854954D01*
X1079333Y856287D01*
X1079500Y857454D01*
G01Y802954D02*
X1079333Y804121D01*
X1078833Y805454D01*
X1078000Y806287D01*
X1076833Y806621D01*
X1075667Y806287D01*
X1074667Y805287D01*
X1074167Y803787D01*
Y802121D01*
X1073833Y801121D01*
X1073000Y800287D01*
X1071833Y799954D01*
X1070667Y800454D01*
X1069833Y801620D01*
X1069500Y802954D01*
X1069833Y804287D01*
X1070667Y805454D01*
X1071833Y805954D01*
X1073000Y805621D01*
X1073833Y804787D01*
X1074167Y803787D01*
Y802121D01*
X1074667Y800621D01*
X1075667Y799621D01*
X1076833Y799287D01*
X1078000Y799621D01*
X1078833Y800454D01*
X1079333Y801787D01*
X1079500Y802954D01*
G01X1137715Y835075D02*
X1141715D01*
Y833475D01*
X1141515Y832942D01*
X1141048Y832542D01*
X1140515Y832409D01*
X1139982Y832542D01*
X1139582Y832875D01*
X1139382Y833475D01*
Y835075D01*
G01X1137715Y830075D02*
X1140382D01*
G01X1139848D02*
X1140115Y829742D01*
X1140315Y829409D01*
X1140382Y828942D01*
X1140315Y828609D01*
X1140115Y828209D01*
G01X1139515Y825542D02*
Y823409D01*
X1139982Y823609D01*
X1140248Y823942D01*
X1140382Y824409D01*
X1140315Y824875D01*
X1140115Y825275D01*
X1139648Y825542D01*
X1139248Y825675D01*
X1138848D01*
X1138448Y825542D01*
X1138048Y825209D01*
X1137782Y824809D01*
X1137715Y824342D01*
X1137848Y823875D01*
X1138248Y823409D01*
G01X1138182Y820942D02*
X1137915Y820609D01*
X1137715Y820142D01*
Y819742D01*
X1137848Y819342D01*
X1138048Y819075D01*
X1138315Y818942D01*
X1138715Y819009D01*
X1138915Y819275D01*
X1139315Y820475D01*
X1139782Y820742D01*
X1140115Y820609D01*
X1140315Y820342D01*
X1140382Y819942D01*
X1140315Y819542D01*
X1140115Y819142D01*
G01X1138182Y816342D02*
X1137915Y816009D01*
X1137715Y815542D01*
Y815142D01*
X1137848Y814742D01*
X1138048Y814475D01*
X1138315Y814342D01*
X1138715Y814409D01*
X1138915Y814675D01*
X1139315Y815875D01*
X1139782Y816142D01*
X1140115Y816009D01*
X1140315Y815742D01*
X1140382Y815342D01*
X1140315Y814942D01*
X1140115Y814542D01*
G01X1137715Y807409D02*
X1141715D01*
Y804875D01*
G01X1139782Y805809D02*
Y807409D01*
G01X1140382Y801542D02*
X1137715D01*
G01X1141448D02*
X1141515Y801675D01*
X1141648D01*
X1141715Y801542D01*
X1141648Y801409D01*
X1141515D01*
X1141448Y801542D01*
G01X1141715Y796942D02*
X1137715D01*
G01X1140382Y797875D02*
Y796009D01*
G01X1155000Y915454D02*
X1154833Y916621D01*
X1154333Y917954D01*
X1153500Y918787D01*
X1152333Y919121D01*
X1151167Y918787D01*
X1150167Y917787D01*
X1149667Y916287D01*
Y914621D01*
X1149333Y913621D01*
X1148500Y912787D01*
X1147333Y912454D01*
X1146167Y912954D01*
X1145333Y914120D01*
X1145000Y915454D01*
X1145333Y916787D01*
X1146167Y917954D01*
X1147333Y918454D01*
X1148500Y918121D01*
X1149333Y917287D01*
X1149667Y916287D01*
Y914621D01*
X1150167Y913121D01*
X1151167Y912121D01*
X1152333Y911787D01*
X1153500Y912121D01*
X1154333Y912954D01*
X1154833Y914287D01*
X1155000Y915454D01*
G01X1079500D02*
X1079333Y916621D01*
X1078833Y917954D01*
X1078000Y918787D01*
X1076833Y919121D01*
X1075667Y918787D01*
X1074667Y917787D01*
X1074167Y916287D01*
Y914621D01*
X1073833Y913621D01*
X1073000Y912787D01*
X1071833Y912454D01*
X1070667Y912954D01*
X1069833Y914120D01*
X1069500Y915454D01*
X1069833Y916787D01*
X1070667Y917954D01*
X1071833Y918454D01*
X1073000Y918121D01*
X1073833Y917287D01*
X1074167Y916287D01*
Y914621D01*
X1074667Y913121D01*
X1075667Y912121D01*
X1076833Y911787D01*
X1078000Y912121D01*
X1078833Y912954D01*
X1079333Y914287D01*
X1079500Y915454D01*
G01X1126675Y950333D02*
X1127008Y950125D01*
X1127383Y950000D01*
X1127717D01*
X1128050Y950125D01*
X1128300Y950333D01*
X1128425Y950625D01*
X1128342Y950917D01*
X1128133Y951167D01*
X1127758Y951333D01*
X1127258Y951417D01*
X1126967Y951583D01*
X1126842Y951875D01*
X1126925Y952167D01*
X1127133Y952375D01*
X1127425Y952500D01*
X1127717D01*
X1128008Y952417D01*
X1128258Y952208D01*
G01X1129608Y950000D02*
X1130650Y952500D01*
X1131692Y950000D01*
G01X1131317Y950875D02*
X1129983D01*
G01X1132875Y950333D02*
X1133208Y950125D01*
X1133583Y950000D01*
X1133917D01*
X1134250Y950125D01*
X1134500Y950333D01*
X1134625Y950625D01*
X1134542Y950917D01*
X1134333Y951167D01*
X1133958Y951333D01*
X1133458Y951417D01*
X1133167Y951583D01*
X1133042Y951875D01*
X1133125Y952167D01*
X1133333Y952375D01*
X1133625Y952500D01*
X1133917D01*
X1134208Y952417D01*
X1134458Y952208D01*
G01X1136850Y950000D02*
Y952500D01*
X1136350Y952000D01*
G01Y950000D02*
X1137350D01*
G01X1140715Y938242D02*
X1143515D01*
Y947392D01*
X1082015D01*
G01X1129826Y1140971D02*
X1133826D01*
Y1139371D01*
X1133626Y1138838D01*
X1133159Y1138438D01*
X1132626Y1138305D01*
X1132093Y1138438D01*
X1131693Y1138771D01*
X1131493Y1139371D01*
Y1140971D01*
G01X1129826Y1135971D02*
X1132493D01*
G01X1131959D02*
X1132226Y1135638D01*
X1132426Y1135305D01*
X1132493Y1134838D01*
X1132426Y1134505D01*
X1132226Y1134105D01*
G01X1131626Y1131438D02*
Y1129305D01*
X1132093Y1129505D01*
X1132359Y1129838D01*
X1132493Y1130305D01*
X1132426Y1130771D01*
X1132226Y1131171D01*
X1131759Y1131438D01*
X1131359Y1131571D01*
X1130959D01*
X1130559Y1131438D01*
X1130159Y1131105D01*
X1129893Y1130705D01*
X1129826Y1130238D01*
X1129959Y1129771D01*
X1130359Y1129305D01*
G01X1129826Y1122505D02*
X1133826D01*
Y1119971D01*
G01X1131893Y1120905D02*
Y1122505D01*
G01X1132493Y1116638D02*
X1129826D01*
G01X1133559D02*
X1133626Y1116771D01*
X1133759D01*
X1133826Y1116638D01*
X1133759Y1116505D01*
X1133626D01*
X1133559Y1116638D01*
G01X1133826Y1112038D02*
X1129826D01*
G01X1132493Y1112971D02*
Y1111105D01*
G01X1093726Y1138338D02*
X1134026D01*
Y1114338D01*
X1093726D01*
Y1138338D01*
G01X1118000Y1233400D02*
Y1230900D01*
G01X1117042Y1233400D02*
X1118958D01*
G01X1122017Y1233192D02*
X1121767Y1233317D01*
X1121475Y1233400D01*
X1121142D01*
X1120767Y1233275D01*
X1120475Y1233067D01*
X1120267Y1232817D01*
X1120100Y1232400D01*
X1120058Y1232025D01*
X1120142Y1231650D01*
X1120267Y1231400D01*
X1120517Y1231150D01*
X1120808Y1230983D01*
X1121100Y1230900D01*
X1121392D01*
X1121683Y1230983D01*
X1121933Y1231108D01*
X1122142Y1231275D01*
G01X1123283D02*
X1123533Y1231067D01*
X1123825Y1230942D01*
X1124200Y1230900D01*
X1124575Y1230983D01*
X1124867Y1231150D01*
X1125075Y1231442D01*
X1125117Y1231775D01*
X1125033Y1232108D01*
X1124825Y1232317D01*
X1124533Y1232483D01*
X1124242Y1232525D01*
X1123950Y1232483D01*
X1123575Y1232317D01*
X1123700Y1233400D01*
X1124825D01*
G01X1107600Y1193250D02*
Y1224850D01*
X1112300Y1229550D01*
X1130900D01*
X1135600Y1224850D01*
Y1193250D01*
X1107600D01*
G01X1125308Y1321017D02*
X1125183Y1320767D01*
X1125100Y1320475D01*
Y1320142D01*
X1125225Y1319767D01*
X1125433Y1319475D01*
X1125683Y1319267D01*
X1126100Y1319100D01*
X1126475Y1319058D01*
X1126850Y1319142D01*
X1127100Y1319267D01*
X1127350Y1319517D01*
X1127517Y1319808D01*
X1127600Y1320100D01*
Y1320392D01*
X1127517Y1320683D01*
X1127392Y1320933D01*
X1127225Y1321142D01*
G01X1127600Y1323200D02*
X1125100D01*
X1125600Y1322700D01*
G01X1127600D02*
Y1323700D01*
G01X1127308Y1325592D02*
X1127517Y1325883D01*
X1127600Y1326217D01*
X1127517Y1326550D01*
X1127267Y1326842D01*
X1126892Y1327050D01*
X1126517Y1327133D01*
X1126058D01*
X1125683Y1327050D01*
X1125350Y1326842D01*
X1125183Y1326592D01*
X1125100Y1326300D01*
X1125183Y1325967D01*
X1125350Y1325717D01*
X1125600Y1325550D01*
X1125933Y1325467D01*
X1126225Y1325550D01*
X1126517Y1325758D01*
X1126683Y1326008D01*
X1126725Y1326300D01*
X1126642Y1326633D01*
X1126433Y1326883D01*
X1126058Y1327133D01*
G01X1061567Y1304700D02*
Y1307200D01*
X1062608D01*
X1062942Y1307075D01*
X1063150Y1306908D01*
X1063233Y1306575D01*
X1063150Y1306242D01*
X1062900Y1306033D01*
X1062608Y1305908D01*
X1061567D01*
G01X1062608D02*
X1063233Y1304700D01*
G01X1065500D02*
X1065792Y1304742D01*
X1066125Y1304867D01*
X1066333Y1305075D01*
X1066417Y1305367D01*
X1066333Y1305658D01*
X1066083Y1305908D01*
X1065708Y1306033D01*
X1065292D01*
X1065042Y1306117D01*
X1064833Y1306325D01*
X1064750Y1306617D01*
X1064875Y1306908D01*
X1065167Y1307117D01*
X1065500Y1307200D01*
X1065833Y1307117D01*
X1066125Y1306908D01*
X1066250Y1306617D01*
X1066167Y1306325D01*
X1065958Y1306117D01*
X1065708Y1306033D01*
X1065292D01*
X1064917Y1305908D01*
X1064667Y1305658D01*
X1064583Y1305367D01*
X1064667Y1305075D01*
X1064875Y1304867D01*
X1065208Y1304742D01*
X1065500Y1304700D01*
G01X1067892Y1304992D02*
X1068183Y1304783D01*
X1068517Y1304700D01*
X1068850Y1304783D01*
X1069142Y1305033D01*
X1069350Y1305408D01*
X1069433Y1305783D01*
Y1306242D01*
X1069350Y1306617D01*
X1069142Y1306950D01*
X1068892Y1307117D01*
X1068600Y1307200D01*
X1068267Y1307117D01*
X1068017Y1306950D01*
X1067850Y1306700D01*
X1067767Y1306367D01*
X1067850Y1306075D01*
X1068058Y1305783D01*
X1068308Y1305617D01*
X1068600Y1305575D01*
X1068933Y1305658D01*
X1069183Y1305867D01*
X1069433Y1306242D01*
G01X1073400Y1311495D02*
Y1307495D01*
X1080800D01*
G01X1061567Y1299700D02*
Y1302200D01*
X1062608D01*
X1062942Y1302075D01*
X1063150Y1301908D01*
X1063233Y1301575D01*
X1063150Y1301242D01*
X1062900Y1301033D01*
X1062608Y1300908D01*
X1061567D01*
G01X1062608D02*
X1063233Y1299700D01*
G01X1064792Y1299992D02*
X1065083Y1299783D01*
X1065417Y1299700D01*
X1065750Y1299783D01*
X1066042Y1300033D01*
X1066250Y1300408D01*
X1066333Y1300783D01*
Y1301242D01*
X1066250Y1301617D01*
X1066042Y1301950D01*
X1065792Y1302117D01*
X1065500Y1302200D01*
X1065167Y1302117D01*
X1064917Y1301950D01*
X1064750Y1301700D01*
X1064667Y1301367D01*
X1064750Y1301075D01*
X1064958Y1300783D01*
X1065208Y1300617D01*
X1065500Y1300575D01*
X1065833Y1300658D01*
X1066083Y1300867D01*
X1066333Y1301242D01*
G01X1068600Y1302200D02*
X1068267Y1302117D01*
X1068017Y1301908D01*
X1067850Y1301658D01*
X1067725Y1301325D01*
X1067683Y1300950D01*
X1067725Y1300575D01*
X1067850Y1300242D01*
X1068017Y1299992D01*
X1068267Y1299783D01*
X1068600Y1299700D01*
X1068933Y1299783D01*
X1069183Y1299992D01*
X1069350Y1300242D01*
X1069475Y1300575D01*
X1069517Y1300950D01*
X1069475Y1301325D01*
X1069350Y1301658D01*
X1069183Y1301908D01*
X1068933Y1302117D01*
X1068600Y1302200D01*
G01X1073400Y1306495D02*
Y1302495D01*
X1080800D01*
G01X1061567Y1294200D02*
Y1296700D01*
X1062608D01*
X1062942Y1296575D01*
X1063150Y1296408D01*
X1063233Y1296075D01*
X1063150Y1295742D01*
X1062900Y1295533D01*
X1062608Y1295408D01*
X1061567D01*
G01X1062608D02*
X1063233Y1294200D01*
G01X1064792Y1294492D02*
X1065083Y1294283D01*
X1065417Y1294200D01*
X1065750Y1294283D01*
X1066042Y1294533D01*
X1066250Y1294908D01*
X1066333Y1295283D01*
Y1295742D01*
X1066250Y1296117D01*
X1066042Y1296450D01*
X1065792Y1296617D01*
X1065500Y1296700D01*
X1065167Y1296617D01*
X1064917Y1296450D01*
X1064750Y1296200D01*
X1064667Y1295867D01*
X1064750Y1295575D01*
X1064958Y1295283D01*
X1065208Y1295117D01*
X1065500Y1295075D01*
X1065833Y1295158D01*
X1066083Y1295367D01*
X1066333Y1295742D01*
G01X1068600Y1294200D02*
Y1296700D01*
X1068100Y1296200D01*
G01Y1294200D02*
X1069100D01*
G01X1073400Y1301375D02*
Y1297375D01*
X1080800D01*
G01X1061567Y1287700D02*
Y1290200D01*
X1062608D01*
X1062942Y1290075D01*
X1063150Y1289908D01*
X1063233Y1289575D01*
X1063150Y1289242D01*
X1062900Y1289033D01*
X1062608Y1288908D01*
X1061567D01*
G01X1062608D02*
X1063233Y1287700D01*
G01X1064792Y1287992D02*
X1065083Y1287783D01*
X1065417Y1287700D01*
X1065750Y1287783D01*
X1066042Y1288033D01*
X1066250Y1288408D01*
X1066333Y1288783D01*
Y1289242D01*
X1066250Y1289617D01*
X1066042Y1289950D01*
X1065792Y1290117D01*
X1065500Y1290200D01*
X1065167Y1290117D01*
X1064917Y1289950D01*
X1064750Y1289700D01*
X1064667Y1289367D01*
X1064750Y1289075D01*
X1064958Y1288783D01*
X1065208Y1288617D01*
X1065500Y1288575D01*
X1065833Y1288658D01*
X1066083Y1288867D01*
X1066333Y1289242D01*
G01X1067808Y1289783D02*
X1068058Y1290033D01*
X1068350Y1290158D01*
X1068683Y1290200D01*
X1069100Y1290117D01*
X1069392Y1289908D01*
X1069475Y1289658D01*
X1069433Y1289408D01*
X1069267Y1289200D01*
X1068433Y1288783D01*
X1068058Y1288492D01*
X1067808Y1288075D01*
X1067725Y1287700D01*
X1069475D01*
G01X1073400Y1294460D02*
Y1290460D01*
X1080800D01*
G01X1129667Y1286300D02*
Y1288800D01*
X1130708D01*
X1131042Y1288675D01*
X1131250Y1288508D01*
X1131333Y1288175D01*
X1131250Y1287842D01*
X1131000Y1287633D01*
X1130708Y1287508D01*
X1129667D01*
G01X1130708D02*
X1131333Y1286300D01*
G01X1132892Y1286592D02*
X1133183Y1286383D01*
X1133517Y1286300D01*
X1133850Y1286383D01*
X1134142Y1286633D01*
X1134350Y1287008D01*
X1134433Y1287383D01*
Y1287842D01*
X1134350Y1288217D01*
X1134142Y1288550D01*
X1133892Y1288717D01*
X1133600Y1288800D01*
X1133267Y1288717D01*
X1133017Y1288550D01*
X1132850Y1288300D01*
X1132767Y1287967D01*
X1132850Y1287675D01*
X1133058Y1287383D01*
X1133308Y1287217D01*
X1133600Y1287175D01*
X1133933Y1287258D01*
X1134183Y1287467D01*
X1134433Y1287842D01*
G01X1135783Y1286800D02*
X1136033Y1286508D01*
X1136367Y1286342D01*
X1136742Y1286300D01*
X1137075Y1286342D01*
X1137408Y1286550D01*
X1137617Y1286800D01*
X1137658Y1287050D01*
X1137575Y1287342D01*
X1137283Y1287550D01*
X1136992Y1287633D01*
X1136617D01*
G01X1136992D02*
X1137242Y1287758D01*
X1137450Y1287967D01*
X1137533Y1288217D01*
X1137450Y1288467D01*
X1137242Y1288675D01*
X1136867Y1288800D01*
X1136492Y1288758D01*
X1136117Y1288592D01*
G01X1132200Y1289700D02*
Y1293700D01*
X1124800D01*
G01X1124517Y1300700D02*
Y1303200D01*
X1125558D01*
X1125892Y1303075D01*
X1126100Y1302908D01*
X1126183Y1302575D01*
X1126100Y1302242D01*
X1125850Y1302033D01*
X1125558Y1301908D01*
X1124517D01*
G01X1125558D02*
X1126183Y1300700D01*
G01X1128450D02*
Y1303200D01*
X1127950Y1302700D01*
G01Y1300700D02*
X1128950D01*
G01X1130758Y1301742D02*
X1131050Y1302033D01*
X1131300Y1302200D01*
X1131633Y1302283D01*
X1131925Y1302200D01*
X1132133Y1302033D01*
X1132300Y1301783D01*
X1132342Y1301492D01*
X1132300Y1301242D01*
X1132133Y1300992D01*
X1131883Y1300783D01*
X1131592Y1300700D01*
X1131258Y1300783D01*
X1130967Y1301033D01*
X1130800Y1301408D01*
X1130758Y1301825D01*
X1130842Y1302367D01*
X1130967Y1302658D01*
X1131175Y1302950D01*
X1131467Y1303158D01*
X1131758Y1303200D01*
X1132050Y1303117D01*
X1132258Y1302908D01*
G01X1133858Y1302783D02*
X1134108Y1303033D01*
X1134400Y1303158D01*
X1134733Y1303200D01*
X1135150Y1303117D01*
X1135442Y1302908D01*
X1135525Y1302658D01*
X1135483Y1302408D01*
X1135317Y1302200D01*
X1134483Y1301783D01*
X1134108Y1301492D01*
X1133858Y1301075D01*
X1133775Y1300700D01*
X1135525D01*
G01X1132200Y1294700D02*
Y1298700D01*
X1124800D01*
G01X1129308Y1321017D02*
X1129183Y1320767D01*
X1129100Y1320475D01*
Y1320142D01*
X1129225Y1319767D01*
X1129433Y1319475D01*
X1129683Y1319267D01*
X1130100Y1319100D01*
X1130475Y1319058D01*
X1130850Y1319142D01*
X1131100Y1319267D01*
X1131350Y1319517D01*
X1131517Y1319808D01*
X1131600Y1320100D01*
Y1320392D01*
X1131517Y1320683D01*
X1131392Y1320933D01*
X1131225Y1321142D01*
G01X1129517Y1322408D02*
X1129267Y1322658D01*
X1129142Y1322950D01*
X1129100Y1323283D01*
X1129183Y1323700D01*
X1129392Y1323992D01*
X1129642Y1324075D01*
X1129892Y1324033D01*
X1130100Y1323867D01*
X1130517Y1323033D01*
X1130808Y1322658D01*
X1131225Y1322408D01*
X1131600Y1322325D01*
Y1324075D01*
G01X1129100Y1326300D02*
X1129183Y1325967D01*
X1129392Y1325717D01*
X1129642Y1325550D01*
X1129975Y1325425D01*
X1130350Y1325383D01*
X1130725Y1325425D01*
X1131058Y1325550D01*
X1131308Y1325717D01*
X1131517Y1325967D01*
X1131600Y1326300D01*
X1131517Y1326633D01*
X1131308Y1326883D01*
X1131058Y1327050D01*
X1130725Y1327175D01*
X1130350Y1327217D01*
X1129975Y1327175D01*
X1129642Y1327050D01*
X1129392Y1326883D01*
X1129183Y1326633D01*
X1129100Y1326300D01*
G01X1097717Y1328392D02*
X1097467Y1328517D01*
X1097175Y1328600D01*
X1096842D01*
X1096467Y1328475D01*
X1096175Y1328267D01*
X1095967Y1328017D01*
X1095800Y1327600D01*
X1095758Y1327225D01*
X1095842Y1326850D01*
X1095967Y1326600D01*
X1096217Y1326350D01*
X1096508Y1326183D01*
X1096800Y1326100D01*
X1097092D01*
X1097383Y1326183D01*
X1097633Y1326308D01*
X1097842Y1326475D01*
G01X1098983Y1326600D02*
X1099233Y1326308D01*
X1099567Y1326142D01*
X1099942Y1326100D01*
X1100275Y1326142D01*
X1100608Y1326350D01*
X1100817Y1326600D01*
X1100858Y1326850D01*
X1100775Y1327142D01*
X1100483Y1327350D01*
X1100192Y1327433D01*
X1099817D01*
G01X1100192D02*
X1100442Y1327558D01*
X1100650Y1327767D01*
X1100733Y1328017D01*
X1100650Y1328267D01*
X1100442Y1328475D01*
X1100067Y1328600D01*
X1099692Y1328558D01*
X1099317Y1328392D01*
G01X1102083Y1326600D02*
X1102333Y1326308D01*
X1102667Y1326142D01*
X1103042Y1326100D01*
X1103375Y1326142D01*
X1103708Y1326350D01*
X1103917Y1326600D01*
X1103958Y1326850D01*
X1103875Y1327142D01*
X1103583Y1327350D01*
X1103292Y1327433D01*
X1102917D01*
G01X1103292D02*
X1103542Y1327558D01*
X1103750Y1327767D01*
X1103833Y1328017D01*
X1103750Y1328267D01*
X1103542Y1328475D01*
X1103167Y1328600D01*
X1102792Y1328558D01*
X1102417Y1328392D01*
G01X1100483Y1316700D02*
Y1314908D01*
X1100650Y1314533D01*
X1100983Y1314283D01*
X1101400Y1314200D01*
X1101817Y1314283D01*
X1102150Y1314533D01*
X1102317Y1314908D01*
Y1316700D01*
G01X1104500Y1314200D02*
Y1316700D01*
X1104000Y1316200D01*
G01Y1314200D02*
X1105000D01*
G01X1107600D02*
Y1316700D01*
X1107100Y1316200D01*
G01Y1314200D02*
X1108100D01*
G01X1112000Y1291300D02*
X1098000D01*
Y1311400D01*
X1112000D01*
Y1291300D01*
G01X1106850Y1311250D02*
Y1311150D01*
X1105000Y1309300D01*
X1103200Y1311100D01*
Y1311200D01*
G01X1069974Y1327392D02*
Y1329892D01*
X1071015D01*
X1071349Y1329767D01*
X1071557Y1329600D01*
X1071640Y1329267D01*
X1071557Y1328934D01*
X1071307Y1328725D01*
X1071015Y1328600D01*
X1069974D01*
G01X1071015D02*
X1071640Y1327392D01*
G01X1073907D02*
Y1329892D01*
X1073407Y1329392D01*
G01Y1327392D02*
X1074407D01*
G01X1077007Y1329892D02*
X1076674Y1329809D01*
X1076424Y1329600D01*
X1076257Y1329350D01*
X1076132Y1329017D01*
X1076090Y1328642D01*
X1076132Y1328267D01*
X1076257Y1327934D01*
X1076424Y1327684D01*
X1076674Y1327475D01*
X1077007Y1327392D01*
X1077340Y1327475D01*
X1077590Y1327684D01*
X1077757Y1327934D01*
X1077882Y1328267D01*
X1077924Y1328642D01*
X1077882Y1329017D01*
X1077757Y1329350D01*
X1077590Y1329600D01*
X1077340Y1329809D01*
X1077007Y1329892D01*
G01X1079190Y1327767D02*
X1079440Y1327559D01*
X1079732Y1327434D01*
X1080107Y1327392D01*
X1080482Y1327475D01*
X1080774Y1327642D01*
X1080982Y1327934D01*
X1081024Y1328267D01*
X1080940Y1328600D01*
X1080732Y1328809D01*
X1080440Y1328975D01*
X1080149Y1329017D01*
X1079857Y1328975D01*
X1079482Y1328809D01*
X1079607Y1329892D01*
X1080732D01*
G01X1083707Y1327392D02*
Y1329892D01*
X1082165Y1328100D01*
X1084249D01*
G01X1115500Y1330315D02*
Y1348315D01*
G01X1101500Y1330315D02*
X1115500D01*
G01X1101500Y1348315D02*
Y1330315D01*
G01X1111430Y1410787D02*
X1111180Y1410912D01*
X1110888Y1410995D01*
X1110555D01*
X1110180Y1410870D01*
X1109888Y1410662D01*
X1109680Y1410412D01*
X1109513Y1409995D01*
X1109471Y1409620D01*
X1109555Y1409245D01*
X1109680Y1408995D01*
X1109930Y1408745D01*
X1110221Y1408578D01*
X1110513Y1408495D01*
X1110805D01*
X1111096Y1408578D01*
X1111346Y1408703D01*
X1111555Y1408870D01*
G01X1112821Y1409537D02*
X1113113Y1409828D01*
X1113363Y1409995D01*
X1113696Y1410078D01*
X1113988Y1409995D01*
X1114196Y1409828D01*
X1114363Y1409578D01*
X1114405Y1409287D01*
X1114363Y1409037D01*
X1114196Y1408787D01*
X1113946Y1408578D01*
X1113655Y1408495D01*
X1113321Y1408578D01*
X1113030Y1408828D01*
X1112863Y1409203D01*
X1112821Y1409620D01*
X1112905Y1410162D01*
X1113030Y1410453D01*
X1113238Y1410745D01*
X1113530Y1410953D01*
X1113821Y1410995D01*
X1114113Y1410912D01*
X1114321Y1410703D01*
G01X1116713Y1408495D02*
Y1410995D01*
X1116213Y1410495D01*
G01Y1408495D02*
X1117213D01*
G01X1118896Y1408870D02*
X1119146Y1408662D01*
X1119438Y1408537D01*
X1119813Y1408495D01*
X1120188Y1408578D01*
X1120480Y1408745D01*
X1120688Y1409037D01*
X1120730Y1409370D01*
X1120646Y1409703D01*
X1120438Y1409912D01*
X1120146Y1410078D01*
X1119855Y1410120D01*
X1119563Y1410078D01*
X1119188Y1409912D01*
X1119313Y1410995D01*
X1120438D01*
G01X1073000Y1379467D02*
X1070500D01*
Y1380508D01*
X1070625Y1380842D01*
X1070792Y1381050D01*
X1071125Y1381133D01*
X1071458Y1381050D01*
X1071667Y1380800D01*
X1071792Y1380508D01*
Y1379467D01*
G01Y1380508D02*
X1073000Y1381133D01*
G01Y1383400D02*
X1070500D01*
X1071000Y1382900D01*
G01X1073000D02*
Y1383900D01*
G01X1070500Y1386500D02*
X1070583Y1386167D01*
X1070792Y1385917D01*
X1071042Y1385750D01*
X1071375Y1385625D01*
X1071750Y1385583D01*
X1072125Y1385625D01*
X1072458Y1385750D01*
X1072708Y1385917D01*
X1072917Y1386167D01*
X1073000Y1386500D01*
X1072917Y1386833D01*
X1072708Y1387083D01*
X1072458Y1387250D01*
X1072125Y1387375D01*
X1071750Y1387417D01*
X1071375Y1387375D01*
X1071042Y1387250D01*
X1070792Y1387083D01*
X1070583Y1386833D01*
X1070500Y1386500D01*
G01X1072625Y1388683D02*
X1072833Y1388933D01*
X1072958Y1389225D01*
X1073000Y1389600D01*
X1072917Y1389975D01*
X1072750Y1390267D01*
X1072458Y1390475D01*
X1072125Y1390517D01*
X1071792Y1390433D01*
X1071583Y1390225D01*
X1071417Y1389933D01*
X1071375Y1389642D01*
X1071417Y1389350D01*
X1071583Y1388975D01*
X1070500Y1389100D01*
Y1390225D01*
G01X1072625Y1391783D02*
X1072833Y1392033D01*
X1072958Y1392325D01*
X1073000Y1392700D01*
X1072917Y1393075D01*
X1072750Y1393367D01*
X1072458Y1393575D01*
X1072125Y1393617D01*
X1071792Y1393533D01*
X1071583Y1393325D01*
X1071417Y1393033D01*
X1071375Y1392742D01*
X1071417Y1392450D01*
X1071583Y1392075D01*
X1070500Y1392200D01*
Y1393325D01*
G01X1062118Y1386789D02*
X1058118D01*
Y1379389D01*
G01X1082967Y1378000D02*
Y1380500D01*
X1084008D01*
X1084342Y1380375D01*
X1084550Y1380208D01*
X1084633Y1379875D01*
X1084550Y1379542D01*
X1084300Y1379333D01*
X1084008Y1379208D01*
X1082967D01*
G01X1084008D02*
X1084633Y1378000D01*
G01X1086900D02*
Y1380500D01*
X1086400Y1380000D01*
G01Y1378000D02*
X1087400D01*
G01X1090000Y1380500D02*
X1089667Y1380417D01*
X1089417Y1380208D01*
X1089250Y1379958D01*
X1089125Y1379625D01*
X1089083Y1379250D01*
X1089125Y1378875D01*
X1089250Y1378542D01*
X1089417Y1378292D01*
X1089667Y1378083D01*
X1090000Y1378000D01*
X1090333Y1378083D01*
X1090583Y1378292D01*
X1090750Y1378542D01*
X1090875Y1378875D01*
X1090917Y1379250D01*
X1090875Y1379625D01*
X1090750Y1379958D01*
X1090583Y1380208D01*
X1090333Y1380417D01*
X1090000Y1380500D01*
G01X1093100Y1378000D02*
X1093392Y1378042D01*
X1093725Y1378167D01*
X1093933Y1378375D01*
X1094017Y1378667D01*
X1093933Y1378958D01*
X1093683Y1379208D01*
X1093308Y1379333D01*
X1092892D01*
X1092642Y1379417D01*
X1092433Y1379625D01*
X1092350Y1379917D01*
X1092475Y1380208D01*
X1092767Y1380417D01*
X1093100Y1380500D01*
X1093433Y1380417D01*
X1093725Y1380208D01*
X1093850Y1379917D01*
X1093767Y1379625D01*
X1093558Y1379417D01*
X1093308Y1379333D01*
X1092892D01*
X1092517Y1379208D01*
X1092267Y1378958D01*
X1092183Y1378667D01*
X1092267Y1378375D01*
X1092475Y1378167D01*
X1092808Y1378042D01*
X1093100Y1378000D01*
G01X1096200Y1380500D02*
X1095867Y1380417D01*
X1095617Y1380208D01*
X1095450Y1379958D01*
X1095325Y1379625D01*
X1095283Y1379250D01*
X1095325Y1378875D01*
X1095450Y1378542D01*
X1095617Y1378292D01*
X1095867Y1378083D01*
X1096200Y1378000D01*
X1096533Y1378083D01*
X1096783Y1378292D01*
X1096950Y1378542D01*
X1097075Y1378875D01*
X1097117Y1379250D01*
X1097075Y1379625D01*
X1096950Y1379958D01*
X1096783Y1380208D01*
X1096533Y1380417D01*
X1096200Y1380500D01*
G01X1107812Y1377273D02*
Y1381273D01*
X1100412D01*
G01X1131365Y1346570D02*
X1128865D01*
Y1347611D01*
X1128990Y1347945D01*
X1129157Y1348153D01*
X1129490Y1348236D01*
X1129823Y1348153D01*
X1130032Y1347903D01*
X1130157Y1347611D01*
Y1346570D01*
G01Y1347611D02*
X1131365Y1348236D01*
G01Y1350503D02*
X1128865D01*
X1129365Y1350003D01*
G01X1131365D02*
Y1351003D01*
G01X1128865Y1353603D02*
X1128948Y1353270D01*
X1129157Y1353020D01*
X1129407Y1352853D01*
X1129740Y1352728D01*
X1130115Y1352686D01*
X1130490Y1352728D01*
X1130823Y1352853D01*
X1131073Y1353020D01*
X1131282Y1353270D01*
X1131365Y1353603D01*
X1131282Y1353936D01*
X1131073Y1354186D01*
X1130823Y1354353D01*
X1130490Y1354478D01*
X1130115Y1354520D01*
X1129740Y1354478D01*
X1129407Y1354353D01*
X1129157Y1354186D01*
X1128948Y1353936D01*
X1128865Y1353603D01*
G01X1131365Y1356620D02*
X1130823Y1356703D01*
X1130365Y1356828D01*
X1129948Y1356995D01*
X1129490Y1357203D01*
X1128865Y1357536D01*
Y1355870D01*
G01X1131365Y1359803D02*
X1128865D01*
X1129365Y1359303D01*
G01X1131365D02*
Y1360303D01*
G01X1120112Y1364573D02*
X1124112D01*
Y1371973D01*
G01X1143600Y1346567D02*
X1141100D01*
Y1347608D01*
X1141225Y1347942D01*
X1141392Y1348150D01*
X1141725Y1348233D01*
X1142058Y1348150D01*
X1142267Y1347900D01*
X1142392Y1347608D01*
Y1346567D01*
G01Y1347608D02*
X1143600Y1348233D01*
G01Y1350500D02*
X1141100D01*
X1141600Y1350000D01*
G01X1143600D02*
Y1351000D01*
G01X1141100Y1353600D02*
X1141183Y1353267D01*
X1141392Y1353017D01*
X1141642Y1352850D01*
X1141975Y1352725D01*
X1142350Y1352683D01*
X1142725Y1352725D01*
X1143058Y1352850D01*
X1143308Y1353017D01*
X1143517Y1353267D01*
X1143600Y1353600D01*
X1143517Y1353933D01*
X1143308Y1354183D01*
X1143058Y1354350D01*
X1142725Y1354475D01*
X1142350Y1354517D01*
X1141975Y1354475D01*
X1141642Y1354350D01*
X1141392Y1354183D01*
X1141183Y1353933D01*
X1141100Y1353600D01*
G01X1143600Y1356617D02*
X1143058Y1356700D01*
X1142600Y1356825D01*
X1142183Y1356992D01*
X1141725Y1357200D01*
X1141100Y1357533D01*
Y1355867D01*
G01X1141517Y1359008D02*
X1141267Y1359258D01*
X1141142Y1359550D01*
X1141100Y1359883D01*
X1141183Y1360300D01*
X1141392Y1360592D01*
X1141642Y1360675D01*
X1141892Y1360633D01*
X1142100Y1360467D01*
X1142517Y1359633D01*
X1142808Y1359258D01*
X1143225Y1359008D01*
X1143600Y1358925D01*
Y1360675D01*
G01X1132112Y1364573D02*
X1136112D01*
Y1371973D01*
G01X1083138Y1370371D02*
Y1372871D01*
X1084179D01*
X1084513Y1372746D01*
X1084721Y1372579D01*
X1084804Y1372246D01*
X1084721Y1371913D01*
X1084471Y1371704D01*
X1084179Y1371579D01*
X1083138D01*
G01X1084179D02*
X1084804Y1370371D01*
G01X1087071D02*
Y1372871D01*
X1086571Y1372371D01*
G01Y1370371D02*
X1087571D01*
G01X1090171Y1372871D02*
X1089838Y1372788D01*
X1089588Y1372579D01*
X1089421Y1372329D01*
X1089296Y1371996D01*
X1089254Y1371621D01*
X1089296Y1371246D01*
X1089421Y1370913D01*
X1089588Y1370663D01*
X1089838Y1370454D01*
X1090171Y1370371D01*
X1090504Y1370454D01*
X1090754Y1370663D01*
X1090921Y1370913D01*
X1091046Y1371246D01*
X1091088Y1371621D01*
X1091046Y1371996D01*
X1090921Y1372329D01*
X1090754Y1372579D01*
X1090504Y1372788D01*
X1090171Y1372871D01*
G01X1093188Y1370371D02*
X1093271Y1370913D01*
X1093396Y1371371D01*
X1093563Y1371788D01*
X1093771Y1372246D01*
X1094104Y1372871D01*
X1092438D01*
G01X1095454Y1370871D02*
X1095704Y1370579D01*
X1096038Y1370413D01*
X1096413Y1370371D01*
X1096746Y1370413D01*
X1097079Y1370621D01*
X1097288Y1370871D01*
X1097329Y1371121D01*
X1097246Y1371413D01*
X1096954Y1371621D01*
X1096663Y1371704D01*
X1096288D01*
G01X1096663D02*
X1096913Y1371829D01*
X1097121Y1372038D01*
X1097204Y1372288D01*
X1097121Y1372538D01*
X1096913Y1372746D01*
X1096538Y1372871D01*
X1096163Y1372829D01*
X1095788Y1372663D01*
G01X1100400Y1373200D02*
Y1369200D01*
X1107800D01*
G01X1135365Y1346570D02*
X1132865D01*
Y1347611D01*
X1132990Y1347945D01*
X1133157Y1348153D01*
X1133490Y1348236D01*
X1133823Y1348153D01*
X1134032Y1347903D01*
X1134157Y1347611D01*
Y1346570D01*
G01Y1347611D02*
X1135365Y1348236D01*
G01Y1350503D02*
X1132865D01*
X1133365Y1350003D01*
G01X1135365D02*
Y1351003D01*
G01X1132865Y1353603D02*
X1132948Y1353270D01*
X1133157Y1353020D01*
X1133407Y1352853D01*
X1133740Y1352728D01*
X1134115Y1352686D01*
X1134490Y1352728D01*
X1134823Y1352853D01*
X1135073Y1353020D01*
X1135282Y1353270D01*
X1135365Y1353603D01*
X1135282Y1353936D01*
X1135073Y1354186D01*
X1134823Y1354353D01*
X1134490Y1354478D01*
X1134115Y1354520D01*
X1133740Y1354478D01*
X1133407Y1354353D01*
X1133157Y1354186D01*
X1132948Y1353936D01*
X1132865Y1353603D01*
G01X1135365Y1356620D02*
X1134823Y1356703D01*
X1134365Y1356828D01*
X1133948Y1356995D01*
X1133490Y1357203D01*
X1132865Y1357536D01*
Y1355870D01*
G01X1135365Y1359803D02*
X1135323Y1360095D01*
X1135198Y1360428D01*
X1134990Y1360636D01*
X1134698Y1360720D01*
X1134407Y1360636D01*
X1134157Y1360386D01*
X1134032Y1360011D01*
Y1359595D01*
X1133948Y1359345D01*
X1133740Y1359136D01*
X1133448Y1359053D01*
X1133157Y1359178D01*
X1132948Y1359470D01*
X1132865Y1359803D01*
X1132948Y1360136D01*
X1133157Y1360428D01*
X1133448Y1360553D01*
X1133740Y1360470D01*
X1133948Y1360261D01*
X1134032Y1360011D01*
Y1359595D01*
X1134157Y1359220D01*
X1134407Y1358970D01*
X1134698Y1358886D01*
X1134990Y1358970D01*
X1135198Y1359178D01*
X1135323Y1359511D01*
X1135365Y1359803D01*
G01X1128112Y1371973D02*
X1124112D01*
Y1364573D01*
G01X1139365Y1346570D02*
X1136865D01*
Y1347611D01*
X1136990Y1347945D01*
X1137157Y1348153D01*
X1137490Y1348236D01*
X1137823Y1348153D01*
X1138032Y1347903D01*
X1138157Y1347611D01*
Y1346570D01*
G01Y1347611D02*
X1139365Y1348236D01*
G01Y1350503D02*
X1136865D01*
X1137365Y1350003D01*
G01X1139365D02*
Y1351003D01*
G01X1136865Y1353603D02*
X1136948Y1353270D01*
X1137157Y1353020D01*
X1137407Y1352853D01*
X1137740Y1352728D01*
X1138115Y1352686D01*
X1138490Y1352728D01*
X1138823Y1352853D01*
X1139073Y1353020D01*
X1139282Y1353270D01*
X1139365Y1353603D01*
X1139282Y1353936D01*
X1139073Y1354186D01*
X1138823Y1354353D01*
X1138490Y1354478D01*
X1138115Y1354520D01*
X1137740Y1354478D01*
X1137407Y1354353D01*
X1137157Y1354186D01*
X1136948Y1353936D01*
X1136865Y1353603D01*
G01X1139365Y1356620D02*
X1138823Y1356703D01*
X1138365Y1356828D01*
X1137948Y1356995D01*
X1137490Y1357203D01*
X1136865Y1357536D01*
Y1355870D01*
G01X1139073Y1359095D02*
X1139282Y1359386D01*
X1139365Y1359720D01*
X1139282Y1360053D01*
X1139032Y1360345D01*
X1138657Y1360553D01*
X1138282Y1360636D01*
X1137823D01*
X1137448Y1360553D01*
X1137115Y1360345D01*
X1136948Y1360095D01*
X1136865Y1359803D01*
X1136948Y1359470D01*
X1137115Y1359220D01*
X1137365Y1359053D01*
X1137698Y1358970D01*
X1137990Y1359053D01*
X1138282Y1359261D01*
X1138448Y1359511D01*
X1138490Y1359803D01*
X1138407Y1360136D01*
X1138198Y1360386D01*
X1137823Y1360636D01*
G01X1132112Y1371973D02*
X1128112D01*
Y1364573D01*
G01X1123365Y1346570D02*
X1120865D01*
Y1347611D01*
X1120990Y1347945D01*
X1121157Y1348153D01*
X1121490Y1348236D01*
X1121823Y1348153D01*
X1122032Y1347903D01*
X1122157Y1347611D01*
Y1346570D01*
G01Y1347611D02*
X1123365Y1348236D01*
G01Y1350503D02*
X1120865D01*
X1121365Y1350003D01*
G01X1123365D02*
Y1351003D01*
G01X1120865Y1353603D02*
X1120948Y1353270D01*
X1121157Y1353020D01*
X1121407Y1352853D01*
X1121740Y1352728D01*
X1122115Y1352686D01*
X1122490Y1352728D01*
X1122823Y1352853D01*
X1123073Y1353020D01*
X1123282Y1353270D01*
X1123365Y1353603D01*
X1123282Y1353936D01*
X1123073Y1354186D01*
X1122823Y1354353D01*
X1122490Y1354478D01*
X1122115Y1354520D01*
X1121740Y1354478D01*
X1121407Y1354353D01*
X1121157Y1354186D01*
X1120948Y1353936D01*
X1120865Y1353603D01*
G01X1123365Y1356703D02*
X1123323Y1356995D01*
X1123198Y1357328D01*
X1122990Y1357536D01*
X1122698Y1357620D01*
X1122407Y1357536D01*
X1122157Y1357286D01*
X1122032Y1356911D01*
Y1356495D01*
X1121948Y1356245D01*
X1121740Y1356036D01*
X1121448Y1355953D01*
X1121157Y1356078D01*
X1120948Y1356370D01*
X1120865Y1356703D01*
X1120948Y1357036D01*
X1121157Y1357328D01*
X1121448Y1357453D01*
X1121740Y1357370D01*
X1121948Y1357161D01*
X1122032Y1356911D01*
Y1356495D01*
X1122157Y1356120D01*
X1122407Y1355870D01*
X1122698Y1355786D01*
X1122990Y1355870D01*
X1123198Y1356078D01*
X1123323Y1356411D01*
X1123365Y1356703D01*
G01Y1359803D02*
X1120865D01*
X1121365Y1359303D01*
G01X1123365D02*
Y1360303D01*
G01X1112112Y1364573D02*
X1116112D01*
Y1371973D01*
G01X1127365Y1346570D02*
X1124865D01*
Y1347611D01*
X1124990Y1347945D01*
X1125157Y1348153D01*
X1125490Y1348236D01*
X1125823Y1348153D01*
X1126032Y1347903D01*
X1126157Y1347611D01*
Y1346570D01*
G01Y1347611D02*
X1127365Y1348236D01*
G01Y1350503D02*
X1124865D01*
X1125365Y1350003D01*
G01X1127365D02*
Y1351003D01*
G01X1124865Y1353603D02*
X1124948Y1353270D01*
X1125157Y1353020D01*
X1125407Y1352853D01*
X1125740Y1352728D01*
X1126115Y1352686D01*
X1126490Y1352728D01*
X1126823Y1352853D01*
X1127073Y1353020D01*
X1127282Y1353270D01*
X1127365Y1353603D01*
X1127282Y1353936D01*
X1127073Y1354186D01*
X1126823Y1354353D01*
X1126490Y1354478D01*
X1126115Y1354520D01*
X1125740Y1354478D01*
X1125407Y1354353D01*
X1125157Y1354186D01*
X1124948Y1353936D01*
X1124865Y1353603D01*
G01X1127365Y1356703D02*
X1127323Y1356995D01*
X1127198Y1357328D01*
X1126990Y1357536D01*
X1126698Y1357620D01*
X1126407Y1357536D01*
X1126157Y1357286D01*
X1126032Y1356911D01*
Y1356495D01*
X1125948Y1356245D01*
X1125740Y1356036D01*
X1125448Y1355953D01*
X1125157Y1356078D01*
X1124948Y1356370D01*
X1124865Y1356703D01*
X1124948Y1357036D01*
X1125157Y1357328D01*
X1125448Y1357453D01*
X1125740Y1357370D01*
X1125948Y1357161D01*
X1126032Y1356911D01*
Y1356495D01*
X1126157Y1356120D01*
X1126407Y1355870D01*
X1126698Y1355786D01*
X1126990Y1355870D01*
X1127198Y1356078D01*
X1127323Y1356411D01*
X1127365Y1356703D01*
G01X1125282Y1359011D02*
X1125032Y1359261D01*
X1124907Y1359553D01*
X1124865Y1359886D01*
X1124948Y1360303D01*
X1125157Y1360595D01*
X1125407Y1360678D01*
X1125657Y1360636D01*
X1125865Y1360470D01*
X1126282Y1359636D01*
X1126573Y1359261D01*
X1126990Y1359011D01*
X1127365Y1358928D01*
Y1360678D01*
G01X1116112Y1364573D02*
X1120112D01*
Y1371973D01*
G01X1147800Y1346567D02*
X1145300D01*
Y1347608D01*
X1145425Y1347942D01*
X1145592Y1348150D01*
X1145925Y1348233D01*
X1146258Y1348150D01*
X1146467Y1347900D01*
X1146592Y1347608D01*
Y1346567D01*
G01Y1347608D02*
X1147800Y1348233D01*
G01Y1350500D02*
X1145300D01*
X1145800Y1350000D01*
G01X1147800D02*
Y1351000D01*
G01X1145300Y1353600D02*
X1145383Y1353267D01*
X1145592Y1353017D01*
X1145842Y1352850D01*
X1146175Y1352725D01*
X1146550Y1352683D01*
X1146925Y1352725D01*
X1147258Y1352850D01*
X1147508Y1353017D01*
X1147717Y1353267D01*
X1147800Y1353600D01*
X1147717Y1353933D01*
X1147508Y1354183D01*
X1147258Y1354350D01*
X1146925Y1354475D01*
X1146550Y1354517D01*
X1146175Y1354475D01*
X1145842Y1354350D01*
X1145592Y1354183D01*
X1145383Y1353933D01*
X1145300Y1353600D01*
G01X1147800Y1356700D02*
X1147758Y1356992D01*
X1147633Y1357325D01*
X1147425Y1357533D01*
X1147133Y1357617D01*
X1146842Y1357533D01*
X1146592Y1357283D01*
X1146467Y1356908D01*
Y1356492D01*
X1146383Y1356242D01*
X1146175Y1356033D01*
X1145883Y1355950D01*
X1145592Y1356075D01*
X1145383Y1356367D01*
X1145300Y1356700D01*
X1145383Y1357033D01*
X1145592Y1357325D01*
X1145883Y1357450D01*
X1146175Y1357367D01*
X1146383Y1357158D01*
X1146467Y1356908D01*
Y1356492D01*
X1146592Y1356117D01*
X1146842Y1355867D01*
X1147133Y1355783D01*
X1147425Y1355867D01*
X1147633Y1356075D01*
X1147758Y1356408D01*
X1147800Y1356700D01*
G01X1147300Y1358883D02*
X1147592Y1359133D01*
X1147758Y1359467D01*
X1147800Y1359842D01*
X1147758Y1360175D01*
X1147550Y1360508D01*
X1147300Y1360717D01*
X1147050Y1360758D01*
X1146758Y1360675D01*
X1146550Y1360383D01*
X1146467Y1360092D01*
Y1359717D01*
G01Y1360092D02*
X1146342Y1360342D01*
X1146133Y1360550D01*
X1145883Y1360633D01*
X1145633Y1360550D01*
X1145425Y1360342D01*
X1145300Y1359967D01*
X1145342Y1359592D01*
X1145508Y1359217D01*
G01X1136112Y1364573D02*
X1140112D01*
Y1371973D01*
G01X1083150Y1390444D02*
Y1392944D01*
X1084191D01*
X1084525Y1392819D01*
X1084733Y1392652D01*
X1084816Y1392319D01*
X1084733Y1391986D01*
X1084483Y1391777D01*
X1084191Y1391652D01*
X1083150D01*
G01X1084191D02*
X1084816Y1390444D01*
G01X1087083D02*
Y1392944D01*
X1086583Y1392444D01*
G01Y1390444D02*
X1087583D01*
G01X1090183Y1392944D02*
X1089850Y1392861D01*
X1089600Y1392652D01*
X1089433Y1392402D01*
X1089308Y1392069D01*
X1089266Y1391694D01*
X1089308Y1391319D01*
X1089433Y1390986D01*
X1089600Y1390736D01*
X1089850Y1390527D01*
X1090183Y1390444D01*
X1090516Y1390527D01*
X1090766Y1390736D01*
X1090933Y1390986D01*
X1091058Y1391319D01*
X1091100Y1391694D01*
X1091058Y1392069D01*
X1090933Y1392402D01*
X1090766Y1392652D01*
X1090516Y1392861D01*
X1090183Y1392944D01*
G01X1093200Y1390444D02*
X1093283Y1390986D01*
X1093408Y1391444D01*
X1093575Y1391861D01*
X1093783Y1392319D01*
X1094116Y1392944D01*
X1092450D01*
G01X1096883Y1390444D02*
Y1392944D01*
X1095341Y1391152D01*
X1097425D01*
G01X1100412Y1393273D02*
Y1389273D01*
X1107812D01*
G01X1083160Y1398634D02*
Y1401134D01*
X1084201D01*
X1084535Y1401009D01*
X1084743Y1400842D01*
X1084826Y1400509D01*
X1084743Y1400176D01*
X1084493Y1399967D01*
X1084201Y1399842D01*
X1083160D01*
G01X1084201D02*
X1084826Y1398634D01*
G01X1087093D02*
Y1401134D01*
X1086593Y1400634D01*
G01Y1398634D02*
X1087593D01*
G01X1090193Y1401134D02*
X1089860Y1401051D01*
X1089610Y1400842D01*
X1089443Y1400592D01*
X1089318Y1400259D01*
X1089276Y1399884D01*
X1089318Y1399509D01*
X1089443Y1399176D01*
X1089610Y1398926D01*
X1089860Y1398717D01*
X1090193Y1398634D01*
X1090526Y1398717D01*
X1090776Y1398926D01*
X1090943Y1399176D01*
X1091068Y1399509D01*
X1091110Y1399884D01*
X1091068Y1400259D01*
X1090943Y1400592D01*
X1090776Y1400842D01*
X1090526Y1401051D01*
X1090193Y1401134D01*
G01X1093210Y1398634D02*
X1093293Y1399176D01*
X1093418Y1399634D01*
X1093585Y1400051D01*
X1093793Y1400509D01*
X1094126Y1401134D01*
X1092460D01*
G01X1095476Y1399009D02*
X1095726Y1398801D01*
X1096018Y1398676D01*
X1096393Y1398634D01*
X1096768Y1398717D01*
X1097060Y1398884D01*
X1097268Y1399176D01*
X1097310Y1399509D01*
X1097226Y1399842D01*
X1097018Y1400051D01*
X1096726Y1400217D01*
X1096435Y1400259D01*
X1096143Y1400217D01*
X1095768Y1400051D01*
X1095893Y1401134D01*
X1097018D01*
G01X1107812Y1397273D02*
Y1401273D01*
X1100412D01*
G01X1083150Y1394444D02*
Y1396944D01*
X1084191D01*
X1084525Y1396819D01*
X1084733Y1396652D01*
X1084816Y1396319D01*
X1084733Y1395986D01*
X1084483Y1395777D01*
X1084191Y1395652D01*
X1083150D01*
G01X1084191D02*
X1084816Y1394444D01*
G01X1087083D02*
Y1396944D01*
X1086583Y1396444D01*
G01Y1394444D02*
X1087583D01*
G01X1090183Y1396944D02*
X1089850Y1396861D01*
X1089600Y1396652D01*
X1089433Y1396402D01*
X1089308Y1396069D01*
X1089266Y1395694D01*
X1089308Y1395319D01*
X1089433Y1394986D01*
X1089600Y1394736D01*
X1089850Y1394527D01*
X1090183Y1394444D01*
X1090516Y1394527D01*
X1090766Y1394736D01*
X1090933Y1394986D01*
X1091058Y1395319D01*
X1091100Y1395694D01*
X1091058Y1396069D01*
X1090933Y1396402D01*
X1090766Y1396652D01*
X1090516Y1396861D01*
X1090183Y1396944D01*
G01X1093200Y1394444D02*
X1093283Y1394986D01*
X1093408Y1395444D01*
X1093575Y1395861D01*
X1093783Y1396319D01*
X1094116Y1396944D01*
X1092450D01*
G01X1095591Y1395486D02*
X1095883Y1395777D01*
X1096133Y1395944D01*
X1096466Y1396027D01*
X1096758Y1395944D01*
X1096966Y1395777D01*
X1097133Y1395527D01*
X1097175Y1395236D01*
X1097133Y1394986D01*
X1096966Y1394736D01*
X1096716Y1394527D01*
X1096425Y1394444D01*
X1096091Y1394527D01*
X1095800Y1394777D01*
X1095633Y1395152D01*
X1095591Y1395569D01*
X1095675Y1396111D01*
X1095800Y1396402D01*
X1096008Y1396694D01*
X1096300Y1396902D01*
X1096591Y1396944D01*
X1096883Y1396861D01*
X1097091Y1396652D01*
G01X1107812Y1393273D02*
Y1397273D01*
X1100412D01*
G01X1082967Y1386000D02*
Y1388500D01*
X1084008D01*
X1084342Y1388375D01*
X1084550Y1388208D01*
X1084633Y1387875D01*
X1084550Y1387542D01*
X1084300Y1387333D01*
X1084008Y1387208D01*
X1082967D01*
G01X1084008D02*
X1084633Y1386000D01*
G01X1086900D02*
Y1388500D01*
X1086400Y1388000D01*
G01Y1386000D02*
X1087400D01*
G01X1090000Y1388500D02*
X1089667Y1388417D01*
X1089417Y1388208D01*
X1089250Y1387958D01*
X1089125Y1387625D01*
X1089083Y1387250D01*
X1089125Y1386875D01*
X1089250Y1386542D01*
X1089417Y1386292D01*
X1089667Y1386083D01*
X1090000Y1386000D01*
X1090333Y1386083D01*
X1090583Y1386292D01*
X1090750Y1386542D01*
X1090875Y1386875D01*
X1090917Y1387250D01*
X1090875Y1387625D01*
X1090750Y1387958D01*
X1090583Y1388208D01*
X1090333Y1388417D01*
X1090000Y1388500D01*
G01X1093017Y1386000D02*
X1093100Y1386542D01*
X1093225Y1387000D01*
X1093392Y1387417D01*
X1093600Y1387875D01*
X1093933Y1388500D01*
X1092267D01*
G01X1096117Y1386000D02*
X1096200Y1386542D01*
X1096325Y1387000D01*
X1096492Y1387417D01*
X1096700Y1387875D01*
X1097033Y1388500D01*
X1095367D01*
G01X1107812Y1385273D02*
Y1389273D01*
X1100412D01*
G01X1091017Y1354000D02*
Y1356500D01*
X1092058D01*
X1092392Y1356375D01*
X1092600Y1356208D01*
X1092683Y1355875D01*
X1092600Y1355542D01*
X1092350Y1355333D01*
X1092058Y1355208D01*
X1091017D01*
G01X1092058D02*
X1092683Y1354000D01*
G01X1095450D02*
Y1356500D01*
X1093908Y1354708D01*
X1095992D01*
G01X1097342Y1354292D02*
X1097633Y1354083D01*
X1097967Y1354000D01*
X1098300Y1354083D01*
X1098592Y1354333D01*
X1098800Y1354708D01*
X1098883Y1355083D01*
Y1355542D01*
X1098800Y1355917D01*
X1098592Y1356250D01*
X1098342Y1356417D01*
X1098050Y1356500D01*
X1097717Y1356417D01*
X1097467Y1356250D01*
X1097300Y1356000D01*
X1097217Y1355667D01*
X1097300Y1355375D01*
X1097508Y1355083D01*
X1097758Y1354917D01*
X1098050Y1354875D01*
X1098383Y1354958D01*
X1098633Y1355167D01*
X1098883Y1355542D01*
G01X1100233Y1354500D02*
X1100483Y1354208D01*
X1100817Y1354042D01*
X1101192Y1354000D01*
X1101525Y1354042D01*
X1101858Y1354250D01*
X1102067Y1354500D01*
X1102108Y1354750D01*
X1102025Y1355042D01*
X1101733Y1355250D01*
X1101442Y1355333D01*
X1101067D01*
G01X1101442D02*
X1101692Y1355458D01*
X1101900Y1355667D01*
X1101983Y1355917D01*
X1101900Y1356167D01*
X1101692Y1356375D01*
X1101317Y1356500D01*
X1100942Y1356458D01*
X1100567Y1356292D01*
G01X1117200Y1356500D02*
Y1360500D01*
X1109800D01*
G01X1082967Y1374000D02*
Y1376500D01*
X1084008D01*
X1084342Y1376375D01*
X1084550Y1376208D01*
X1084633Y1375875D01*
X1084550Y1375542D01*
X1084300Y1375333D01*
X1084008Y1375208D01*
X1082967D01*
G01X1084008D02*
X1084633Y1374000D01*
G01X1086900D02*
Y1376500D01*
X1086400Y1376000D01*
G01Y1374000D02*
X1087400D01*
G01X1090000D02*
Y1376500D01*
X1089500Y1376000D01*
G01Y1374000D02*
X1090500D01*
G01X1093600D02*
Y1376500D01*
X1092058Y1374708D01*
X1094142D01*
G01X1095492Y1374292D02*
X1095783Y1374083D01*
X1096117Y1374000D01*
X1096450Y1374083D01*
X1096742Y1374333D01*
X1096950Y1374708D01*
X1097033Y1375083D01*
Y1375542D01*
X1096950Y1375917D01*
X1096742Y1376250D01*
X1096492Y1376417D01*
X1096200Y1376500D01*
X1095867Y1376417D01*
X1095617Y1376250D01*
X1095450Y1376000D01*
X1095367Y1375667D01*
X1095450Y1375375D01*
X1095658Y1375083D01*
X1095908Y1374917D01*
X1096200Y1374875D01*
X1096533Y1374958D01*
X1096783Y1375167D01*
X1097033Y1375542D01*
G01X1100400Y1377200D02*
Y1373200D01*
X1107800D01*
G01X1082967Y1382000D02*
Y1384500D01*
X1084008D01*
X1084342Y1384375D01*
X1084550Y1384208D01*
X1084633Y1383875D01*
X1084550Y1383542D01*
X1084300Y1383333D01*
X1084008Y1383208D01*
X1082967D01*
G01X1084008D02*
X1084633Y1382000D01*
G01X1086900D02*
Y1384500D01*
X1086400Y1384000D01*
G01Y1382000D02*
X1087400D01*
G01X1090000D02*
Y1384500D01*
X1089500Y1384000D01*
G01Y1382000D02*
X1090500D01*
G01X1092308Y1384083D02*
X1092558Y1384333D01*
X1092850Y1384458D01*
X1093183Y1384500D01*
X1093600Y1384417D01*
X1093892Y1384208D01*
X1093975Y1383958D01*
X1093933Y1383708D01*
X1093767Y1383500D01*
X1092933Y1383083D01*
X1092558Y1382792D01*
X1092308Y1382375D01*
X1092225Y1382000D01*
X1093975D01*
G01X1095492Y1382292D02*
X1095783Y1382083D01*
X1096117Y1382000D01*
X1096450Y1382083D01*
X1096742Y1382333D01*
X1096950Y1382708D01*
X1097033Y1383083D01*
Y1383542D01*
X1096950Y1383917D01*
X1096742Y1384250D01*
X1096492Y1384417D01*
X1096200Y1384500D01*
X1095867Y1384417D01*
X1095617Y1384250D01*
X1095450Y1384000D01*
X1095367Y1383667D01*
X1095450Y1383375D01*
X1095658Y1383083D01*
X1095908Y1382917D01*
X1096200Y1382875D01*
X1096533Y1382958D01*
X1096783Y1383167D01*
X1097033Y1383542D01*
G01X1100412Y1385273D02*
Y1381273D01*
X1107812D01*
G01X1056335Y1425817D02*
X1056210Y1425567D01*
X1056127Y1425275D01*
Y1424942D01*
X1056252Y1424567D01*
X1056460Y1424275D01*
X1056710Y1424067D01*
X1057127Y1423900D01*
X1057502Y1423858D01*
X1057877Y1423942D01*
X1058127Y1424067D01*
X1058377Y1424317D01*
X1058544Y1424608D01*
X1058627Y1424900D01*
Y1425192D01*
X1058544Y1425483D01*
X1058419Y1425733D01*
X1058252Y1425942D01*
G01X1058627Y1427917D02*
X1058085Y1428000D01*
X1057627Y1428125D01*
X1057210Y1428292D01*
X1056752Y1428500D01*
X1056127Y1428833D01*
Y1427167D01*
G01X1058335Y1430392D02*
X1058544Y1430683D01*
X1058627Y1431017D01*
X1058544Y1431350D01*
X1058294Y1431642D01*
X1057919Y1431850D01*
X1057544Y1431933D01*
X1057085D01*
X1056710Y1431850D01*
X1056377Y1431642D01*
X1056210Y1431392D01*
X1056127Y1431100D01*
X1056210Y1430767D01*
X1056377Y1430517D01*
X1056627Y1430350D01*
X1056960Y1430267D01*
X1057252Y1430350D01*
X1057544Y1430558D01*
X1057710Y1430808D01*
X1057752Y1431100D01*
X1057669Y1431433D01*
X1057460Y1431683D01*
X1057085Y1431933D01*
G01X1095817Y1351792D02*
X1095567Y1351917D01*
X1095275Y1352000D01*
X1094942D01*
X1094567Y1351875D01*
X1094275Y1351667D01*
X1094067Y1351417D01*
X1093900Y1351000D01*
X1093858Y1350625D01*
X1093942Y1350250D01*
X1094067Y1350000D01*
X1094317Y1349750D01*
X1094608Y1349583D01*
X1094900Y1349500D01*
X1095192D01*
X1095483Y1349583D01*
X1095733Y1349708D01*
X1095942Y1349875D01*
G01X1097083Y1350000D02*
X1097333Y1349708D01*
X1097667Y1349542D01*
X1098042Y1349500D01*
X1098375Y1349542D01*
X1098708Y1349750D01*
X1098917Y1350000D01*
X1098958Y1350250D01*
X1098875Y1350542D01*
X1098583Y1350750D01*
X1098292Y1350833D01*
X1097917D01*
G01X1098292D02*
X1098542Y1350958D01*
X1098750Y1351167D01*
X1098833Y1351417D01*
X1098750Y1351667D01*
X1098542Y1351875D01*
X1098167Y1352000D01*
X1097792Y1351958D01*
X1097417Y1351792D01*
G01X1101600Y1349500D02*
Y1352000D01*
X1100058Y1350208D01*
X1102142D01*
G01X1055167Y1415700D02*
Y1418200D01*
X1056208D01*
X1056542Y1418075D01*
X1056750Y1417908D01*
X1056833Y1417575D01*
X1056750Y1417242D01*
X1056500Y1417033D01*
X1056208Y1416908D01*
X1055167D01*
G01X1056208D02*
X1056833Y1415700D01*
G01X1059100D02*
Y1418200D01*
X1058600Y1417700D01*
G01Y1415700D02*
X1059600D01*
G01X1061408Y1417783D02*
X1061658Y1418033D01*
X1061950Y1418158D01*
X1062283Y1418200D01*
X1062700Y1418117D01*
X1062992Y1417908D01*
X1063075Y1417658D01*
X1063033Y1417408D01*
X1062867Y1417200D01*
X1062033Y1416783D01*
X1061658Y1416492D01*
X1061408Y1416075D01*
X1061325Y1415700D01*
X1063075D01*
G01X1064592Y1415992D02*
X1064883Y1415783D01*
X1065217Y1415700D01*
X1065550Y1415783D01*
X1065842Y1416033D01*
X1066050Y1416408D01*
X1066133Y1416783D01*
Y1417242D01*
X1066050Y1417617D01*
X1065842Y1417950D01*
X1065592Y1418117D01*
X1065300Y1418200D01*
X1064967Y1418117D01*
X1064717Y1417950D01*
X1064550Y1417700D01*
X1064467Y1417367D01*
X1064550Y1417075D01*
X1064758Y1416783D01*
X1065008Y1416617D01*
X1065300Y1416575D01*
X1065633Y1416658D01*
X1065883Y1416867D01*
X1066133Y1417242D01*
G01X1067483Y1416200D02*
X1067733Y1415908D01*
X1068067Y1415742D01*
X1068442Y1415700D01*
X1068775Y1415742D01*
X1069108Y1415950D01*
X1069317Y1416200D01*
X1069358Y1416450D01*
X1069275Y1416742D01*
X1068983Y1416950D01*
X1068692Y1417033D01*
X1068317D01*
G01X1068692D02*
X1068942Y1417158D01*
X1069150Y1417367D01*
X1069233Y1417617D01*
X1069150Y1417867D01*
X1068942Y1418075D01*
X1068567Y1418200D01*
X1068192Y1418158D01*
X1067817Y1417992D01*
G01X1121983Y1407000D02*
Y1405208D01*
X1122150Y1404833D01*
X1122483Y1404583D01*
X1122900Y1404500D01*
X1123317Y1404583D01*
X1123650Y1404833D01*
X1123817Y1405208D01*
Y1407000D01*
G01X1125208Y1406583D02*
X1125458Y1406833D01*
X1125750Y1406958D01*
X1126083Y1407000D01*
X1126500Y1406917D01*
X1126792Y1406708D01*
X1126875Y1406458D01*
X1126833Y1406208D01*
X1126667Y1406000D01*
X1125833Y1405583D01*
X1125458Y1405292D01*
X1125208Y1404875D01*
X1125125Y1404500D01*
X1126875D01*
G01X1128392Y1404792D02*
X1128683Y1404583D01*
X1129017Y1404500D01*
X1129350Y1404583D01*
X1129642Y1404833D01*
X1129850Y1405208D01*
X1129933Y1405583D01*
Y1406042D01*
X1129850Y1406417D01*
X1129642Y1406750D01*
X1129392Y1406917D01*
X1129100Y1407000D01*
X1128767Y1406917D01*
X1128517Y1406750D01*
X1128350Y1406500D01*
X1128267Y1406167D01*
X1128350Y1405875D01*
X1128558Y1405583D01*
X1128808Y1405417D01*
X1129100Y1405375D01*
X1129433Y1405458D01*
X1129683Y1405667D01*
X1129933Y1406042D01*
G01X1135562Y1387173D02*
X1138562D01*
G01X1113662Y1388773D02*
X1111662D01*
G01X1121412Y1399723D02*
Y1402723D01*
G01X1129312Y1399723D02*
Y1401723D01*
G01X1126212Y1377823D02*
Y1375823D01*
G01X1136462Y1395623D02*
Y1400623D01*
X1131462D01*
G01X1117762D02*
X1112762D01*
Y1395623D01*
G01X1136462Y1381923D02*
Y1376923D01*
X1131462D01*
G01X1062500Y1424950D02*
X1062458Y1424617D01*
X1062292Y1424325D01*
X1062042Y1424075D01*
X1061750Y1423908D01*
X1061417Y1423825D01*
X1061083D01*
X1060750Y1423908D01*
X1060458Y1424075D01*
X1060208Y1424325D01*
X1060042Y1424617D01*
X1060000Y1424950D01*
X1060042Y1425283D01*
X1060208Y1425575D01*
X1060458Y1425825D01*
X1060750Y1425992D01*
X1061083Y1426075D01*
X1061417D01*
X1061750Y1425992D01*
X1062042Y1425825D01*
X1062292Y1425575D01*
X1062458Y1425283D01*
X1062500Y1424950D01*
G01X1061833Y1425283D02*
X1062500Y1425783D01*
G01X1062125Y1427133D02*
X1062333Y1427383D01*
X1062458Y1427675D01*
X1062500Y1428050D01*
X1062417Y1428425D01*
X1062250Y1428717D01*
X1061958Y1428925D01*
X1061625Y1428967D01*
X1061292Y1428883D01*
X1061083Y1428675D01*
X1060917Y1428383D01*
X1060875Y1428092D01*
X1060917Y1427800D01*
X1061083Y1427425D01*
X1060000Y1427550D01*
Y1428675D01*
G01X1056125Y1399931D02*
Y1402431D01*
X1057166D01*
X1057500Y1402306D01*
X1057708Y1402139D01*
X1057791Y1401806D01*
X1057708Y1401473D01*
X1057458Y1401264D01*
X1057166Y1401139D01*
X1056125D01*
G01X1057166D02*
X1057791Y1399931D01*
G01X1060058D02*
Y1402431D01*
X1059558Y1401931D01*
G01Y1399931D02*
X1060558D01*
G01X1062241Y1400306D02*
X1062491Y1400098D01*
X1062783Y1399973D01*
X1063158Y1399931D01*
X1063533Y1400014D01*
X1063825Y1400181D01*
X1064033Y1400473D01*
X1064075Y1400806D01*
X1063991Y1401139D01*
X1063783Y1401348D01*
X1063491Y1401514D01*
X1063200Y1401556D01*
X1062908Y1401514D01*
X1062533Y1401348D01*
X1062658Y1402431D01*
X1063783D01*
G01X1065341Y1400431D02*
X1065591Y1400139D01*
X1065925Y1399973D01*
X1066300Y1399931D01*
X1066633Y1399973D01*
X1066966Y1400181D01*
X1067175Y1400431D01*
X1067216Y1400681D01*
X1067133Y1400973D01*
X1066841Y1401181D01*
X1066550Y1401264D01*
X1066175D01*
G01X1066550D02*
X1066800Y1401389D01*
X1067008Y1401598D01*
X1067091Y1401848D01*
X1067008Y1402098D01*
X1066800Y1402306D01*
X1066425Y1402431D01*
X1066050Y1402389D01*
X1065675Y1402223D01*
G01X1056159Y1403568D02*
Y1406068D01*
X1057200D01*
X1057534Y1405943D01*
X1057742Y1405776D01*
X1057825Y1405443D01*
X1057742Y1405110D01*
X1057492Y1404901D01*
X1057200Y1404776D01*
X1056159D01*
G01X1057200D02*
X1057825Y1403568D01*
G01X1060092D02*
Y1406068D01*
X1059592Y1405568D01*
G01Y1403568D02*
X1060592D01*
G01X1063192Y1406068D02*
X1062859Y1405985D01*
X1062609Y1405776D01*
X1062442Y1405526D01*
X1062317Y1405193D01*
X1062275Y1404818D01*
X1062317Y1404443D01*
X1062442Y1404110D01*
X1062609Y1403860D01*
X1062859Y1403651D01*
X1063192Y1403568D01*
X1063525Y1403651D01*
X1063775Y1403860D01*
X1063942Y1404110D01*
X1064067Y1404443D01*
X1064109Y1404818D01*
X1064067Y1405193D01*
X1063942Y1405526D01*
X1063775Y1405776D01*
X1063525Y1405985D01*
X1063192Y1406068D01*
G01X1065375Y1403943D02*
X1065625Y1403735D01*
X1065917Y1403610D01*
X1066292Y1403568D01*
X1066667Y1403651D01*
X1066959Y1403818D01*
X1067167Y1404110D01*
X1067209Y1404443D01*
X1067125Y1404776D01*
X1066917Y1404985D01*
X1066625Y1405151D01*
X1066334Y1405193D01*
X1066042Y1405151D01*
X1065667Y1404985D01*
X1065792Y1406068D01*
X1066917D01*
G01X1068600Y1404610D02*
X1068892Y1404901D01*
X1069142Y1405068D01*
X1069475Y1405151D01*
X1069767Y1405068D01*
X1069975Y1404901D01*
X1070142Y1404651D01*
X1070184Y1404360D01*
X1070142Y1404110D01*
X1069975Y1403860D01*
X1069725Y1403651D01*
X1069434Y1403568D01*
X1069100Y1403651D01*
X1068809Y1403901D01*
X1068642Y1404276D01*
X1068600Y1404693D01*
X1068684Y1405235D01*
X1068809Y1405526D01*
X1069017Y1405818D01*
X1069309Y1406026D01*
X1069600Y1406068D01*
X1069892Y1405985D01*
X1070100Y1405776D01*
G01X1056121Y1396362D02*
Y1398862D01*
X1057162D01*
X1057496Y1398737D01*
X1057704Y1398570D01*
X1057787Y1398237D01*
X1057704Y1397904D01*
X1057454Y1397695D01*
X1057162Y1397570D01*
X1056121D01*
G01X1057162D02*
X1057787Y1396362D01*
G01X1060054D02*
Y1398862D01*
X1059554Y1398362D01*
G01Y1396362D02*
X1060554D01*
G01X1063154Y1398862D02*
X1062821Y1398779D01*
X1062571Y1398570D01*
X1062404Y1398320D01*
X1062279Y1397987D01*
X1062237Y1397612D01*
X1062279Y1397237D01*
X1062404Y1396904D01*
X1062571Y1396654D01*
X1062821Y1396445D01*
X1063154Y1396362D01*
X1063487Y1396445D01*
X1063737Y1396654D01*
X1063904Y1396904D01*
X1064029Y1397237D01*
X1064071Y1397612D01*
X1064029Y1397987D01*
X1063904Y1398320D01*
X1063737Y1398570D01*
X1063487Y1398779D01*
X1063154Y1398862D01*
G01X1065337Y1396737D02*
X1065587Y1396529D01*
X1065879Y1396404D01*
X1066254Y1396362D01*
X1066629Y1396445D01*
X1066921Y1396612D01*
X1067129Y1396904D01*
X1067171Y1397237D01*
X1067087Y1397570D01*
X1066879Y1397779D01*
X1066587Y1397945D01*
X1066296Y1397987D01*
X1066004Y1397945D01*
X1065629Y1397779D01*
X1065754Y1398862D01*
X1066879D01*
G01X1068562Y1398445D02*
X1068812Y1398695D01*
X1069104Y1398820D01*
X1069437Y1398862D01*
X1069854Y1398779D01*
X1070146Y1398570D01*
X1070229Y1398320D01*
X1070187Y1398070D01*
X1070021Y1397862D01*
X1069187Y1397445D01*
X1068812Y1397154D01*
X1068562Y1396737D01*
X1068479Y1396362D01*
X1070229D01*
G01X1092183Y1342800D02*
Y1341008D01*
X1092350Y1340633D01*
X1092683Y1340383D01*
X1093100Y1340300D01*
X1093517Y1340383D01*
X1093850Y1340633D01*
X1094017Y1341008D01*
Y1342800D01*
G01X1096700Y1340300D02*
Y1342800D01*
X1095158Y1341008D01*
X1097242D01*
G01X1099300Y1340300D02*
X1099592Y1340342D01*
X1099925Y1340467D01*
X1100133Y1340675D01*
X1100217Y1340967D01*
X1100133Y1341258D01*
X1099883Y1341508D01*
X1099508Y1341633D01*
X1099092D01*
X1098842Y1341717D01*
X1098633Y1341925D01*
X1098550Y1342217D01*
X1098675Y1342508D01*
X1098967Y1342717D01*
X1099300Y1342800D01*
X1099633Y1342717D01*
X1099925Y1342508D01*
X1100050Y1342217D01*
X1099967Y1341925D01*
X1099758Y1341717D01*
X1099508Y1341633D01*
X1099092D01*
X1098717Y1341508D01*
X1098467Y1341258D01*
X1098383Y1340967D01*
X1098467Y1340675D01*
X1098675Y1340467D01*
X1099008Y1340342D01*
X1099300Y1340300D01*
G01X1109500Y1348315D02*
X1101500D01*
G01X1115500D02*
X1109500D01*
G01X1115500D02*
X1101500D01*
G01X1057943Y1442016D02*
X1055443D01*
Y1443057D01*
X1055568Y1443391D01*
X1055735Y1443599D01*
X1056068Y1443682D01*
X1056401Y1443599D01*
X1056610Y1443349D01*
X1056735Y1443057D01*
Y1442016D01*
G01Y1443057D02*
X1057943Y1443682D01*
G01Y1445949D02*
X1055443D01*
X1055943Y1445449D01*
G01X1057943D02*
Y1446449D01*
G01X1094272Y1502820D02*
Y1500320D01*
X1095938D01*
G01X1099038D02*
X1097372D01*
Y1502820D01*
X1099038D01*
G01X1098372Y1501612D02*
X1097372D01*
G01X1100388Y1500320D02*
Y1502820D01*
X1101222D01*
X1101555Y1502695D01*
X1101805Y1502528D01*
X1102013Y1502278D01*
X1102180Y1501987D01*
X1102222Y1501570D01*
X1102180Y1501153D01*
X1102013Y1500862D01*
X1101805Y1500612D01*
X1101555Y1500445D01*
X1101222Y1500320D01*
X1100388D01*
G01X1103613Y1502403D02*
X1103863Y1502653D01*
X1104155Y1502778D01*
X1104488Y1502820D01*
X1104905Y1502737D01*
X1105197Y1502528D01*
X1105280Y1502278D01*
X1105238Y1502028D01*
X1105072Y1501820D01*
X1104238Y1501403D01*
X1103863Y1501112D01*
X1103613Y1500695D01*
X1103530Y1500320D01*
X1105280D01*
G01X1106588Y1500695D02*
X1106838Y1500487D01*
X1107130Y1500362D01*
X1107505Y1500320D01*
X1107880Y1500403D01*
X1108172Y1500570D01*
X1108380Y1500862D01*
X1108422Y1501195D01*
X1108338Y1501528D01*
X1108130Y1501737D01*
X1107838Y1501903D01*
X1107547Y1501945D01*
X1107255Y1501903D01*
X1106880Y1501737D01*
X1107005Y1502820D01*
X1108130D01*
G01X1108900Y1497489D02*
X1090400D01*
Y1478889D01*
X1108900D01*
Y1497489D01*
G01X1059533Y1478167D02*
X1059333Y1477767D01*
X1059200Y1477300D01*
Y1476767D01*
X1059400Y1476167D01*
X1059733Y1475700D01*
X1060133Y1475367D01*
X1060800Y1475100D01*
X1061400Y1475033D01*
X1062000Y1475167D01*
X1062400Y1475367D01*
X1062800Y1475767D01*
X1063067Y1476233D01*
X1063200Y1476700D01*
Y1477167D01*
X1063067Y1477633D01*
X1062867Y1478033D01*
X1062600Y1478367D01*
G01X1062900Y1501233D02*
Y1498567D01*
X1058900D01*
Y1501233D01*
G01X1060833Y1500167D02*
Y1498567D01*
G01X1070305Y1479339D02*
X1053805D01*
Y1497039D01*
X1070305D01*
Y1479339D01*
G01X1117990Y1499580D02*
Y1502080D01*
X1119031D01*
X1119365Y1501955D01*
X1119573Y1501788D01*
X1119656Y1501455D01*
X1119573Y1501122D01*
X1119323Y1500913D01*
X1119031Y1500788D01*
X1117990D01*
G01X1119031D02*
X1119656Y1499580D01*
G01X1121923D02*
Y1502080D01*
X1121423Y1501580D01*
G01Y1499580D02*
X1122423D01*
G01X1125023Y1502080D02*
X1124690Y1501997D01*
X1124440Y1501788D01*
X1124273Y1501538D01*
X1124148Y1501205D01*
X1124106Y1500830D01*
X1124148Y1500455D01*
X1124273Y1500122D01*
X1124440Y1499872D01*
X1124690Y1499663D01*
X1125023Y1499580D01*
X1125356Y1499663D01*
X1125606Y1499872D01*
X1125773Y1500122D01*
X1125898Y1500455D01*
X1125940Y1500830D01*
X1125898Y1501205D01*
X1125773Y1501538D01*
X1125606Y1501788D01*
X1125356Y1501997D01*
X1125023Y1502080D01*
G01X1127331Y1500622D02*
X1127623Y1500913D01*
X1127873Y1501080D01*
X1128206Y1501163D01*
X1128498Y1501080D01*
X1128706Y1500913D01*
X1128873Y1500663D01*
X1128915Y1500372D01*
X1128873Y1500122D01*
X1128706Y1499872D01*
X1128456Y1499663D01*
X1128165Y1499580D01*
X1127831Y1499663D01*
X1127540Y1499913D01*
X1127373Y1500288D01*
X1127331Y1500705D01*
X1127415Y1501247D01*
X1127540Y1501538D01*
X1127748Y1501830D01*
X1128040Y1502038D01*
X1128331Y1502080D01*
X1128623Y1501997D01*
X1128831Y1501788D01*
G01X1130306Y1499955D02*
X1130556Y1499747D01*
X1130848Y1499622D01*
X1131223Y1499580D01*
X1131598Y1499663D01*
X1131890Y1499830D01*
X1132098Y1500122D01*
X1132140Y1500455D01*
X1132056Y1500788D01*
X1131848Y1500997D01*
X1131556Y1501163D01*
X1131265Y1501205D01*
X1130973Y1501163D01*
X1130598Y1500997D01*
X1130723Y1502080D01*
X1131848D01*
G01X1115173Y1496948D02*
X1120373D01*
G01X1115173Y1489948D02*
X1122973D01*
G01X1115173Y1496948D02*
Y1489948D01*
G01X1128573Y1496948D02*
X1119873D01*
G01X1128573Y1489948D02*
Y1496948D01*
G01X1122173Y1489948D02*
X1128573D01*
G01X1234967Y268500D02*
Y266000D01*
X1236633D01*
G01X1239733D02*
X1238067D01*
Y268500D01*
X1239733D01*
G01X1239067Y267292D02*
X1238067D01*
G01X1241083Y266000D02*
Y268500D01*
X1241917D01*
X1242250Y268375D01*
X1242500Y268208D01*
X1242708Y267958D01*
X1242875Y267667D01*
X1242917Y267250D01*
X1242875Y266833D01*
X1242708Y266542D01*
X1242500Y266292D01*
X1242250Y266125D01*
X1241917Y266000D01*
X1241083D01*
G01X1245100D02*
Y268500D01*
X1244600Y268000D01*
G01Y266000D02*
X1245600D01*
G01X1247492Y266292D02*
X1247783Y266083D01*
X1248117Y266000D01*
X1248450Y266083D01*
X1248742Y266333D01*
X1248950Y266708D01*
X1249033Y267083D01*
Y267542D01*
X1248950Y267917D01*
X1248742Y268250D01*
X1248492Y268417D01*
X1248200Y268500D01*
X1247867Y268417D01*
X1247617Y268250D01*
X1247450Y268000D01*
X1247367Y267667D01*
X1247450Y267375D01*
X1247658Y267083D01*
X1247908Y266917D01*
X1248200Y266875D01*
X1248533Y266958D01*
X1248783Y267167D01*
X1249033Y267542D01*
G01X1236348Y251880D02*
Y263080D01*
X1245148D01*
Y251880D01*
X1236348D01*
G01X1245500Y396517D02*
X1243000D01*
Y397558D01*
X1243125Y397892D01*
X1243292Y398100D01*
X1243625Y398183D01*
X1243958Y398100D01*
X1244167Y397850D01*
X1244292Y397558D01*
Y396517D01*
G01Y397558D02*
X1245500Y398183D01*
G01Y400950D02*
X1243000D01*
X1244792Y399408D01*
Y401492D01*
G01X1243417Y402758D02*
X1243167Y403008D01*
X1243042Y403300D01*
X1243000Y403633D01*
X1243083Y404050D01*
X1243292Y404342D01*
X1243542Y404425D01*
X1243792Y404383D01*
X1244000Y404217D01*
X1244417Y403383D01*
X1244708Y403008D01*
X1245125Y402758D01*
X1245500Y402675D01*
Y404425D01*
G01Y406650D02*
X1245458Y406942D01*
X1245333Y407275D01*
X1245125Y407483D01*
X1244833Y407567D01*
X1244542Y407483D01*
X1244292Y407233D01*
X1244167Y406858D01*
Y406442D01*
X1244083Y406192D01*
X1243875Y405983D01*
X1243583Y405900D01*
X1243292Y406025D01*
X1243083Y406317D01*
X1243000Y406650D01*
X1243083Y406983D01*
X1243292Y407275D01*
X1243583Y407400D01*
X1243875Y407317D01*
X1244083Y407108D01*
X1244167Y406858D01*
Y406442D01*
X1244292Y406067D01*
X1244542Y405817D01*
X1244833Y405733D01*
X1245125Y405817D01*
X1245333Y406025D01*
X1245458Y406358D01*
X1245500Y406650D01*
G01X1234517Y721500D02*
Y719000D01*
X1236183D01*
G01X1239283D02*
X1237617D01*
Y721500D01*
X1239283D01*
G01X1238617Y720292D02*
X1237617D01*
G01X1240633Y719000D02*
Y721500D01*
X1241467D01*
X1241800Y721375D01*
X1242050Y721208D01*
X1242258Y720958D01*
X1242425Y720667D01*
X1242467Y720250D01*
X1242425Y719833D01*
X1242258Y719542D01*
X1242050Y719292D01*
X1241800Y719125D01*
X1241467Y719000D01*
X1240633D01*
G01X1244567D02*
X1244650Y719542D01*
X1244775Y720000D01*
X1244942Y720417D01*
X1245150Y720875D01*
X1245483Y721500D01*
X1243817D01*
G01X1236348Y704636D02*
Y715836D01*
X1245148D01*
Y704636D01*
X1236348D01*
G01X1199017Y834500D02*
Y837000D01*
X1200058D01*
X1200392Y836875D01*
X1200600Y836708D01*
X1200683Y836375D01*
X1200600Y836042D01*
X1200350Y835833D01*
X1200058Y835708D01*
X1199017D01*
G01X1200058D02*
X1200683Y834500D01*
G01X1202158Y836583D02*
X1202408Y836833D01*
X1202700Y836958D01*
X1203033Y837000D01*
X1203450Y836917D01*
X1203742Y836708D01*
X1203825Y836458D01*
X1203783Y836208D01*
X1203617Y836000D01*
X1202783Y835583D01*
X1202408Y835292D01*
X1202158Y834875D01*
X1202075Y834500D01*
X1203825D01*
G01X1206550D02*
Y837000D01*
X1205008Y835208D01*
X1207092D01*
G01X1208233Y834875D02*
X1208483Y834667D01*
X1208775Y834542D01*
X1209150Y834500D01*
X1209525Y834583D01*
X1209817Y834750D01*
X1210025Y835042D01*
X1210067Y835375D01*
X1209983Y835708D01*
X1209775Y835917D01*
X1209483Y836083D01*
X1209192Y836125D01*
X1208900Y836083D01*
X1208525Y835917D01*
X1208650Y837000D01*
X1209775D01*
G01X1219061Y834182D02*
Y838182D01*
X1211661D01*
G01X1233794Y853959D02*
Y857959D01*
X1226394D01*
G01X1240462Y849305D02*
X1237962D01*
Y850346D01*
X1238087Y850680D01*
X1238254Y850888D01*
X1238587Y850971D01*
X1238920Y850888D01*
X1239129Y850638D01*
X1239254Y850346D01*
Y849305D01*
G01Y850346D02*
X1240462Y850971D01*
G01X1239962Y852321D02*
X1240254Y852571D01*
X1240420Y852905D01*
X1240462Y853280D01*
X1240420Y853613D01*
X1240212Y853946D01*
X1239962Y854155D01*
X1239712Y854196D01*
X1239420Y854113D01*
X1239212Y853821D01*
X1239129Y853530D01*
Y853155D01*
G01Y853530D02*
X1239004Y853780D01*
X1238795Y853988D01*
X1238545Y854071D01*
X1238295Y853988D01*
X1238087Y853780D01*
X1237962Y853405D01*
X1238004Y853030D01*
X1238170Y852655D01*
G01X1237962Y856338D02*
X1238045Y856005D01*
X1238254Y855755D01*
X1238504Y855588D01*
X1238837Y855463D01*
X1239212Y855421D01*
X1239587Y855463D01*
X1239920Y855588D01*
X1240170Y855755D01*
X1240379Y856005D01*
X1240462Y856338D01*
X1240379Y856671D01*
X1240170Y856921D01*
X1239920Y857088D01*
X1239587Y857213D01*
X1239212Y857255D01*
X1238837Y857213D01*
X1238504Y857088D01*
X1238254Y856921D01*
X1238045Y856671D01*
X1237962Y856338D01*
G01Y859438D02*
X1238045Y859105D01*
X1238254Y858855D01*
X1238504Y858688D01*
X1238837Y858563D01*
X1239212Y858521D01*
X1239587Y858563D01*
X1239920Y858688D01*
X1240170Y858855D01*
X1240379Y859105D01*
X1240462Y859438D01*
X1240379Y859771D01*
X1240170Y860021D01*
X1239920Y860188D01*
X1239587Y860313D01*
X1239212Y860355D01*
X1238837Y860313D01*
X1238504Y860188D01*
X1238254Y860021D01*
X1238045Y859771D01*
X1237962Y859438D01*
G01X1244462Y849305D02*
X1241962D01*
Y850346D01*
X1242087Y850680D01*
X1242254Y850888D01*
X1242587Y850971D01*
X1242920Y850888D01*
X1243129Y850638D01*
X1243254Y850346D01*
Y849305D01*
G01Y850346D02*
X1244462Y850971D01*
G01X1243962Y852321D02*
X1244254Y852571D01*
X1244420Y852905D01*
X1244462Y853280D01*
X1244420Y853613D01*
X1244212Y853946D01*
X1243962Y854155D01*
X1243712Y854196D01*
X1243420Y854113D01*
X1243212Y853821D01*
X1243129Y853530D01*
Y853155D01*
G01Y853530D02*
X1243004Y853780D01*
X1242795Y853988D01*
X1242545Y854071D01*
X1242295Y853988D01*
X1242087Y853780D01*
X1241962Y853405D01*
X1242004Y853030D01*
X1242170Y852655D01*
G01X1241962Y856338D02*
X1242045Y856005D01*
X1242254Y855755D01*
X1242504Y855588D01*
X1242837Y855463D01*
X1243212Y855421D01*
X1243587Y855463D01*
X1243920Y855588D01*
X1244170Y855755D01*
X1244379Y856005D01*
X1244462Y856338D01*
X1244379Y856671D01*
X1244170Y856921D01*
X1243920Y857088D01*
X1243587Y857213D01*
X1243212Y857255D01*
X1242837Y857213D01*
X1242504Y857088D01*
X1242254Y856921D01*
X1242045Y856671D01*
X1241962Y856338D01*
G01X1244462Y859438D02*
X1241962D01*
X1242462Y858938D01*
G01X1244462D02*
Y859938D01*
G01X1224850Y835000D02*
X1224517Y835042D01*
X1224225Y835208D01*
X1223975Y835458D01*
X1223808Y835750D01*
X1223725Y836083D01*
Y836417D01*
X1223808Y836750D01*
X1223975Y837042D01*
X1224225Y837292D01*
X1224517Y837458D01*
X1224850Y837500D01*
X1225183Y837458D01*
X1225475Y837292D01*
X1225725Y837042D01*
X1225892Y836750D01*
X1225975Y836417D01*
Y836083D01*
X1225892Y835750D01*
X1225725Y835458D01*
X1225475Y835208D01*
X1225183Y835042D01*
X1224850Y835000D01*
G01X1225183Y835667D02*
X1225683Y835000D01*
G01X1227158Y837083D02*
X1227408Y837333D01*
X1227700Y837458D01*
X1228033Y837500D01*
X1228450Y837417D01*
X1228742Y837208D01*
X1228825Y836958D01*
X1228783Y836708D01*
X1228617Y836500D01*
X1227783Y836083D01*
X1227408Y835792D01*
X1227158Y835375D01*
X1227075Y835000D01*
X1228825D01*
G01X1230258Y837083D02*
X1230508Y837333D01*
X1230800Y837458D01*
X1231133Y837500D01*
X1231550Y837417D01*
X1231842Y837208D01*
X1231925Y836958D01*
X1231883Y836708D01*
X1231717Y836500D01*
X1230883Y836083D01*
X1230508Y835792D01*
X1230258Y835375D01*
X1230175Y835000D01*
X1231925D01*
G01X1233233Y835375D02*
X1233483Y835167D01*
X1233775Y835042D01*
X1234150Y835000D01*
X1234525Y835083D01*
X1234817Y835250D01*
X1235025Y835542D01*
X1235067Y835875D01*
X1234983Y836208D01*
X1234775Y836417D01*
X1234483Y836583D01*
X1234192Y836625D01*
X1233900Y836583D01*
X1233525Y836417D01*
X1233650Y837500D01*
X1234775D01*
G01X1234469Y838500D02*
Y852500D01*
G01X1221469Y838500D02*
X1234469D01*
G01X1221469Y852500D02*
Y838500D01*
G01X1234469Y852500D02*
X1221469D01*
G01X1209250Y854000D02*
X1208917Y854042D01*
X1208625Y854208D01*
X1208375Y854458D01*
X1208208Y854750D01*
X1208125Y855083D01*
Y855417D01*
X1208208Y855750D01*
X1208375Y856042D01*
X1208625Y856292D01*
X1208917Y856458D01*
X1209250Y856500D01*
X1209583Y856458D01*
X1209875Y856292D01*
X1210125Y856042D01*
X1210292Y855750D01*
X1210375Y855417D01*
Y855083D01*
X1210292Y854750D01*
X1210125Y854458D01*
X1209875Y854208D01*
X1209583Y854042D01*
X1209250Y854000D01*
G01X1209583Y854667D02*
X1210083Y854000D01*
G01X1211558Y856083D02*
X1211808Y856333D01*
X1212100Y856458D01*
X1212433Y856500D01*
X1212850Y856417D01*
X1213142Y856208D01*
X1213225Y855958D01*
X1213183Y855708D01*
X1213017Y855500D01*
X1212183Y855083D01*
X1211808Y854792D01*
X1211558Y854375D01*
X1211475Y854000D01*
X1213225D01*
G01X1215950D02*
Y856500D01*
X1214408Y854708D01*
X1216492D01*
G01X1217842Y854292D02*
X1218133Y854083D01*
X1218467Y854000D01*
X1218800Y854083D01*
X1219092Y854333D01*
X1219300Y854708D01*
X1219383Y855083D01*
Y855542D01*
X1219300Y855917D01*
X1219092Y856250D01*
X1218842Y856417D01*
X1218550Y856500D01*
X1218217Y856417D01*
X1217967Y856250D01*
X1217800Y856000D01*
X1217717Y855667D01*
X1217800Y855375D01*
X1218008Y855083D01*
X1218258Y854917D01*
X1218550Y854875D01*
X1218883Y854958D01*
X1219133Y855167D01*
X1219383Y855542D01*
G01X1206361Y839407D02*
X1220361D01*
G01X1206361Y852407D02*
Y839407D01*
G01X1220361Y852407D02*
X1206361D01*
G01X1220361Y839407D02*
Y852407D01*
G01X1202811Y917262D02*
Y919762D01*
X1203852D01*
X1204186Y919637D01*
X1204394Y919470D01*
X1204477Y919137D01*
X1204394Y918804D01*
X1204144Y918595D01*
X1203852Y918470D01*
X1202811D01*
G01X1203852D02*
X1204477Y917262D01*
G01X1206036Y917554D02*
X1206327Y917345D01*
X1206661Y917262D01*
X1206994Y917345D01*
X1207286Y917595D01*
X1207494Y917970D01*
X1207577Y918345D01*
Y918804D01*
X1207494Y919179D01*
X1207286Y919512D01*
X1207036Y919679D01*
X1206744Y919762D01*
X1206411Y919679D01*
X1206161Y919512D01*
X1205994Y919262D01*
X1205911Y918929D01*
X1205994Y918637D01*
X1206202Y918345D01*
X1206452Y918179D01*
X1206744Y918137D01*
X1207077Y918220D01*
X1207327Y918429D01*
X1207577Y918804D01*
G01X1209844Y917262D02*
Y919762D01*
X1209344Y919262D01*
G01Y917262D02*
X1210344D01*
G01X1212236Y917554D02*
X1212527Y917345D01*
X1212861Y917262D01*
X1213194Y917345D01*
X1213486Y917595D01*
X1213694Y917970D01*
X1213777Y918345D01*
Y918804D01*
X1213694Y919179D01*
X1213486Y919512D01*
X1213236Y919679D01*
X1212944Y919762D01*
X1212611Y919679D01*
X1212361Y919512D01*
X1212194Y919262D01*
X1212111Y918929D01*
X1212194Y918637D01*
X1212402Y918345D01*
X1212652Y918179D01*
X1212944Y918137D01*
X1213277Y918220D01*
X1213527Y918429D01*
X1213777Y918804D01*
G01X1191594Y920091D02*
Y916091D01*
X1198994D01*
G01X1202741Y911502D02*
Y914002D01*
X1203782D01*
X1204116Y913877D01*
X1204324Y913710D01*
X1204407Y913377D01*
X1204324Y913044D01*
X1204074Y912835D01*
X1203782Y912710D01*
X1202741D01*
G01X1203782D02*
X1204407Y911502D01*
G01X1205966Y911794D02*
X1206257Y911585D01*
X1206591Y911502D01*
X1206924Y911585D01*
X1207216Y911835D01*
X1207424Y912210D01*
X1207507Y912585D01*
Y913044D01*
X1207424Y913419D01*
X1207216Y913752D01*
X1206966Y913919D01*
X1206674Y914002D01*
X1206341Y913919D01*
X1206091Y913752D01*
X1205924Y913502D01*
X1205841Y913169D01*
X1205924Y912877D01*
X1206132Y912585D01*
X1206382Y912419D01*
X1206674Y912377D01*
X1207007Y912460D01*
X1207257Y912669D01*
X1207507Y913044D01*
G01X1208982Y913585D02*
X1209232Y913835D01*
X1209524Y913960D01*
X1209857Y914002D01*
X1210274Y913919D01*
X1210566Y913710D01*
X1210649Y913460D01*
X1210607Y913210D01*
X1210441Y913002D01*
X1209607Y912585D01*
X1209232Y912294D01*
X1208982Y911877D01*
X1208899Y911502D01*
X1210649D01*
G01X1212874Y914002D02*
X1212541Y913919D01*
X1212291Y913710D01*
X1212124Y913460D01*
X1211999Y913127D01*
X1211957Y912752D01*
X1211999Y912377D01*
X1212124Y912044D01*
X1212291Y911794D01*
X1212541Y911585D01*
X1212874Y911502D01*
X1213207Y911585D01*
X1213457Y911794D01*
X1213624Y912044D01*
X1213749Y912377D01*
X1213791Y912752D01*
X1213749Y913127D01*
X1213624Y913460D01*
X1213457Y913710D01*
X1213207Y913919D01*
X1212874Y914002D01*
G01X1191524Y914331D02*
Y910331D01*
X1198924D01*
G01X1192117Y891261D02*
Y893761D01*
X1193158D01*
X1193492Y893636D01*
X1193700Y893469D01*
X1193783Y893136D01*
X1193700Y892803D01*
X1193450Y892594D01*
X1193158Y892469D01*
X1192117D01*
G01X1193158D02*
X1193783Y891261D01*
G01X1195967D02*
X1196050Y891803D01*
X1196175Y892261D01*
X1196342Y892678D01*
X1196550Y893136D01*
X1196883Y893761D01*
X1195217D01*
G01X1190200Y890600D02*
Y894600D01*
X1182800D01*
G01X1192117Y884661D02*
Y887161D01*
X1193158D01*
X1193492Y887036D01*
X1193700Y886869D01*
X1193783Y886536D01*
X1193700Y886203D01*
X1193450Y885994D01*
X1193158Y885869D01*
X1192117D01*
G01X1193158D02*
X1193783Y884661D01*
G01X1195258Y885703D02*
X1195550Y885994D01*
X1195800Y886161D01*
X1196133Y886244D01*
X1196425Y886161D01*
X1196633Y885994D01*
X1196800Y885744D01*
X1196842Y885453D01*
X1196800Y885203D01*
X1196633Y884953D01*
X1196383Y884744D01*
X1196092Y884661D01*
X1195758Y884744D01*
X1195467Y884994D01*
X1195300Y885369D01*
X1195258Y885786D01*
X1195342Y886328D01*
X1195467Y886619D01*
X1195675Y886911D01*
X1195967Y887119D01*
X1196258Y887161D01*
X1196550Y887078D01*
X1196758Y886869D01*
G01X1190200Y884000D02*
Y888000D01*
X1182800D01*
G01X1196102Y902392D02*
Y904892D01*
X1197143D01*
X1197477Y904767D01*
X1197685Y904600D01*
X1197768Y904267D01*
X1197685Y903934D01*
X1197435Y903725D01*
X1197143Y903600D01*
X1196102D01*
G01X1197143D02*
X1197768Y902392D01*
G01X1199118Y902767D02*
X1199368Y902559D01*
X1199660Y902434D01*
X1200035Y902392D01*
X1200410Y902475D01*
X1200702Y902642D01*
X1200910Y902934D01*
X1200952Y903267D01*
X1200868Y903600D01*
X1200660Y903809D01*
X1200368Y903975D01*
X1200077Y904017D01*
X1199785Y903975D01*
X1199410Y903809D01*
X1199535Y904892D01*
X1200660D01*
G01X1190200Y904100D02*
Y908100D01*
X1182800D01*
G01X1192117Y897161D02*
Y899661D01*
X1193158D01*
X1193492Y899536D01*
X1193700Y899369D01*
X1193783Y899036D01*
X1193700Y898703D01*
X1193450Y898494D01*
X1193158Y898369D01*
X1192117D01*
G01X1193158D02*
X1193783Y897161D01*
G01X1196550D02*
Y899661D01*
X1195008Y897869D01*
X1197092D01*
G01X1190200Y897500D02*
Y901500D01*
X1182800D01*
G01X1223517Y860000D02*
Y862500D01*
X1224558D01*
X1224892Y862375D01*
X1225100Y862208D01*
X1225183Y861875D01*
X1225100Y861542D01*
X1224850Y861333D01*
X1224558Y861208D01*
X1223517D01*
G01X1224558D02*
X1225183Y860000D01*
G01X1226658Y862083D02*
X1226908Y862333D01*
X1227200Y862458D01*
X1227533Y862500D01*
X1227950Y862417D01*
X1228242Y862208D01*
X1228325Y861958D01*
X1228283Y861708D01*
X1228117Y861500D01*
X1227283Y861083D01*
X1226908Y860792D01*
X1226658Y860375D01*
X1226575Y860000D01*
X1228325D01*
G01X1231050D02*
Y862500D01*
X1229508Y860708D01*
X1231592D01*
G01X1232858Y862083D02*
X1233108Y862333D01*
X1233400Y862458D01*
X1233733Y862500D01*
X1234150Y862417D01*
X1234442Y862208D01*
X1234525Y861958D01*
X1234483Y861708D01*
X1234317Y861500D01*
X1233483Y861083D01*
X1233108Y860792D01*
X1232858Y860375D01*
X1232775Y860000D01*
X1234525D01*
G01X1160517Y1179000D02*
Y1181500D01*
X1161517D01*
X1161850Y1181375D01*
X1162100Y1181083D01*
X1162183Y1180750D01*
X1162100Y1180417D01*
X1161892Y1180167D01*
X1161517Y1180042D01*
X1160517D01*
G01X1163200Y1181500D02*
X1163783Y1179000D01*
X1164450Y1181500D01*
X1165117Y1179000D01*
X1165700Y1181500D01*
G01X1166717Y1179000D02*
Y1181500D01*
X1167758D01*
X1168092Y1181375D01*
X1168300Y1181208D01*
X1168383Y1180875D01*
X1168300Y1180542D01*
X1168050Y1180333D01*
X1167758Y1180208D01*
X1166717D01*
G01X1167758D02*
X1168383Y1179000D01*
G01X1170650D02*
Y1181500D01*
X1170150Y1181000D01*
G01Y1179000D02*
X1171150D01*
G01X1174541Y1320050D02*
X1174416Y1319800D01*
X1174333Y1319508D01*
Y1319175D01*
X1174458Y1318800D01*
X1174666Y1318508D01*
X1174916Y1318300D01*
X1175333Y1318133D01*
X1175708Y1318091D01*
X1176083Y1318175D01*
X1176333Y1318300D01*
X1176583Y1318550D01*
X1176750Y1318841D01*
X1176833Y1319133D01*
Y1319425D01*
X1176750Y1319716D01*
X1176625Y1319966D01*
X1176458Y1320175D01*
G01X1174750Y1321441D02*
X1174500Y1321691D01*
X1174375Y1321983D01*
X1174333Y1322316D01*
X1174416Y1322733D01*
X1174625Y1323025D01*
X1174875Y1323108D01*
X1175125Y1323066D01*
X1175333Y1322900D01*
X1175750Y1322066D01*
X1176041Y1321691D01*
X1176458Y1321441D01*
X1176833Y1321358D01*
Y1323108D01*
G01Y1325333D02*
X1174333D01*
X1174833Y1324833D01*
G01X1176833D02*
Y1325833D01*
G01X1207708Y1299817D02*
X1207583Y1299567D01*
X1207500Y1299275D01*
Y1298942D01*
X1207625Y1298567D01*
X1207833Y1298275D01*
X1208083Y1298067D01*
X1208500Y1297900D01*
X1208875Y1297858D01*
X1209250Y1297942D01*
X1209500Y1298067D01*
X1209750Y1298317D01*
X1209917Y1298608D01*
X1210000Y1298900D01*
Y1299192D01*
X1209917Y1299483D01*
X1209792Y1299733D01*
X1209625Y1299942D01*
G01X1207917Y1301208D02*
X1207667Y1301458D01*
X1207542Y1301750D01*
X1207500Y1302083D01*
X1207583Y1302500D01*
X1207792Y1302792D01*
X1208042Y1302875D01*
X1208292Y1302833D01*
X1208500Y1302667D01*
X1208917Y1301833D01*
X1209208Y1301458D01*
X1209625Y1301208D01*
X1210000Y1301125D01*
Y1302875D01*
G01X1208958Y1304308D02*
X1208667Y1304600D01*
X1208500Y1304850D01*
X1208417Y1305183D01*
X1208500Y1305475D01*
X1208667Y1305683D01*
X1208917Y1305850D01*
X1209208Y1305892D01*
X1209458Y1305850D01*
X1209708Y1305683D01*
X1209917Y1305433D01*
X1210000Y1305142D01*
X1209917Y1304808D01*
X1209667Y1304517D01*
X1209292Y1304350D01*
X1208875Y1304308D01*
X1208333Y1304392D01*
X1208042Y1304517D01*
X1207750Y1304725D01*
X1207542Y1305017D01*
X1207500Y1305308D01*
X1207583Y1305600D01*
X1207792Y1305808D01*
G01X1225069Y1271800D02*
X1222569D01*
Y1272841D01*
X1222694Y1273175D01*
X1222861Y1273383D01*
X1223194Y1273466D01*
X1223527Y1273383D01*
X1223736Y1273133D01*
X1223861Y1272841D01*
Y1271800D01*
G01Y1272841D02*
X1225069Y1273466D01*
G01Y1275733D02*
X1222569D01*
X1223069Y1275233D01*
G01X1225069D02*
Y1276233D01*
G01Y1278833D02*
X1222569D01*
X1223069Y1278333D01*
G01X1225069D02*
Y1279333D01*
G01X1224694Y1281016D02*
X1224902Y1281266D01*
X1225027Y1281558D01*
X1225069Y1281933D01*
X1224986Y1282308D01*
X1224819Y1282600D01*
X1224527Y1282808D01*
X1224194Y1282850D01*
X1223861Y1282766D01*
X1223652Y1282558D01*
X1223486Y1282266D01*
X1223444Y1281975D01*
X1223486Y1281683D01*
X1223652Y1281308D01*
X1222569Y1281433D01*
Y1282558D01*
G01X1225730Y1294483D02*
X1221730D01*
Y1287083D01*
G01X1236939Y1271800D02*
X1234439D01*
Y1272841D01*
X1234564Y1273175D01*
X1234731Y1273383D01*
X1235064Y1273466D01*
X1235397Y1273383D01*
X1235606Y1273133D01*
X1235731Y1272841D01*
Y1271800D01*
G01Y1272841D02*
X1236939Y1273466D01*
G01Y1275733D02*
X1234439D01*
X1234939Y1275233D01*
G01X1236939D02*
Y1276233D01*
G01X1234439Y1278833D02*
X1234522Y1278500D01*
X1234731Y1278250D01*
X1234981Y1278083D01*
X1235314Y1277958D01*
X1235689Y1277916D01*
X1236064Y1277958D01*
X1236397Y1278083D01*
X1236647Y1278250D01*
X1236856Y1278500D01*
X1236939Y1278833D01*
X1236856Y1279166D01*
X1236647Y1279416D01*
X1236397Y1279583D01*
X1236064Y1279708D01*
X1235689Y1279750D01*
X1235314Y1279708D01*
X1234981Y1279583D01*
X1234731Y1279416D01*
X1234522Y1279166D01*
X1234439Y1278833D01*
G01X1236439Y1281016D02*
X1236731Y1281266D01*
X1236897Y1281600D01*
X1236939Y1281975D01*
X1236897Y1282308D01*
X1236689Y1282641D01*
X1236439Y1282850D01*
X1236189Y1282891D01*
X1235897Y1282808D01*
X1235689Y1282516D01*
X1235606Y1282225D01*
Y1281850D01*
G01Y1282225D02*
X1235481Y1282475D01*
X1235272Y1282683D01*
X1235022Y1282766D01*
X1234772Y1282683D01*
X1234564Y1282475D01*
X1234439Y1282100D01*
X1234481Y1281725D01*
X1234647Y1281350D01*
G01X1237600Y1294483D02*
X1233600D01*
Y1287083D01*
G01X1231939Y1271800D02*
X1229439D01*
Y1272841D01*
X1229564Y1273175D01*
X1229731Y1273383D01*
X1230064Y1273466D01*
X1230397Y1273383D01*
X1230606Y1273133D01*
X1230731Y1272841D01*
Y1271800D01*
G01Y1272841D02*
X1231939Y1273466D01*
G01Y1275733D02*
X1229439D01*
X1229939Y1275233D01*
G01X1231939D02*
Y1276233D01*
G01X1231564Y1277916D02*
X1231772Y1278166D01*
X1231897Y1278458D01*
X1231939Y1278833D01*
X1231856Y1279208D01*
X1231689Y1279500D01*
X1231397Y1279708D01*
X1231064Y1279750D01*
X1230731Y1279666D01*
X1230522Y1279458D01*
X1230356Y1279166D01*
X1230314Y1278875D01*
X1230356Y1278583D01*
X1230522Y1278208D01*
X1229439Y1278333D01*
Y1279458D01*
G01X1231939Y1281933D02*
X1231897Y1282225D01*
X1231772Y1282558D01*
X1231564Y1282766D01*
X1231272Y1282850D01*
X1230981Y1282766D01*
X1230731Y1282516D01*
X1230606Y1282141D01*
Y1281725D01*
X1230522Y1281475D01*
X1230314Y1281266D01*
X1230022Y1281183D01*
X1229731Y1281308D01*
X1229522Y1281600D01*
X1229439Y1281933D01*
X1229522Y1282266D01*
X1229731Y1282558D01*
X1230022Y1282683D01*
X1230314Y1282600D01*
X1230522Y1282391D01*
X1230606Y1282141D01*
Y1281725D01*
X1230731Y1281350D01*
X1230981Y1281100D01*
X1231272Y1281016D01*
X1231564Y1281100D01*
X1231772Y1281308D01*
X1231897Y1281641D01*
X1231939Y1281933D01*
G01X1232600Y1294483D02*
X1228600D01*
Y1287083D01*
G01X1191363Y1275350D02*
X1188863D01*
Y1276391D01*
X1188988Y1276725D01*
X1189155Y1276933D01*
X1189488Y1277016D01*
X1189821Y1276933D01*
X1190030Y1276683D01*
X1190155Y1276391D01*
Y1275350D01*
G01Y1276391D02*
X1191363Y1277016D01*
G01X1191071Y1278575D02*
X1191280Y1278866D01*
X1191363Y1279200D01*
X1191280Y1279533D01*
X1191030Y1279825D01*
X1190655Y1280033D01*
X1190280Y1280116D01*
X1189821D01*
X1189446Y1280033D01*
X1189113Y1279825D01*
X1188946Y1279575D01*
X1188863Y1279283D01*
X1188946Y1278950D01*
X1189113Y1278700D01*
X1189363Y1278533D01*
X1189696Y1278450D01*
X1189988Y1278533D01*
X1190280Y1278741D01*
X1190446Y1278991D01*
X1190488Y1279283D01*
X1190405Y1279616D01*
X1190196Y1279866D01*
X1189821Y1280116D01*
G01X1190321Y1281591D02*
X1190030Y1281883D01*
X1189863Y1282133D01*
X1189780Y1282466D01*
X1189863Y1282758D01*
X1190030Y1282966D01*
X1190280Y1283133D01*
X1190571Y1283175D01*
X1190821Y1283133D01*
X1191071Y1282966D01*
X1191280Y1282716D01*
X1191363Y1282425D01*
X1191280Y1282091D01*
X1191030Y1281800D01*
X1190655Y1281633D01*
X1190238Y1281591D01*
X1189696Y1281675D01*
X1189405Y1281800D01*
X1189113Y1282008D01*
X1188905Y1282300D01*
X1188863Y1282591D01*
X1188946Y1282883D01*
X1189155Y1283091D01*
G01X1192524Y1294483D02*
X1188524D01*
Y1287083D01*
G01X1198233Y1275350D02*
X1195733D01*
Y1276391D01*
X1195858Y1276725D01*
X1196025Y1276933D01*
X1196358Y1277016D01*
X1196691Y1276933D01*
X1196900Y1276683D01*
X1197025Y1276391D01*
Y1275350D01*
G01Y1276391D02*
X1198233Y1277016D01*
G01X1197941Y1278575D02*
X1198150Y1278866D01*
X1198233Y1279200D01*
X1198150Y1279533D01*
X1197900Y1279825D01*
X1197525Y1280033D01*
X1197150Y1280116D01*
X1196691D01*
X1196316Y1280033D01*
X1195983Y1279825D01*
X1195816Y1279575D01*
X1195733Y1279283D01*
X1195816Y1278950D01*
X1195983Y1278700D01*
X1196233Y1278533D01*
X1196566Y1278450D01*
X1196858Y1278533D01*
X1197150Y1278741D01*
X1197316Y1278991D01*
X1197358Y1279283D01*
X1197275Y1279616D01*
X1197066Y1279866D01*
X1196691Y1280116D01*
G01X1198233Y1282300D02*
X1197691Y1282383D01*
X1197233Y1282508D01*
X1196816Y1282675D01*
X1196358Y1282883D01*
X1195733Y1283216D01*
Y1281550D01*
G01X1199394Y1294483D02*
X1195394D01*
Y1287083D01*
G01X1203233Y1275350D02*
X1200733D01*
Y1276391D01*
X1200858Y1276725D01*
X1201025Y1276933D01*
X1201358Y1277016D01*
X1201691Y1276933D01*
X1201900Y1276683D01*
X1202025Y1276391D01*
Y1275350D01*
G01Y1276391D02*
X1203233Y1277016D01*
G01X1202941Y1278575D02*
X1203150Y1278866D01*
X1203233Y1279200D01*
X1203150Y1279533D01*
X1202900Y1279825D01*
X1202525Y1280033D01*
X1202150Y1280116D01*
X1201691D01*
X1201316Y1280033D01*
X1200983Y1279825D01*
X1200816Y1279575D01*
X1200733Y1279283D01*
X1200816Y1278950D01*
X1200983Y1278700D01*
X1201233Y1278533D01*
X1201566Y1278450D01*
X1201858Y1278533D01*
X1202150Y1278741D01*
X1202316Y1278991D01*
X1202358Y1279283D01*
X1202275Y1279616D01*
X1202066Y1279866D01*
X1201691Y1280116D01*
G01X1203233Y1282383D02*
X1203191Y1282675D01*
X1203066Y1283008D01*
X1202858Y1283216D01*
X1202566Y1283300D01*
X1202275Y1283216D01*
X1202025Y1282966D01*
X1201900Y1282591D01*
Y1282175D01*
X1201816Y1281925D01*
X1201608Y1281716D01*
X1201316Y1281633D01*
X1201025Y1281758D01*
X1200816Y1282050D01*
X1200733Y1282383D01*
X1200816Y1282716D01*
X1201025Y1283008D01*
X1201316Y1283133D01*
X1201608Y1283050D01*
X1201816Y1282841D01*
X1201900Y1282591D01*
Y1282175D01*
X1202025Y1281800D01*
X1202275Y1281550D01*
X1202566Y1281466D01*
X1202858Y1281550D01*
X1203066Y1281758D01*
X1203191Y1282091D01*
X1203233Y1282383D01*
G01X1204394Y1294483D02*
X1200394D01*
Y1287083D01*
G01X1212208Y1298317D02*
X1212083Y1298067D01*
X1212000Y1297775D01*
Y1297442D01*
X1212125Y1297067D01*
X1212333Y1296775D01*
X1212583Y1296567D01*
X1213000Y1296400D01*
X1213375Y1296358D01*
X1213750Y1296442D01*
X1214000Y1296567D01*
X1214250Y1296817D01*
X1214417Y1297108D01*
X1214500Y1297400D01*
Y1297692D01*
X1214417Y1297983D01*
X1214292Y1298233D01*
X1214125Y1298442D01*
G01X1214000Y1299583D02*
X1214292Y1299833D01*
X1214458Y1300167D01*
X1214500Y1300542D01*
X1214458Y1300875D01*
X1214250Y1301208D01*
X1214000Y1301417D01*
X1213750Y1301458D01*
X1213458Y1301375D01*
X1213250Y1301083D01*
X1213167Y1300792D01*
Y1300417D01*
G01Y1300792D02*
X1213042Y1301042D01*
X1212833Y1301250D01*
X1212583Y1301333D01*
X1212333Y1301250D01*
X1212125Y1301042D01*
X1212000Y1300667D01*
X1212042Y1300292D01*
X1212208Y1299917D01*
G01X1214500Y1303600D02*
X1214458Y1303892D01*
X1214333Y1304225D01*
X1214125Y1304433D01*
X1213833Y1304517D01*
X1213542Y1304433D01*
X1213292Y1304183D01*
X1213167Y1303808D01*
Y1303392D01*
X1213083Y1303142D01*
X1212875Y1302933D01*
X1212583Y1302850D01*
X1212292Y1302975D01*
X1212083Y1303267D01*
X1212000Y1303600D01*
X1212083Y1303933D01*
X1212292Y1304225D01*
X1212583Y1304350D01*
X1212875Y1304267D01*
X1213083Y1304058D01*
X1213167Y1303808D01*
Y1303392D01*
X1213292Y1303017D01*
X1213542Y1302767D01*
X1213833Y1302683D01*
X1214125Y1302767D01*
X1214333Y1302975D01*
X1214458Y1303308D01*
X1214500Y1303600D01*
G01X1178674Y1319683D02*
X1178549Y1319433D01*
X1178466Y1319141D01*
Y1318808D01*
X1178591Y1318433D01*
X1178799Y1318141D01*
X1179049Y1317933D01*
X1179466Y1317766D01*
X1179841Y1317724D01*
X1180216Y1317808D01*
X1180466Y1317933D01*
X1180716Y1318183D01*
X1180883Y1318474D01*
X1180966Y1318766D01*
Y1319058D01*
X1180883Y1319349D01*
X1180758Y1319599D01*
X1180591Y1319808D01*
G01X1178883Y1321074D02*
X1178633Y1321324D01*
X1178508Y1321616D01*
X1178466Y1321949D01*
X1178549Y1322366D01*
X1178758Y1322658D01*
X1179008Y1322741D01*
X1179258Y1322699D01*
X1179466Y1322533D01*
X1179883Y1321699D01*
X1180174Y1321324D01*
X1180591Y1321074D01*
X1180966Y1320991D01*
Y1322741D01*
G01X1178883Y1324174D02*
X1178633Y1324424D01*
X1178508Y1324716D01*
X1178466Y1325049D01*
X1178549Y1325466D01*
X1178758Y1325758D01*
X1179008Y1325841D01*
X1179258Y1325799D01*
X1179466Y1325633D01*
X1179883Y1324799D01*
X1180174Y1324424D01*
X1180591Y1324174D01*
X1180966Y1324091D01*
Y1325841D01*
G01X1241394Y1311766D02*
X1243186D01*
X1243561Y1311933D01*
X1243811Y1312266D01*
X1243894Y1312683D01*
X1243811Y1313100D01*
X1243561Y1313433D01*
X1243186Y1313600D01*
X1241394D01*
G01X1241811Y1314991D02*
X1241561Y1315241D01*
X1241436Y1315533D01*
X1241394Y1315866D01*
X1241477Y1316283D01*
X1241686Y1316575D01*
X1241936Y1316658D01*
X1242186Y1316616D01*
X1242394Y1316450D01*
X1242811Y1315616D01*
X1243102Y1315241D01*
X1243519Y1314991D01*
X1243894Y1314908D01*
Y1316658D01*
G01X1241394Y1318883D02*
X1241477Y1318550D01*
X1241686Y1318300D01*
X1241936Y1318133D01*
X1242269Y1318008D01*
X1242644Y1317966D01*
X1243019Y1318008D01*
X1243352Y1318133D01*
X1243602Y1318300D01*
X1243811Y1318550D01*
X1243894Y1318883D01*
X1243811Y1319216D01*
X1243602Y1319466D01*
X1243352Y1319633D01*
X1243019Y1319758D01*
X1242644Y1319800D01*
X1242269Y1319758D01*
X1241936Y1319633D01*
X1241686Y1319466D01*
X1241477Y1319216D01*
X1241394Y1318883D01*
G01X1216750Y1319233D02*
X1219250Y1316733D01*
X1216750Y1314233D01*
Y1319233D01*
G01Y1331083D02*
X1238800D01*
Y1302483D01*
X1216750D01*
Y1331083D01*
G01X1207500Y1323483D02*
X1209292D01*
X1209667Y1323650D01*
X1209917Y1323983D01*
X1210000Y1324400D01*
X1209917Y1324817D01*
X1209667Y1325150D01*
X1209292Y1325317D01*
X1207500D01*
G01X1210000Y1327500D02*
X1207500D01*
X1208000Y1327000D01*
G01X1210000D02*
Y1328000D01*
G01X1207917Y1329808D02*
X1207667Y1330058D01*
X1207542Y1330350D01*
X1207500Y1330683D01*
X1207583Y1331100D01*
X1207792Y1331392D01*
X1208042Y1331475D01*
X1208292Y1331433D01*
X1208500Y1331267D01*
X1208917Y1330433D01*
X1209208Y1330058D01*
X1209625Y1329808D01*
X1210000Y1329725D01*
Y1331475D01*
G01X1183544Y1319233D02*
X1186044Y1316733D01*
X1183544Y1314233D01*
Y1319233D01*
G01Y1331083D02*
X1205594D01*
Y1302483D01*
X1183544D01*
Y1331083D01*
G01X1206208Y1429967D02*
X1206083Y1429717D01*
X1206000Y1429425D01*
Y1429092D01*
X1206125Y1428717D01*
X1206333Y1428425D01*
X1206583Y1428217D01*
X1207000Y1428050D01*
X1207375Y1428008D01*
X1207750Y1428092D01*
X1208000Y1428217D01*
X1208250Y1428467D01*
X1208417Y1428758D01*
X1208500Y1429050D01*
Y1429342D01*
X1208417Y1429633D01*
X1208292Y1429883D01*
X1208125Y1430092D01*
G01X1208500Y1432067D02*
X1207958Y1432150D01*
X1207500Y1432275D01*
X1207083Y1432442D01*
X1206625Y1432650D01*
X1206000Y1432983D01*
Y1431317D01*
G01Y1435250D02*
X1206083Y1434917D01*
X1206292Y1434667D01*
X1206542Y1434500D01*
X1206875Y1434375D01*
X1207250Y1434333D01*
X1207625Y1434375D01*
X1207958Y1434500D01*
X1208208Y1434667D01*
X1208417Y1434917D01*
X1208500Y1435250D01*
X1208417Y1435583D01*
X1208208Y1435833D01*
X1207958Y1436000D01*
X1207625Y1436125D01*
X1207250Y1436167D01*
X1206875Y1436125D01*
X1206542Y1436000D01*
X1206292Y1435833D01*
X1206083Y1435583D01*
X1206000Y1435250D01*
G01X1208500Y1438350D02*
X1208458Y1438642D01*
X1208333Y1438975D01*
X1208125Y1439183D01*
X1207833Y1439267D01*
X1207542Y1439183D01*
X1207292Y1438933D01*
X1207167Y1438558D01*
Y1438142D01*
X1207083Y1437892D01*
X1206875Y1437683D01*
X1206583Y1437600D01*
X1206292Y1437725D01*
X1206083Y1438017D01*
X1206000Y1438350D01*
X1206083Y1438683D01*
X1206292Y1438975D01*
X1206583Y1439100D01*
X1206875Y1439017D01*
X1207083Y1438808D01*
X1207167Y1438558D01*
Y1438142D01*
X1207292Y1437767D01*
X1207542Y1437517D01*
X1207833Y1437433D01*
X1208125Y1437517D01*
X1208333Y1437725D01*
X1208458Y1438058D01*
X1208500Y1438350D01*
G01X1195008Y1406567D02*
X1194883Y1406317D01*
X1194800Y1406025D01*
Y1405692D01*
X1194925Y1405317D01*
X1195133Y1405025D01*
X1195383Y1404817D01*
X1195800Y1404650D01*
X1196175Y1404608D01*
X1196550Y1404692D01*
X1196800Y1404817D01*
X1197050Y1405067D01*
X1197217Y1405358D01*
X1197300Y1405650D01*
Y1405942D01*
X1197217Y1406233D01*
X1197092Y1406483D01*
X1196925Y1406692D01*
G01X1196258Y1407958D02*
X1195967Y1408250D01*
X1195800Y1408500D01*
X1195717Y1408833D01*
X1195800Y1409125D01*
X1195967Y1409333D01*
X1196217Y1409500D01*
X1196508Y1409542D01*
X1196758Y1409500D01*
X1197008Y1409333D01*
X1197217Y1409083D01*
X1197300Y1408792D01*
X1197217Y1408458D01*
X1196967Y1408167D01*
X1196592Y1408000D01*
X1196175Y1407958D01*
X1195633Y1408042D01*
X1195342Y1408167D01*
X1195050Y1408375D01*
X1194842Y1408667D01*
X1194800Y1408958D01*
X1194883Y1409250D01*
X1195092Y1409458D01*
G01X1196800Y1410933D02*
X1197092Y1411183D01*
X1197258Y1411517D01*
X1197300Y1411892D01*
X1197258Y1412225D01*
X1197050Y1412558D01*
X1196800Y1412767D01*
X1196550Y1412808D01*
X1196258Y1412725D01*
X1196050Y1412433D01*
X1195967Y1412142D01*
Y1411767D01*
G01Y1412142D02*
X1195842Y1412392D01*
X1195633Y1412600D01*
X1195383Y1412683D01*
X1195133Y1412600D01*
X1194925Y1412392D01*
X1194800Y1412017D01*
X1194842Y1411642D01*
X1195008Y1411267D01*
G01X1197300Y1414950D02*
X1194800D01*
X1195300Y1414450D01*
G01X1197300D02*
Y1415450D01*
G01X1204815Y1348678D02*
X1202315D01*
Y1349719D01*
X1202440Y1350053D01*
X1202607Y1350261D01*
X1202940Y1350344D01*
X1203273Y1350261D01*
X1203482Y1350011D01*
X1203607Y1349719D01*
Y1348678D01*
G01Y1349719D02*
X1204815Y1350344D01*
G01Y1352611D02*
X1202315D01*
X1202815Y1352111D01*
G01X1204815D02*
Y1353111D01*
G01X1202315Y1355711D02*
X1202398Y1355378D01*
X1202607Y1355128D01*
X1202857Y1354961D01*
X1203190Y1354836D01*
X1203565Y1354794D01*
X1203940Y1354836D01*
X1204273Y1354961D01*
X1204523Y1355128D01*
X1204732Y1355378D01*
X1204815Y1355711D01*
X1204732Y1356044D01*
X1204523Y1356294D01*
X1204273Y1356461D01*
X1203940Y1356586D01*
X1203565Y1356628D01*
X1203190Y1356586D01*
X1202857Y1356461D01*
X1202607Y1356294D01*
X1202398Y1356044D01*
X1202315Y1355711D01*
G01X1204815Y1358811D02*
X1202315D01*
X1202815Y1358311D01*
G01X1204815D02*
Y1359311D01*
G01X1201394Y1338083D02*
X1205394D01*
Y1345483D01*
G01X1223500Y1350017D02*
X1221000D01*
Y1351058D01*
X1221125Y1351392D01*
X1221292Y1351600D01*
X1221625Y1351683D01*
X1221958Y1351600D01*
X1222167Y1351350D01*
X1222292Y1351058D01*
Y1350017D01*
G01Y1351058D02*
X1223500Y1351683D01*
G01Y1353950D02*
X1221000D01*
X1221500Y1353450D01*
G01X1223500D02*
Y1354450D01*
G01X1221000Y1357050D02*
X1221083Y1356717D01*
X1221292Y1356467D01*
X1221542Y1356300D01*
X1221875Y1356175D01*
X1222250Y1356133D01*
X1222625Y1356175D01*
X1222958Y1356300D01*
X1223208Y1356467D01*
X1223417Y1356717D01*
X1223500Y1357050D01*
X1223417Y1357383D01*
X1223208Y1357633D01*
X1222958Y1357800D01*
X1222625Y1357925D01*
X1222250Y1357967D01*
X1221875Y1357925D01*
X1221542Y1357800D01*
X1221292Y1357633D01*
X1221083Y1357383D01*
X1221000Y1357050D01*
G01X1223500Y1360650D02*
X1221000D01*
X1222792Y1359108D01*
Y1361192D01*
G01X1220100Y1338083D02*
X1224100D01*
Y1345483D01*
G01X1238000Y1350017D02*
X1235500D01*
Y1351058D01*
X1235625Y1351392D01*
X1235792Y1351600D01*
X1236125Y1351683D01*
X1236458Y1351600D01*
X1236667Y1351350D01*
X1236792Y1351058D01*
Y1350017D01*
G01Y1351058D02*
X1238000Y1351683D01*
G01Y1353950D02*
X1235500D01*
X1236000Y1353450D01*
G01X1238000D02*
Y1354450D01*
G01X1235500Y1357050D02*
X1235583Y1356717D01*
X1235792Y1356467D01*
X1236042Y1356300D01*
X1236375Y1356175D01*
X1236750Y1356133D01*
X1237125Y1356175D01*
X1237458Y1356300D01*
X1237708Y1356467D01*
X1237917Y1356717D01*
X1238000Y1357050D01*
X1237917Y1357383D01*
X1237708Y1357633D01*
X1237458Y1357800D01*
X1237125Y1357925D01*
X1236750Y1357967D01*
X1236375Y1357925D01*
X1236042Y1357800D01*
X1235792Y1357633D01*
X1235583Y1357383D01*
X1235500Y1357050D01*
G01X1237625Y1359233D02*
X1237833Y1359483D01*
X1237958Y1359775D01*
X1238000Y1360150D01*
X1237917Y1360525D01*
X1237750Y1360817D01*
X1237458Y1361025D01*
X1237125Y1361067D01*
X1236792Y1360983D01*
X1236583Y1360775D01*
X1236417Y1360483D01*
X1236375Y1360192D01*
X1236417Y1359900D01*
X1236583Y1359525D01*
X1235500Y1359650D01*
Y1360775D01*
G01X1234600Y1338083D02*
X1238600D01*
Y1345483D01*
G01X1243000Y1350017D02*
X1240500D01*
Y1351058D01*
X1240625Y1351392D01*
X1240792Y1351600D01*
X1241125Y1351683D01*
X1241458Y1351600D01*
X1241667Y1351350D01*
X1241792Y1351058D01*
Y1350017D01*
G01Y1351058D02*
X1243000Y1351683D01*
G01Y1353950D02*
X1240500D01*
X1241000Y1353450D01*
G01X1243000D02*
Y1354450D01*
G01X1240917Y1356258D02*
X1240667Y1356508D01*
X1240542Y1356800D01*
X1240500Y1357133D01*
X1240583Y1357550D01*
X1240792Y1357842D01*
X1241042Y1357925D01*
X1241292Y1357883D01*
X1241500Y1357717D01*
X1241917Y1356883D01*
X1242208Y1356508D01*
X1242625Y1356258D01*
X1243000Y1356175D01*
Y1357925D01*
G01X1240500Y1360150D02*
X1240583Y1359817D01*
X1240792Y1359567D01*
X1241042Y1359400D01*
X1241375Y1359275D01*
X1241750Y1359233D01*
X1242125Y1359275D01*
X1242458Y1359400D01*
X1242708Y1359567D01*
X1242917Y1359817D01*
X1243000Y1360150D01*
X1242917Y1360483D01*
X1242708Y1360733D01*
X1242458Y1360900D01*
X1242125Y1361025D01*
X1241750Y1361067D01*
X1241375Y1361025D01*
X1241042Y1360900D01*
X1240792Y1360733D01*
X1240583Y1360483D01*
X1240500Y1360150D01*
G01X1243600Y1345483D02*
X1239600D01*
Y1338083D01*
G01X1233000Y1350017D02*
X1230500D01*
Y1351058D01*
X1230625Y1351392D01*
X1230792Y1351600D01*
X1231125Y1351683D01*
X1231458Y1351600D01*
X1231667Y1351350D01*
X1231792Y1351058D01*
Y1350017D01*
G01Y1351058D02*
X1233000Y1351683D01*
G01Y1353950D02*
X1230500D01*
X1231000Y1353450D01*
G01X1233000D02*
Y1354450D01*
G01X1232625Y1356133D02*
X1232833Y1356383D01*
X1232958Y1356675D01*
X1233000Y1357050D01*
X1232917Y1357425D01*
X1232750Y1357717D01*
X1232458Y1357925D01*
X1232125Y1357967D01*
X1231792Y1357883D01*
X1231583Y1357675D01*
X1231417Y1357383D01*
X1231375Y1357092D01*
X1231417Y1356800D01*
X1231583Y1356425D01*
X1230500Y1356550D01*
Y1357675D01*
G01X1232708Y1359442D02*
X1232917Y1359733D01*
X1233000Y1360067D01*
X1232917Y1360400D01*
X1232667Y1360692D01*
X1232292Y1360900D01*
X1231917Y1360983D01*
X1231458D01*
X1231083Y1360900D01*
X1230750Y1360692D01*
X1230583Y1360442D01*
X1230500Y1360150D01*
X1230583Y1359817D01*
X1230750Y1359567D01*
X1231000Y1359400D01*
X1231333Y1359317D01*
X1231625Y1359400D01*
X1231917Y1359608D01*
X1232083Y1359858D01*
X1232125Y1360150D01*
X1232042Y1360483D01*
X1231833Y1360733D01*
X1231458Y1360983D01*
G01X1230100Y1338083D02*
X1234100D01*
Y1345483D01*
G01X1228500Y1350017D02*
X1226000D01*
Y1351058D01*
X1226125Y1351392D01*
X1226292Y1351600D01*
X1226625Y1351683D01*
X1226958Y1351600D01*
X1227167Y1351350D01*
X1227292Y1351058D01*
Y1350017D01*
G01Y1351058D02*
X1228500Y1351683D01*
G01Y1353950D02*
X1226000D01*
X1226500Y1353450D01*
G01X1228500D02*
Y1354450D01*
G01X1227458Y1356258D02*
X1227167Y1356550D01*
X1227000Y1356800D01*
X1226917Y1357133D01*
X1227000Y1357425D01*
X1227167Y1357633D01*
X1227417Y1357800D01*
X1227708Y1357842D01*
X1227958Y1357800D01*
X1228208Y1357633D01*
X1228417Y1357383D01*
X1228500Y1357092D01*
X1228417Y1356758D01*
X1228167Y1356467D01*
X1227792Y1356300D01*
X1227375Y1356258D01*
X1226833Y1356342D01*
X1226542Y1356467D01*
X1226250Y1356675D01*
X1226042Y1356967D01*
X1226000Y1357258D01*
X1226083Y1357550D01*
X1226292Y1357758D01*
G01X1226000Y1360150D02*
X1226083Y1359817D01*
X1226292Y1359567D01*
X1226542Y1359400D01*
X1226875Y1359275D01*
X1227250Y1359233D01*
X1227625Y1359275D01*
X1227958Y1359400D01*
X1228208Y1359567D01*
X1228417Y1359817D01*
X1228500Y1360150D01*
X1228417Y1360483D01*
X1228208Y1360733D01*
X1227958Y1360900D01*
X1227625Y1361025D01*
X1227250Y1361067D01*
X1226875Y1361025D01*
X1226542Y1360900D01*
X1226292Y1360733D01*
X1226083Y1360483D01*
X1226000Y1360150D01*
G01X1229100Y1345483D02*
X1225100D01*
Y1338083D01*
G01X1218500Y1350017D02*
X1216000D01*
Y1351058D01*
X1216125Y1351392D01*
X1216292Y1351600D01*
X1216625Y1351683D01*
X1216958Y1351600D01*
X1217167Y1351350D01*
X1217292Y1351058D01*
Y1350017D01*
G01Y1351058D02*
X1218500Y1351683D01*
G01Y1353950D02*
X1216000D01*
X1216500Y1353450D01*
G01X1218500D02*
Y1354450D01*
G01X1217458Y1356258D02*
X1217167Y1356550D01*
X1217000Y1356800D01*
X1216917Y1357133D01*
X1217000Y1357425D01*
X1217167Y1357633D01*
X1217417Y1357800D01*
X1217708Y1357842D01*
X1217958Y1357800D01*
X1218208Y1357633D01*
X1218417Y1357383D01*
X1218500Y1357092D01*
X1218417Y1356758D01*
X1218167Y1356467D01*
X1217792Y1356300D01*
X1217375Y1356258D01*
X1216833Y1356342D01*
X1216542Y1356467D01*
X1216250Y1356675D01*
X1216042Y1356967D01*
X1216000Y1357258D01*
X1216083Y1357550D01*
X1216292Y1357758D01*
G01X1218500Y1360150D02*
X1216000D01*
X1216500Y1359650D01*
G01X1218500D02*
Y1360650D01*
G01X1215100Y1338083D02*
X1219100D01*
Y1345483D01*
G01X1209815Y1348678D02*
X1207315D01*
Y1349719D01*
X1207440Y1350053D01*
X1207607Y1350261D01*
X1207940Y1350344D01*
X1208273Y1350261D01*
X1208482Y1350011D01*
X1208607Y1349719D01*
Y1348678D01*
G01Y1349719D02*
X1209815Y1350344D01*
G01Y1352611D02*
X1207315D01*
X1207815Y1352111D01*
G01X1209815D02*
Y1353111D01*
G01X1207315Y1355711D02*
X1207398Y1355378D01*
X1207607Y1355128D01*
X1207857Y1354961D01*
X1208190Y1354836D01*
X1208565Y1354794D01*
X1208940Y1354836D01*
X1209273Y1354961D01*
X1209523Y1355128D01*
X1209732Y1355378D01*
X1209815Y1355711D01*
X1209732Y1356044D01*
X1209523Y1356294D01*
X1209273Y1356461D01*
X1208940Y1356586D01*
X1208565Y1356628D01*
X1208190Y1356586D01*
X1207857Y1356461D01*
X1207607Y1356294D01*
X1207398Y1356044D01*
X1207315Y1355711D01*
G01Y1358811D02*
X1207398Y1358478D01*
X1207607Y1358228D01*
X1207857Y1358061D01*
X1208190Y1357936D01*
X1208565Y1357894D01*
X1208940Y1357936D01*
X1209273Y1358061D01*
X1209523Y1358228D01*
X1209732Y1358478D01*
X1209815Y1358811D01*
X1209732Y1359144D01*
X1209523Y1359394D01*
X1209273Y1359561D01*
X1208940Y1359686D01*
X1208565Y1359728D01*
X1208190Y1359686D01*
X1207857Y1359561D01*
X1207607Y1359394D01*
X1207398Y1359144D01*
X1207315Y1358811D01*
G01X1210394Y1345483D02*
X1206394D01*
Y1338083D01*
G01X1185315Y1349178D02*
X1182815D01*
Y1350219D01*
X1182940Y1350553D01*
X1183107Y1350761D01*
X1183440Y1350844D01*
X1183773Y1350761D01*
X1183982Y1350511D01*
X1184107Y1350219D01*
Y1349178D01*
G01Y1350219D02*
X1185315Y1350844D01*
G01Y1353111D02*
X1182815D01*
X1183315Y1352611D01*
G01X1185315D02*
Y1353611D01*
G01X1182815Y1356211D02*
X1182898Y1355878D01*
X1183107Y1355628D01*
X1183357Y1355461D01*
X1183690Y1355336D01*
X1184065Y1355294D01*
X1184440Y1355336D01*
X1184773Y1355461D01*
X1185023Y1355628D01*
X1185232Y1355878D01*
X1185315Y1356211D01*
X1185232Y1356544D01*
X1185023Y1356794D01*
X1184773Y1356961D01*
X1184440Y1357086D01*
X1184065Y1357128D01*
X1183690Y1357086D01*
X1183357Y1356961D01*
X1183107Y1356794D01*
X1182898Y1356544D01*
X1182815Y1356211D01*
G01X1183232Y1358519D02*
X1182982Y1358769D01*
X1182857Y1359061D01*
X1182815Y1359394D01*
X1182898Y1359811D01*
X1183107Y1360103D01*
X1183357Y1360186D01*
X1183607Y1360144D01*
X1183815Y1359978D01*
X1184232Y1359144D01*
X1184523Y1358769D01*
X1184940Y1358519D01*
X1185315Y1358436D01*
Y1360186D01*
G01X1181894Y1338083D02*
X1185894D01*
Y1345483D01*
G01X1194815Y1348728D02*
X1192315D01*
Y1349769D01*
X1192440Y1350103D01*
X1192607Y1350311D01*
X1192940Y1350394D01*
X1193273Y1350311D01*
X1193482Y1350061D01*
X1193607Y1349769D01*
Y1348728D01*
G01Y1349769D02*
X1194815Y1350394D01*
G01X1194523Y1351953D02*
X1194732Y1352244D01*
X1194815Y1352578D01*
X1194732Y1352911D01*
X1194482Y1353203D01*
X1194107Y1353411D01*
X1193732Y1353494D01*
X1193273D01*
X1192898Y1353411D01*
X1192565Y1353203D01*
X1192398Y1352953D01*
X1192315Y1352661D01*
X1192398Y1352328D01*
X1192565Y1352078D01*
X1192815Y1351911D01*
X1193148Y1351828D01*
X1193440Y1351911D01*
X1193732Y1352119D01*
X1193898Y1352369D01*
X1193940Y1352661D01*
X1193857Y1352994D01*
X1193648Y1353244D01*
X1193273Y1353494D01*
G01X1194815Y1356261D02*
X1192315D01*
X1194107Y1354719D01*
Y1356803D01*
G01X1195894Y1345483D02*
X1191894D01*
Y1338083D01*
G01X1190315Y1348728D02*
X1187815D01*
Y1349769D01*
X1187940Y1350103D01*
X1188107Y1350311D01*
X1188440Y1350394D01*
X1188773Y1350311D01*
X1188982Y1350061D01*
X1189107Y1349769D01*
Y1348728D01*
G01Y1349769D02*
X1190315Y1350394D01*
G01X1190023Y1351953D02*
X1190232Y1352244D01*
X1190315Y1352578D01*
X1190232Y1352911D01*
X1189982Y1353203D01*
X1189607Y1353411D01*
X1189232Y1353494D01*
X1188773D01*
X1188398Y1353411D01*
X1188065Y1353203D01*
X1187898Y1352953D01*
X1187815Y1352661D01*
X1187898Y1352328D01*
X1188065Y1352078D01*
X1188315Y1351911D01*
X1188648Y1351828D01*
X1188940Y1351911D01*
X1189232Y1352119D01*
X1189398Y1352369D01*
X1189440Y1352661D01*
X1189357Y1352994D01*
X1189148Y1353244D01*
X1188773Y1353494D01*
G01X1189940Y1354844D02*
X1190148Y1355094D01*
X1190273Y1355386D01*
X1190315Y1355761D01*
X1190232Y1356136D01*
X1190065Y1356428D01*
X1189773Y1356636D01*
X1189440Y1356678D01*
X1189107Y1356594D01*
X1188898Y1356386D01*
X1188732Y1356094D01*
X1188690Y1355803D01*
X1188732Y1355511D01*
X1188898Y1355136D01*
X1187815Y1355261D01*
Y1356386D01*
G01X1186894Y1338083D02*
X1190894D01*
Y1345483D01*
G01X1200315Y1348728D02*
X1197815D01*
Y1349769D01*
X1197940Y1350103D01*
X1198107Y1350311D01*
X1198440Y1350394D01*
X1198773Y1350311D01*
X1198982Y1350061D01*
X1199107Y1349769D01*
Y1348728D01*
G01Y1349769D02*
X1200315Y1350394D01*
G01X1200023Y1351953D02*
X1200232Y1352244D01*
X1200315Y1352578D01*
X1200232Y1352911D01*
X1199982Y1353203D01*
X1199607Y1353411D01*
X1199232Y1353494D01*
X1198773D01*
X1198398Y1353411D01*
X1198065Y1353203D01*
X1197898Y1352953D01*
X1197815Y1352661D01*
X1197898Y1352328D01*
X1198065Y1352078D01*
X1198315Y1351911D01*
X1198648Y1351828D01*
X1198940Y1351911D01*
X1199232Y1352119D01*
X1199398Y1352369D01*
X1199440Y1352661D01*
X1199357Y1352994D01*
X1199148Y1353244D01*
X1198773Y1353494D01*
G01X1200023Y1355053D02*
X1200232Y1355344D01*
X1200315Y1355678D01*
X1200232Y1356011D01*
X1199982Y1356303D01*
X1199607Y1356511D01*
X1199232Y1356594D01*
X1198773D01*
X1198398Y1356511D01*
X1198065Y1356303D01*
X1197898Y1356053D01*
X1197815Y1355761D01*
X1197898Y1355428D01*
X1198065Y1355178D01*
X1198315Y1355011D01*
X1198648Y1354928D01*
X1198940Y1355011D01*
X1199232Y1355219D01*
X1199398Y1355469D01*
X1199440Y1355761D01*
X1199357Y1356094D01*
X1199148Y1356344D01*
X1198773Y1356594D01*
G01X1196894Y1338083D02*
X1200894D01*
Y1345483D01*
G01X1204400Y1428317D02*
X1201900D01*
Y1429358D01*
X1202025Y1429692D01*
X1202192Y1429900D01*
X1202525Y1429983D01*
X1202858Y1429900D01*
X1203067Y1429650D01*
X1203192Y1429358D01*
Y1428317D01*
G01Y1429358D02*
X1204400Y1429983D01*
G01X1204025Y1431333D02*
X1204233Y1431583D01*
X1204358Y1431875D01*
X1204400Y1432250D01*
X1204317Y1432625D01*
X1204150Y1432917D01*
X1203858Y1433125D01*
X1203525Y1433167D01*
X1203192Y1433083D01*
X1202983Y1432875D01*
X1202817Y1432583D01*
X1202775Y1432292D01*
X1202817Y1432000D01*
X1202983Y1431625D01*
X1201900Y1431750D01*
Y1432875D01*
G01Y1435350D02*
X1201983Y1435017D01*
X1202192Y1434767D01*
X1202442Y1434600D01*
X1202775Y1434475D01*
X1203150Y1434433D01*
X1203525Y1434475D01*
X1203858Y1434600D01*
X1204108Y1434767D01*
X1204317Y1435017D01*
X1204400Y1435350D01*
X1204317Y1435683D01*
X1204108Y1435933D01*
X1203858Y1436100D01*
X1203525Y1436225D01*
X1203150Y1436267D01*
X1202775Y1436225D01*
X1202442Y1436100D01*
X1202192Y1435933D01*
X1201983Y1435683D01*
X1201900Y1435350D01*
G01X1204400Y1438950D02*
X1201900D01*
X1203692Y1437408D01*
Y1439492D01*
G01X1201487Y1419241D02*
X1205487D01*
Y1426641D01*
G01X1215528Y1400082D02*
Y1402582D01*
X1216569D01*
X1216903Y1402457D01*
X1217111Y1402290D01*
X1217194Y1401957D01*
X1217111Y1401624D01*
X1216861Y1401415D01*
X1216569Y1401290D01*
X1215528D01*
G01X1216569D02*
X1217194Y1400082D01*
G01X1218544Y1400457D02*
X1218794Y1400249D01*
X1219086Y1400124D01*
X1219461Y1400082D01*
X1219836Y1400165D01*
X1220128Y1400332D01*
X1220336Y1400624D01*
X1220378Y1400957D01*
X1220294Y1401290D01*
X1220086Y1401499D01*
X1219794Y1401665D01*
X1219503Y1401707D01*
X1219211Y1401665D01*
X1218836Y1401499D01*
X1218961Y1402582D01*
X1220086D01*
G01X1222561D02*
X1222228Y1402499D01*
X1221978Y1402290D01*
X1221811Y1402040D01*
X1221686Y1401707D01*
X1221644Y1401332D01*
X1221686Y1400957D01*
X1221811Y1400624D01*
X1221978Y1400374D01*
X1222228Y1400165D01*
X1222561Y1400082D01*
X1222894Y1400165D01*
X1223144Y1400374D01*
X1223311Y1400624D01*
X1223436Y1400957D01*
X1223478Y1401332D01*
X1223436Y1401707D01*
X1223311Y1402040D01*
X1223144Y1402290D01*
X1222894Y1402499D01*
X1222561Y1402582D01*
G01X1224744Y1400582D02*
X1224994Y1400290D01*
X1225328Y1400124D01*
X1225703Y1400082D01*
X1226036Y1400124D01*
X1226369Y1400332D01*
X1226578Y1400582D01*
X1226619Y1400832D01*
X1226536Y1401124D01*
X1226244Y1401332D01*
X1225953Y1401415D01*
X1225578D01*
G01X1225953D02*
X1226203Y1401540D01*
X1226411Y1401749D01*
X1226494Y1401999D01*
X1226411Y1402249D01*
X1226203Y1402457D01*
X1225828Y1402582D01*
X1225453Y1402540D01*
X1225078Y1402374D01*
G01X1205312Y1403814D02*
Y1399814D01*
X1212712D01*
G01X1221200Y1406850D02*
X1221158Y1406517D01*
X1220992Y1406225D01*
X1220742Y1405975D01*
X1220450Y1405808D01*
X1220117Y1405725D01*
X1219783D01*
X1219450Y1405808D01*
X1219158Y1405975D01*
X1218908Y1406225D01*
X1218742Y1406517D01*
X1218700Y1406850D01*
X1218742Y1407183D01*
X1218908Y1407475D01*
X1219158Y1407725D01*
X1219450Y1407892D01*
X1219783Y1407975D01*
X1220117D01*
X1220450Y1407892D01*
X1220742Y1407725D01*
X1220992Y1407475D01*
X1221158Y1407183D01*
X1221200Y1406850D01*
G01X1220533Y1407183D02*
X1221200Y1407683D01*
G01X1219117Y1409158D02*
X1218867Y1409408D01*
X1218742Y1409700D01*
X1218700Y1410033D01*
X1218783Y1410450D01*
X1218992Y1410742D01*
X1219242Y1410825D01*
X1219492Y1410783D01*
X1219700Y1410617D01*
X1220117Y1409783D01*
X1220408Y1409408D01*
X1220825Y1409158D01*
X1221200Y1409075D01*
Y1410825D01*
G01X1220158Y1412258D02*
X1219867Y1412550D01*
X1219700Y1412800D01*
X1219617Y1413133D01*
X1219700Y1413425D01*
X1219867Y1413633D01*
X1220117Y1413800D01*
X1220408Y1413842D01*
X1220658Y1413800D01*
X1220908Y1413633D01*
X1221117Y1413383D01*
X1221200Y1413092D01*
X1221117Y1412758D01*
X1220867Y1412467D01*
X1220492Y1412300D01*
X1220075Y1412258D01*
X1219533Y1412342D01*
X1219242Y1412467D01*
X1218950Y1412675D01*
X1218742Y1412967D01*
X1218700Y1413258D01*
X1218783Y1413550D01*
X1218992Y1413758D01*
G01X1221200Y1416067D02*
X1220658Y1416150D01*
X1220200Y1416275D01*
X1219783Y1416442D01*
X1219325Y1416650D01*
X1218700Y1416983D01*
Y1415317D01*
G01X1216346Y1404303D02*
Y1418303D01*
G01X1203346Y1404303D02*
X1216346D01*
G01X1203346Y1418303D02*
Y1404303D01*
G01X1216346Y1418303D02*
X1203346D01*
G01X1186782Y1372014D02*
Y1370222D01*
X1186949Y1369847D01*
X1187282Y1369597D01*
X1187699Y1369514D01*
X1188116Y1369597D01*
X1188449Y1369847D01*
X1188616Y1370222D01*
Y1372014D01*
G01X1190799Y1369514D02*
Y1372014D01*
X1190299Y1371514D01*
G01Y1369514D02*
X1191299D01*
G01X1193816D02*
X1193899Y1370056D01*
X1194024Y1370514D01*
X1194191Y1370931D01*
X1194399Y1371389D01*
X1194732Y1372014D01*
X1193066D01*
G01X1230191Y1453817D02*
Y1456317D01*
X1231232D01*
X1231566Y1456192D01*
X1231774Y1456025D01*
X1231857Y1455692D01*
X1231774Y1455359D01*
X1231524Y1455150D01*
X1231232Y1455025D01*
X1230191D01*
G01X1231232D02*
X1231857Y1453817D01*
G01X1233416Y1454109D02*
X1233707Y1453900D01*
X1234041Y1453817D01*
X1234374Y1453900D01*
X1234666Y1454150D01*
X1234874Y1454525D01*
X1234957Y1454900D01*
Y1455359D01*
X1234874Y1455734D01*
X1234666Y1456067D01*
X1234416Y1456234D01*
X1234124Y1456317D01*
X1233791Y1456234D01*
X1233541Y1456067D01*
X1233374Y1455817D01*
X1233291Y1455484D01*
X1233374Y1455192D01*
X1233582Y1454900D01*
X1233832Y1454734D01*
X1234124Y1454692D01*
X1234457Y1454775D01*
X1234707Y1454984D01*
X1234957Y1455359D01*
G01X1237141Y1453817D02*
X1237224Y1454359D01*
X1237349Y1454817D01*
X1237516Y1455234D01*
X1237724Y1455692D01*
X1238057Y1456317D01*
X1236391D01*
G01X1239532Y1455900D02*
X1239782Y1456150D01*
X1240074Y1456275D01*
X1240407Y1456317D01*
X1240824Y1456234D01*
X1241116Y1456025D01*
X1241199Y1455775D01*
X1241157Y1455525D01*
X1240991Y1455317D01*
X1240157Y1454900D01*
X1239782Y1454609D01*
X1239532Y1454192D01*
X1239449Y1453817D01*
X1241199D01*
G01X1245374Y1462000D02*
X1240174D01*
G01X1245374Y1469000D02*
X1237574D01*
G01X1231974Y1462000D02*
X1240674D01*
G01X1231974Y1469000D02*
Y1462000D01*
G01X1238374Y1469000D02*
X1231974D01*
G01X1230191Y1457850D02*
Y1460350D01*
X1231232D01*
X1231566Y1460225D01*
X1231774Y1460058D01*
X1231857Y1459725D01*
X1231774Y1459392D01*
X1231524Y1459183D01*
X1231232Y1459058D01*
X1230191D01*
G01X1231232D02*
X1231857Y1457850D01*
G01X1233416Y1458142D02*
X1233707Y1457933D01*
X1234041Y1457850D01*
X1234374Y1457933D01*
X1234666Y1458183D01*
X1234874Y1458558D01*
X1234957Y1458933D01*
Y1459392D01*
X1234874Y1459767D01*
X1234666Y1460100D01*
X1234416Y1460267D01*
X1234124Y1460350D01*
X1233791Y1460267D01*
X1233541Y1460100D01*
X1233374Y1459850D01*
X1233291Y1459517D01*
X1233374Y1459225D01*
X1233582Y1458933D01*
X1233832Y1458767D01*
X1234124Y1458725D01*
X1234457Y1458808D01*
X1234707Y1459017D01*
X1234957Y1459392D01*
G01X1237141Y1457850D02*
X1237224Y1458392D01*
X1237349Y1458850D01*
X1237516Y1459267D01*
X1237724Y1459725D01*
X1238057Y1460350D01*
X1236391D01*
G01X1239407Y1458225D02*
X1239657Y1458017D01*
X1239949Y1457892D01*
X1240324Y1457850D01*
X1240699Y1457933D01*
X1240991Y1458100D01*
X1241199Y1458392D01*
X1241241Y1458725D01*
X1241157Y1459058D01*
X1240949Y1459267D01*
X1240657Y1459433D01*
X1240366Y1459475D01*
X1240074Y1459433D01*
X1239699Y1459267D01*
X1239824Y1460350D01*
X1240949D01*
G01X1231974Y1476700D02*
X1237174D01*
G01X1231974Y1469700D02*
X1239774D01*
G01X1231974Y1476700D02*
Y1469700D01*
G01X1245374Y1476700D02*
X1236674D01*
G01X1238974Y1469700D02*
X1245374D01*
G01X1214782Y1474300D02*
Y1476800D01*
X1216366D01*
G01X1215782Y1475592D02*
X1214782D01*
G01X1217841Y1476800D02*
Y1474300D01*
X1219507D01*
G01X1222607D02*
X1220941D01*
Y1476800D01*
X1222607D01*
G01X1221941Y1475592D02*
X1220941D01*
G01X1223957Y1474300D02*
Y1476800D01*
X1224791D01*
X1225124Y1476675D01*
X1225374Y1476508D01*
X1225582Y1476258D01*
X1225749Y1475967D01*
X1225791Y1475550D01*
X1225749Y1475133D01*
X1225582Y1474842D01*
X1225374Y1474592D01*
X1225124Y1474425D01*
X1224791Y1474300D01*
X1223957D01*
G01X1227057Y1474800D02*
X1227307Y1474508D01*
X1227641Y1474342D01*
X1228016Y1474300D01*
X1228349Y1474342D01*
X1228682Y1474550D01*
X1228891Y1474800D01*
X1228932Y1475050D01*
X1228849Y1475342D01*
X1228557Y1475550D01*
X1228266Y1475633D01*
X1227891D01*
G01X1228266D02*
X1228516Y1475758D01*
X1228724Y1475967D01*
X1228807Y1476217D01*
X1228724Y1476467D01*
X1228516Y1476675D01*
X1228141Y1476800D01*
X1227766Y1476758D01*
X1227391Y1476592D01*
G01X1242753Y1479118D02*
X1213153D01*
Y1516718D01*
X1242753D01*
Y1479118D01*
G01X1234858Y1494328D02*
X1241558D01*
G01X1229758D02*
X1225658D01*
G01X1234858Y1499428D02*
X1229758Y1494328D01*
G01X1234858Y1489228D02*
Y1499428D01*
G01X1229758Y1494328D02*
X1234858Y1489228D01*
G01X1220558Y1499428D02*
X1225658Y1494328D01*
G01X1220558Y1489228D02*
Y1499428D01*
G01X1225658Y1494328D02*
X1220558Y1489228D01*
G01Y1494328D02*
X1216858D01*
G01X1229758Y1497128D02*
Y1490728D01*
G01X1225658Y1497128D02*
Y1490728D01*
G01X1264793Y107319D02*
X1269843D01*
Y206019D01*
X1294493D01*
Y21619D01*
X1269843D01*
Y80319D01*
X1264793D01*
Y107319D01*
G01X1252645Y63572D02*
X1252395Y63697D01*
X1252103Y63780D01*
X1251770D01*
X1251395Y63655D01*
X1251103Y63447D01*
X1250895Y63197D01*
X1250728Y62780D01*
X1250686Y62405D01*
X1250770Y62030D01*
X1250895Y61780D01*
X1251145Y61530D01*
X1251436Y61363D01*
X1251728Y61280D01*
X1252020D01*
X1252311Y61363D01*
X1252561Y61488D01*
X1252770Y61655D01*
G01X1255328Y61280D02*
Y63780D01*
X1253786Y61988D01*
X1255870D01*
G01X1257928Y61280D02*
Y63780D01*
X1257428Y63280D01*
G01Y61280D02*
X1258428D01*
G01X1260320Y61572D02*
X1260611Y61363D01*
X1260945Y61280D01*
X1261278Y61363D01*
X1261570Y61613D01*
X1261778Y61988D01*
X1261861Y62363D01*
Y62822D01*
X1261778Y63197D01*
X1261570Y63530D01*
X1261320Y63697D01*
X1261028Y63780D01*
X1260695Y63697D01*
X1260445Y63530D01*
X1260278Y63280D01*
X1260195Y62947D01*
X1260278Y62655D01*
X1260486Y62363D01*
X1260736Y62197D01*
X1261028Y62155D01*
X1261361Y62238D01*
X1261611Y62447D01*
X1261861Y62822D01*
G01X1252767Y67792D02*
X1252517Y67917D01*
X1252225Y68000D01*
X1251892D01*
X1251517Y67875D01*
X1251225Y67667D01*
X1251017Y67417D01*
X1250850Y67000D01*
X1250808Y66625D01*
X1250892Y66250D01*
X1251017Y66000D01*
X1251267Y65750D01*
X1251558Y65583D01*
X1251850Y65500D01*
X1252142D01*
X1252433Y65583D01*
X1252683Y65708D01*
X1252892Y65875D01*
G01X1255450Y65500D02*
Y68000D01*
X1253908Y66208D01*
X1255992D01*
G01X1258050Y65500D02*
Y68000D01*
X1257550Y67500D01*
G01Y65500D02*
X1258550D01*
G01X1261150D02*
X1261442Y65542D01*
X1261775Y65667D01*
X1261983Y65875D01*
X1262067Y66167D01*
X1261983Y66458D01*
X1261733Y66708D01*
X1261358Y66833D01*
X1260942D01*
X1260692Y66917D01*
X1260483Y67125D01*
X1260400Y67417D01*
X1260525Y67708D01*
X1260817Y67917D01*
X1261150Y68000D01*
X1261483Y67917D01*
X1261775Y67708D01*
X1261900Y67417D01*
X1261817Y67125D01*
X1261608Y66917D01*
X1261358Y66833D01*
X1260942D01*
X1260567Y66708D01*
X1260317Y66458D01*
X1260233Y66167D01*
X1260317Y65875D01*
X1260525Y65667D01*
X1260858Y65542D01*
X1261150Y65500D01*
G01X1295908Y59867D02*
X1295783Y59617D01*
X1295700Y59325D01*
Y58992D01*
X1295825Y58617D01*
X1296033Y58325D01*
X1296283Y58117D01*
X1296700Y57950D01*
X1297075Y57908D01*
X1297450Y57992D01*
X1297700Y58117D01*
X1297950Y58367D01*
X1298117Y58658D01*
X1298200Y58950D01*
Y59242D01*
X1298117Y59533D01*
X1297992Y59783D01*
X1297825Y59992D01*
G01X1298200Y62550D02*
X1295700D01*
X1297492Y61008D01*
Y63092D01*
G01X1296117Y64358D02*
X1295867Y64608D01*
X1295742Y64900D01*
X1295700Y65233D01*
X1295783Y65650D01*
X1295992Y65942D01*
X1296242Y66025D01*
X1296492Y65983D01*
X1296700Y65817D01*
X1297117Y64983D01*
X1297408Y64608D01*
X1297825Y64358D01*
X1298200Y64275D01*
Y66025D01*
G01Y68250D02*
X1298158Y68542D01*
X1298033Y68875D01*
X1297825Y69083D01*
X1297533Y69167D01*
X1297242Y69083D01*
X1296992Y68833D01*
X1296867Y68458D01*
Y68042D01*
X1296783Y67792D01*
X1296575Y67583D01*
X1296283Y67500D01*
X1295992Y67625D01*
X1295783Y67917D01*
X1295700Y68250D01*
X1295783Y68583D01*
X1295992Y68875D01*
X1296283Y69000D01*
X1296575Y68917D01*
X1296783Y68708D01*
X1296867Y68458D01*
Y68042D01*
X1296992Y67667D01*
X1297242Y67417D01*
X1297533Y67333D01*
X1297825Y67417D01*
X1298033Y67625D01*
X1298158Y67958D01*
X1298200Y68250D01*
G01X1296617Y71600D02*
Y74100D01*
X1297658D01*
X1297992Y73975D01*
X1298200Y73808D01*
X1298283Y73475D01*
X1298200Y73142D01*
X1297950Y72933D01*
X1297658Y72808D01*
X1296617D01*
G01X1297658D02*
X1298283Y71600D01*
G01X1300467D02*
X1300550Y72142D01*
X1300675Y72600D01*
X1300842Y73017D01*
X1301050Y73475D01*
X1301383Y74100D01*
X1299717D01*
G01X1302858Y72642D02*
X1303150Y72933D01*
X1303400Y73100D01*
X1303733Y73183D01*
X1304025Y73100D01*
X1304233Y72933D01*
X1304400Y72683D01*
X1304442Y72392D01*
X1304400Y72142D01*
X1304233Y71892D01*
X1303983Y71683D01*
X1303692Y71600D01*
X1303358Y71683D01*
X1303067Y71933D01*
X1302900Y72308D01*
X1302858Y72725D01*
X1302942Y73267D01*
X1303067Y73558D01*
X1303275Y73850D01*
X1303567Y74058D01*
X1303858Y74100D01*
X1304150Y74017D01*
X1304358Y73808D01*
G01X1306667Y71600D02*
X1306750Y72142D01*
X1306875Y72600D01*
X1307042Y73017D01*
X1307250Y73475D01*
X1307583Y74100D01*
X1305917D01*
G01X1299600Y70900D02*
Y66900D01*
X1307000D01*
G01X1309339Y16517D02*
X1306839D01*
Y17558D01*
X1306964Y17892D01*
X1307131Y18100D01*
X1307464Y18183D01*
X1307797Y18100D01*
X1308006Y17850D01*
X1308131Y17558D01*
Y16517D01*
G01Y17558D02*
X1309339Y18183D01*
G01Y20367D02*
X1308797Y20450D01*
X1308339Y20575D01*
X1307922Y20742D01*
X1307464Y20950D01*
X1306839Y21283D01*
Y19617D01*
G01X1308297Y22758D02*
X1308006Y23050D01*
X1307839Y23300D01*
X1307756Y23633D01*
X1307839Y23925D01*
X1308006Y24133D01*
X1308256Y24300D01*
X1308547Y24342D01*
X1308797Y24300D01*
X1309047Y24133D01*
X1309256Y23883D01*
X1309339Y23592D01*
X1309256Y23258D01*
X1309006Y22967D01*
X1308631Y22800D01*
X1308214Y22758D01*
X1307672Y22842D01*
X1307381Y22967D01*
X1307089Y23175D01*
X1306881Y23467D01*
X1306839Y23758D01*
X1306922Y24050D01*
X1307131Y24258D01*
G01X1309339Y26650D02*
X1309297Y26942D01*
X1309172Y27275D01*
X1308964Y27483D01*
X1308672Y27567D01*
X1308381Y27483D01*
X1308131Y27233D01*
X1308006Y26858D01*
Y26442D01*
X1307922Y26192D01*
X1307714Y25983D01*
X1307422Y25900D01*
X1307131Y26025D01*
X1306922Y26317D01*
X1306839Y26650D01*
X1306922Y26983D01*
X1307131Y27275D01*
X1307422Y27400D01*
X1307714Y27317D01*
X1307922Y27108D01*
X1308006Y26858D01*
Y26442D01*
X1308131Y26067D01*
X1308381Y25817D01*
X1308672Y25733D01*
X1308964Y25817D01*
X1309172Y26025D01*
X1309297Y26358D01*
X1309339Y26650D01*
G01X1306000Y36300D02*
X1310000D01*
Y43700D01*
G01X1317500Y11017D02*
X1315000D01*
Y12058D01*
X1315125Y12392D01*
X1315292Y12600D01*
X1315625Y12683D01*
X1315958Y12600D01*
X1316167Y12350D01*
X1316292Y12058D01*
Y11017D01*
G01Y12058D02*
X1317500Y12683D01*
G01Y14867D02*
X1316958Y14950D01*
X1316500Y15075D01*
X1316083Y15242D01*
X1315625Y15450D01*
X1315000Y15783D01*
Y14117D01*
G01X1317500Y17967D02*
X1316958Y18050D01*
X1316500Y18175D01*
X1316083Y18342D01*
X1315625Y18550D01*
X1315000Y18883D01*
Y17217D01*
G01X1317500Y21150D02*
X1315000D01*
X1315500Y20650D01*
G01X1317500D02*
Y21650D01*
G01X1316000Y36300D02*
X1320000D01*
Y43700D01*
G01X1304839Y16517D02*
X1302339D01*
Y17558D01*
X1302464Y17892D01*
X1302631Y18100D01*
X1302964Y18183D01*
X1303297Y18100D01*
X1303506Y17850D01*
X1303631Y17558D01*
Y16517D01*
G01Y17558D02*
X1304839Y18183D01*
G01Y20367D02*
X1304297Y20450D01*
X1303839Y20575D01*
X1303422Y20742D01*
X1302964Y20950D01*
X1302339Y21283D01*
Y19617D01*
G01X1304839Y23467D02*
X1304297Y23550D01*
X1303839Y23675D01*
X1303422Y23842D01*
X1302964Y24050D01*
X1302339Y24383D01*
Y22717D01*
G01X1304339Y25733D02*
X1304631Y25983D01*
X1304797Y26317D01*
X1304839Y26692D01*
X1304797Y27025D01*
X1304589Y27358D01*
X1304339Y27567D01*
X1304089Y27608D01*
X1303797Y27525D01*
X1303589Y27233D01*
X1303506Y26942D01*
Y26567D01*
G01Y26942D02*
X1303381Y27192D01*
X1303172Y27400D01*
X1302922Y27483D01*
X1302672Y27400D01*
X1302464Y27192D01*
X1302339Y26817D01*
X1302381Y26442D01*
X1302547Y26067D01*
G01X1305500Y43700D02*
X1301500D01*
Y36300D01*
G01X1318400Y23417D02*
X1315900D01*
Y24458D01*
X1316025Y24792D01*
X1316192Y25000D01*
X1316525Y25083D01*
X1316858Y25000D01*
X1317067Y24750D01*
X1317192Y24458D01*
Y23417D01*
G01Y24458D02*
X1318400Y25083D01*
G01Y27267D02*
X1317858Y27350D01*
X1317400Y27475D01*
X1316983Y27642D01*
X1316525Y27850D01*
X1315900Y28183D01*
Y26517D01*
G01X1318400Y30367D02*
X1317858Y30450D01*
X1317400Y30575D01*
X1316983Y30742D01*
X1316525Y30950D01*
X1315900Y31283D01*
Y29617D01*
G01X1318400Y34050D02*
X1315900D01*
X1317692Y32508D01*
Y34592D01*
G01X1315800Y48600D02*
X1319800D01*
Y56000D01*
G01X1321700Y74917D02*
X1319200D01*
Y75958D01*
X1319325Y76292D01*
X1319492Y76500D01*
X1319825Y76583D01*
X1320158Y76500D01*
X1320367Y76250D01*
X1320492Y75958D01*
Y74917D01*
G01Y75958D02*
X1321700Y76583D01*
G01Y78767D02*
X1321158Y78850D01*
X1320700Y78975D01*
X1320283Y79142D01*
X1319825Y79350D01*
X1319200Y79683D01*
Y78017D01*
G01X1321700Y81867D02*
X1321158Y81950D01*
X1320700Y82075D01*
X1320283Y82242D01*
X1319825Y82450D01*
X1319200Y82783D01*
Y81117D01*
G01X1320658Y84258D02*
X1320367Y84550D01*
X1320200Y84800D01*
X1320117Y85133D01*
X1320200Y85425D01*
X1320367Y85633D01*
X1320617Y85800D01*
X1320908Y85842D01*
X1321158Y85800D01*
X1321408Y85633D01*
X1321617Y85383D01*
X1321700Y85092D01*
X1321617Y84758D01*
X1321367Y84467D01*
X1320992Y84300D01*
X1320575Y84258D01*
X1320033Y84342D01*
X1319742Y84467D01*
X1319450Y84675D01*
X1319242Y84967D01*
X1319200Y85258D01*
X1319283Y85550D01*
X1319492Y85758D01*
G01X1309700Y63700D02*
X1313700D01*
Y71100D01*
G01X1314300Y23417D02*
X1311800D01*
Y24458D01*
X1311925Y24792D01*
X1312092Y25000D01*
X1312425Y25083D01*
X1312758Y25000D01*
X1312967Y24750D01*
X1313092Y24458D01*
Y23417D01*
G01Y24458D02*
X1314300Y25083D01*
G01Y27267D02*
X1313758Y27350D01*
X1313300Y27475D01*
X1312883Y27642D01*
X1312425Y27850D01*
X1311800Y28183D01*
Y26517D01*
G01X1314300Y30367D02*
X1313758Y30450D01*
X1313300Y30575D01*
X1312883Y30742D01*
X1312425Y30950D01*
X1311800Y31283D01*
Y29617D01*
G01X1314300Y33467D02*
X1313758Y33550D01*
X1313300Y33675D01*
X1312883Y33842D01*
X1312425Y34050D01*
X1311800Y34383D01*
Y32717D01*
G01X1311700Y48600D02*
X1315700D01*
Y56000D01*
G01X1317700Y90000D02*
X1315600Y91800D01*
X1317700Y94000D01*
G01X1317800Y97600D02*
X1298600D01*
Y86400D01*
X1317800D01*
Y97600D01*
X1317400D01*
G01X1325200Y74983D02*
X1322700D01*
Y75817D01*
X1322825Y76150D01*
X1322992Y76400D01*
X1323242Y76608D01*
X1323533Y76775D01*
X1323950Y76817D01*
X1324367Y76775D01*
X1324658Y76608D01*
X1324908Y76400D01*
X1325075Y76150D01*
X1325200Y75817D01*
Y74983D01*
G01X1324700Y78083D02*
X1324992Y78333D01*
X1325158Y78667D01*
X1325200Y79042D01*
X1325158Y79375D01*
X1324950Y79708D01*
X1324700Y79917D01*
X1324450Y79958D01*
X1324158Y79875D01*
X1323950Y79583D01*
X1323867Y79292D01*
Y78917D01*
G01Y79292D02*
X1323742Y79542D01*
X1323533Y79750D01*
X1323283Y79833D01*
X1323033Y79750D01*
X1322825Y79542D01*
X1322700Y79167D01*
X1322742Y78792D01*
X1322908Y78417D01*
G01X1322700Y82100D02*
X1322783Y81767D01*
X1322992Y81517D01*
X1323242Y81350D01*
X1323575Y81225D01*
X1323950Y81183D01*
X1324325Y81225D01*
X1324658Y81350D01*
X1324908Y81517D01*
X1325117Y81767D01*
X1325200Y82100D01*
X1325117Y82433D01*
X1324908Y82683D01*
X1324658Y82850D01*
X1324325Y82975D01*
X1323950Y83017D01*
X1323575Y82975D01*
X1323242Y82850D01*
X1322992Y82683D01*
X1322783Y82433D01*
X1322700Y82100D01*
G01X1321400Y72900D02*
Y56800D01*
G01X1314400Y72900D02*
X1321400D01*
G01X1314400Y56800D02*
Y72900D01*
G01X1321400Y56800D02*
X1314400D01*
G01X1299350Y29661D02*
X1299017Y29703D01*
X1298725Y29869D01*
X1298475Y30119D01*
X1298308Y30411D01*
X1298225Y30744D01*
Y31078D01*
X1298308Y31411D01*
X1298475Y31703D01*
X1298725Y31953D01*
X1299017Y32119D01*
X1299350Y32161D01*
X1299683Y32119D01*
X1299975Y31953D01*
X1300225Y31703D01*
X1300392Y31411D01*
X1300475Y31078D01*
Y30744D01*
X1300392Y30411D01*
X1300225Y30119D01*
X1299975Y29869D01*
X1299683Y29703D01*
X1299350Y29661D01*
G01X1299683Y30328D02*
X1300183Y29661D01*
G01X1302450D02*
Y32161D01*
X1301950Y31661D01*
G01Y29661D02*
X1302950D01*
G01X1304633Y30036D02*
X1304883Y29828D01*
X1305175Y29703D01*
X1305550Y29661D01*
X1305925Y29744D01*
X1306217Y29911D01*
X1306425Y30203D01*
X1306467Y30536D01*
X1306383Y30869D01*
X1306175Y31078D01*
X1305883Y31244D01*
X1305592Y31286D01*
X1305300Y31244D01*
X1304925Y31078D01*
X1305050Y32161D01*
X1306175D01*
G01X1307733Y30036D02*
X1307983Y29828D01*
X1308275Y29703D01*
X1308650Y29661D01*
X1309025Y29744D01*
X1309317Y29911D01*
X1309525Y30203D01*
X1309567Y30536D01*
X1309483Y30869D01*
X1309275Y31078D01*
X1308983Y31244D01*
X1308692Y31286D01*
X1308400Y31244D01*
X1308025Y31078D01*
X1308150Y32161D01*
X1309275D01*
G01X1296800Y56200D02*
Y44800D01*
G01X1310200Y56200D02*
X1296800D01*
G01X1310200Y44800D02*
Y56200D01*
G01X1296800Y44800D02*
X1310200D01*
G01X1265647Y131367D02*
X1265522Y131117D01*
X1265439Y130825D01*
Y130492D01*
X1265564Y130117D01*
X1265772Y129825D01*
X1266022Y129617D01*
X1266439Y129450D01*
X1266814Y129408D01*
X1267189Y129492D01*
X1267439Y129617D01*
X1267689Y129867D01*
X1267856Y130158D01*
X1267939Y130450D01*
Y130742D01*
X1267856Y131033D01*
X1267731Y131283D01*
X1267564Y131492D01*
G01X1267939Y134050D02*
X1265439D01*
X1267231Y132508D01*
Y134592D01*
G01X1265856Y135858D02*
X1265606Y136108D01*
X1265481Y136400D01*
X1265439Y136733D01*
X1265522Y137150D01*
X1265731Y137442D01*
X1265981Y137525D01*
X1266231Y137483D01*
X1266439Y137317D01*
X1266856Y136483D01*
X1267147Y136108D01*
X1267564Y135858D01*
X1267939Y135775D01*
Y137525D01*
G01Y139667D02*
X1267397Y139750D01*
X1266939Y139875D01*
X1266522Y140042D01*
X1266064Y140250D01*
X1265439Y140583D01*
Y138917D01*
G01X1263939Y129617D02*
X1261439D01*
Y130658D01*
X1261564Y130992D01*
X1261731Y131200D01*
X1262064Y131283D01*
X1262397Y131200D01*
X1262606Y130950D01*
X1262731Y130658D01*
Y129617D01*
G01Y130658D02*
X1263939Y131283D01*
G01Y133467D02*
X1263397Y133550D01*
X1262939Y133675D01*
X1262522Y133842D01*
X1262064Y134050D01*
X1261439Y134383D01*
Y132717D01*
G01X1262897Y135858D02*
X1262606Y136150D01*
X1262439Y136400D01*
X1262356Y136733D01*
X1262439Y137025D01*
X1262606Y137233D01*
X1262856Y137400D01*
X1263147Y137442D01*
X1263397Y137400D01*
X1263647Y137233D01*
X1263856Y136983D01*
X1263939Y136692D01*
X1263856Y136358D01*
X1263606Y136067D01*
X1263231Y135900D01*
X1262814Y135858D01*
X1262272Y135942D01*
X1261981Y136067D01*
X1261689Y136275D01*
X1261481Y136567D01*
X1261439Y136858D01*
X1261522Y137150D01*
X1261731Y137358D01*
G01X1261439Y139750D02*
X1261522Y139417D01*
X1261731Y139167D01*
X1261981Y139000D01*
X1262314Y138875D01*
X1262689Y138833D01*
X1263064Y138875D01*
X1263397Y139000D01*
X1263647Y139167D01*
X1263856Y139417D01*
X1263939Y139750D01*
X1263856Y140083D01*
X1263647Y140333D01*
X1263397Y140500D01*
X1263064Y140625D01*
X1262689Y140667D01*
X1262314Y140625D01*
X1261981Y140500D01*
X1261731Y140333D01*
X1261522Y140083D01*
X1261439Y139750D01*
G01X1260600Y120900D02*
X1264600D01*
Y128300D01*
G01X1336200Y107500D02*
Y111500D01*
X1328800D01*
G01X1297208Y157767D02*
X1297083Y157517D01*
X1297000Y157225D01*
Y156892D01*
X1297125Y156517D01*
X1297333Y156225D01*
X1297583Y156017D01*
X1298000Y155850D01*
X1298375Y155808D01*
X1298750Y155892D01*
X1299000Y156017D01*
X1299250Y156267D01*
X1299417Y156558D01*
X1299500Y156850D01*
Y157142D01*
X1299417Y157433D01*
X1299292Y157683D01*
X1299125Y157892D01*
G01X1299500Y160450D02*
X1297000D01*
X1298792Y158908D01*
Y160992D01*
G01X1297417Y162258D02*
X1297167Y162508D01*
X1297042Y162800D01*
X1297000Y163133D01*
X1297083Y163550D01*
X1297292Y163842D01*
X1297542Y163925D01*
X1297792Y163883D01*
X1298000Y163717D01*
X1298417Y162883D01*
X1298708Y162508D01*
X1299125Y162258D01*
X1299500Y162175D01*
Y163925D01*
G01X1297000Y166150D02*
X1297083Y165817D01*
X1297292Y165567D01*
X1297542Y165400D01*
X1297875Y165275D01*
X1298250Y165233D01*
X1298625Y165275D01*
X1298958Y165400D01*
X1299208Y165567D01*
X1299417Y165817D01*
X1299500Y166150D01*
X1299417Y166483D01*
X1299208Y166733D01*
X1298958Y166900D01*
X1298625Y167025D01*
X1298250Y167067D01*
X1297875Y167025D01*
X1297542Y166900D01*
X1297292Y166733D01*
X1297083Y166483D01*
X1297000Y166150D01*
G01X1297208Y190267D02*
X1297083Y190017D01*
X1297000Y189725D01*
Y189392D01*
X1297125Y189017D01*
X1297333Y188725D01*
X1297583Y188517D01*
X1298000Y188350D01*
X1298375Y188308D01*
X1298750Y188392D01*
X1299000Y188517D01*
X1299250Y188767D01*
X1299417Y189058D01*
X1299500Y189350D01*
Y189642D01*
X1299417Y189933D01*
X1299292Y190183D01*
X1299125Y190392D01*
G01X1299500Y192950D02*
X1297000D01*
X1298792Y191408D01*
Y193492D01*
G01X1297417Y194758D02*
X1297167Y195008D01*
X1297042Y195300D01*
X1297000Y195633D01*
X1297083Y196050D01*
X1297292Y196342D01*
X1297542Y196425D01*
X1297792Y196383D01*
X1298000Y196217D01*
X1298417Y195383D01*
X1298708Y195008D01*
X1299125Y194758D01*
X1299500Y194675D01*
Y196425D01*
G01X1298458Y197858D02*
X1298167Y198150D01*
X1298000Y198400D01*
X1297917Y198733D01*
X1298000Y199025D01*
X1298167Y199233D01*
X1298417Y199400D01*
X1298708Y199442D01*
X1298958Y199400D01*
X1299208Y199233D01*
X1299417Y198983D01*
X1299500Y198692D01*
X1299417Y198358D01*
X1299167Y198067D01*
X1298792Y197900D01*
X1298375Y197858D01*
X1297833Y197942D01*
X1297542Y198067D01*
X1297250Y198275D01*
X1297042Y198567D01*
X1297000Y198858D01*
X1297083Y199150D01*
X1297292Y199358D01*
G01X1250800Y163000D02*
Y160500D01*
G01X1249842Y163000D02*
X1251758D01*
G01X1253067Y160500D02*
Y163000D01*
X1254067D01*
X1254400Y162875D01*
X1254650Y162583D01*
X1254733Y162250D01*
X1254650Y161917D01*
X1254442Y161667D01*
X1254067Y161542D01*
X1253067D01*
G01X1257000Y160500D02*
Y163000D01*
X1256500Y162500D01*
G01Y160500D02*
X1257500D01*
G01X1260017D02*
X1260100Y161042D01*
X1260225Y161500D01*
X1260392Y161917D01*
X1260600Y162375D01*
X1260933Y163000D01*
X1259267D01*
G01X1263200Y160500D02*
Y163000D01*
X1262700Y162500D01*
G01Y160500D02*
X1263700D01*
G01X1301850Y107500D02*
X1301517Y107542D01*
X1301225Y107708D01*
X1300975Y107958D01*
X1300808Y108250D01*
X1300725Y108583D01*
Y108917D01*
X1300808Y109250D01*
X1300975Y109542D01*
X1301225Y109792D01*
X1301517Y109958D01*
X1301850Y110000D01*
X1302183Y109958D01*
X1302475Y109792D01*
X1302725Y109542D01*
X1302892Y109250D01*
X1302975Y108917D01*
Y108583D01*
X1302892Y108250D01*
X1302725Y107958D01*
X1302475Y107708D01*
X1302183Y107542D01*
X1301850Y107500D01*
G01X1302183Y108167D02*
X1302683Y107500D01*
G01X1304950D02*
Y110000D01*
X1304450Y109500D01*
G01Y107500D02*
X1305450D01*
G01X1307133Y107875D02*
X1307383Y107667D01*
X1307675Y107542D01*
X1308050Y107500D01*
X1308425Y107583D01*
X1308717Y107750D01*
X1308925Y108042D01*
X1308967Y108375D01*
X1308883Y108708D01*
X1308675Y108917D01*
X1308383Y109083D01*
X1308092Y109125D01*
X1307800Y109083D01*
X1307425Y108917D01*
X1307550Y110000D01*
X1308675D01*
G01X1311650Y107500D02*
Y110000D01*
X1310108Y108208D01*
X1312192D01*
G01X1326350Y145500D02*
X1326017Y145542D01*
X1325725Y145708D01*
X1325475Y145958D01*
X1325308Y146250D01*
X1325225Y146583D01*
Y146917D01*
X1325308Y147250D01*
X1325475Y147542D01*
X1325725Y147792D01*
X1326017Y147958D01*
X1326350Y148000D01*
X1326683Y147958D01*
X1326975Y147792D01*
X1327225Y147542D01*
X1327392Y147250D01*
X1327475Y146917D01*
Y146583D01*
X1327392Y146250D01*
X1327225Y145958D01*
X1326975Y145708D01*
X1326683Y145542D01*
X1326350Y145500D01*
G01X1326683Y146167D02*
X1327183Y145500D01*
G01X1329450D02*
Y148000D01*
X1328950Y147500D01*
G01Y145500D02*
X1329950D01*
G01X1331633Y145875D02*
X1331883Y145667D01*
X1332175Y145542D01*
X1332550Y145500D01*
X1332925Y145583D01*
X1333217Y145750D01*
X1333425Y146042D01*
X1333467Y146375D01*
X1333383Y146708D01*
X1333175Y146917D01*
X1332883Y147083D01*
X1332592Y147125D01*
X1332300Y147083D01*
X1331925Y146917D01*
X1332050Y148000D01*
X1333175D01*
G01X1334858Y146542D02*
X1335150Y146833D01*
X1335400Y147000D01*
X1335733Y147083D01*
X1336025Y147000D01*
X1336233Y146833D01*
X1336400Y146583D01*
X1336442Y146292D01*
X1336400Y146042D01*
X1336233Y145792D01*
X1335983Y145583D01*
X1335692Y145500D01*
X1335358Y145583D01*
X1335067Y145833D01*
X1334900Y146208D01*
X1334858Y146625D01*
X1334942Y147167D01*
X1335067Y147458D01*
X1335275Y147750D01*
X1335567Y147958D01*
X1335858Y148000D01*
X1336150Y147917D01*
X1336358Y147708D01*
G01X1314800Y132000D02*
X1316900Y130200D01*
X1314800Y128000D01*
G01X1314700Y124400D02*
X1333900D01*
Y135600D01*
X1314700D01*
Y124400D01*
X1315100D01*
G01X1254166Y135917D02*
X1251666D01*
Y136958D01*
X1251791Y137292D01*
X1251958Y137500D01*
X1252291Y137583D01*
X1252624Y137500D01*
X1252833Y137250D01*
X1252958Y136958D01*
Y135917D01*
G01Y136958D02*
X1254166Y137583D01*
G01Y139767D02*
X1253624Y139850D01*
X1253166Y139975D01*
X1252749Y140142D01*
X1252291Y140350D01*
X1251666Y140683D01*
Y139017D01*
G01X1253124Y142158D02*
X1252833Y142450D01*
X1252666Y142700D01*
X1252583Y143033D01*
X1252666Y143325D01*
X1252833Y143533D01*
X1253083Y143700D01*
X1253374Y143742D01*
X1253624Y143700D01*
X1253874Y143533D01*
X1254083Y143283D01*
X1254166Y142992D01*
X1254083Y142658D01*
X1253833Y142367D01*
X1253458Y142200D01*
X1253041Y142158D01*
X1252499Y142242D01*
X1252208Y142367D01*
X1251916Y142575D01*
X1251708Y142867D01*
X1251666Y143158D01*
X1251749Y143450D01*
X1251958Y143658D01*
G01X1254166Y146550D02*
X1251666D01*
X1253458Y145008D01*
Y147092D01*
G01X1301208Y157767D02*
X1301083Y157517D01*
X1301000Y157225D01*
Y156892D01*
X1301125Y156517D01*
X1301333Y156225D01*
X1301583Y156017D01*
X1302000Y155850D01*
X1302375Y155808D01*
X1302750Y155892D01*
X1303000Y156017D01*
X1303250Y156267D01*
X1303417Y156558D01*
X1303500Y156850D01*
Y157142D01*
X1303417Y157433D01*
X1303292Y157683D01*
X1303125Y157892D01*
G01X1303500Y160450D02*
X1301000D01*
X1302792Y158908D01*
Y160992D01*
G01X1301417Y162258D02*
X1301167Y162508D01*
X1301042Y162800D01*
X1301000Y163133D01*
X1301083Y163550D01*
X1301292Y163842D01*
X1301542Y163925D01*
X1301792Y163883D01*
X1302000Y163717D01*
X1302417Y162883D01*
X1302708Y162508D01*
X1303125Y162258D01*
X1303500Y162175D01*
Y163925D01*
G01Y166150D02*
X1301000D01*
X1301500Y165650D01*
G01X1303500D02*
Y166650D01*
G01X1304500Y136200D02*
Y141700D01*
G01X1312500Y136200D02*
X1304500D01*
G01X1312500Y141700D02*
Y136200D01*
G01Y153800D02*
Y148300D01*
G01X1304500Y153800D02*
X1312500D01*
G01X1304500Y148300D02*
Y153800D01*
G01X1300017Y118000D02*
Y120500D01*
X1301058D01*
X1301392Y120375D01*
X1301600Y120208D01*
X1301683Y119875D01*
X1301600Y119542D01*
X1301350Y119333D01*
X1301058Y119208D01*
X1300017D01*
G01X1301058D02*
X1301683Y118000D01*
G01X1303867D02*
X1303950Y118542D01*
X1304075Y119000D01*
X1304242Y119417D01*
X1304450Y119875D01*
X1304783Y120500D01*
X1303117D01*
G01X1306133Y118375D02*
X1306383Y118167D01*
X1306675Y118042D01*
X1307050Y118000D01*
X1307425Y118083D01*
X1307717Y118250D01*
X1307925Y118542D01*
X1307967Y118875D01*
X1307883Y119208D01*
X1307675Y119417D01*
X1307383Y119583D01*
X1307092Y119625D01*
X1306800Y119583D01*
X1306425Y119417D01*
X1306550Y120500D01*
X1307675D01*
G01X1309442Y118292D02*
X1309733Y118083D01*
X1310067Y118000D01*
X1310400Y118083D01*
X1310692Y118333D01*
X1310900Y118708D01*
X1310983Y119083D01*
Y119542D01*
X1310900Y119917D01*
X1310692Y120250D01*
X1310442Y120417D01*
X1310150Y120500D01*
X1309817Y120417D01*
X1309567Y120250D01*
X1309400Y120000D01*
X1309317Y119667D01*
X1309400Y119375D01*
X1309608Y119083D01*
X1309858Y118917D01*
X1310150Y118875D01*
X1310483Y118958D01*
X1310733Y119167D01*
X1310983Y119542D01*
G01X1313800Y130000D02*
Y122000D01*
X1296200D01*
Y130000D01*
X1313800D01*
G01X1311517Y165300D02*
Y167800D01*
X1312558D01*
X1312892Y167675D01*
X1313100Y167508D01*
X1313183Y167175D01*
X1313100Y166842D01*
X1312850Y166633D01*
X1312558Y166508D01*
X1311517D01*
G01X1312558D02*
X1313183Y165300D01*
G01X1315367D02*
X1315450Y165842D01*
X1315575Y166300D01*
X1315742Y166717D01*
X1315950Y167175D01*
X1316283Y167800D01*
X1314617D01*
G01X1317758Y166342D02*
X1318050Y166633D01*
X1318300Y166800D01*
X1318633Y166883D01*
X1318925Y166800D01*
X1319133Y166633D01*
X1319300Y166383D01*
X1319342Y166092D01*
X1319300Y165842D01*
X1319133Y165592D01*
X1318883Y165383D01*
X1318592Y165300D01*
X1318258Y165383D01*
X1317967Y165633D01*
X1317800Y166008D01*
X1317758Y166425D01*
X1317842Y166967D01*
X1317967Y167258D01*
X1318175Y167550D01*
X1318467Y167758D01*
X1318758Y167800D01*
X1319050Y167717D01*
X1319258Y167508D01*
G01X1321650Y165300D02*
Y167800D01*
X1321150Y167300D01*
G01Y165300D02*
X1322150D01*
G01X1322300Y163800D02*
Y155800D01*
X1304700D01*
Y163800D01*
X1322300D01*
G01X1306408Y190267D02*
X1306283Y190017D01*
X1306200Y189725D01*
Y189392D01*
X1306325Y189017D01*
X1306533Y188725D01*
X1306783Y188517D01*
X1307200Y188350D01*
X1307575Y188308D01*
X1307950Y188392D01*
X1308200Y188517D01*
X1308450Y188767D01*
X1308617Y189058D01*
X1308700Y189350D01*
Y189642D01*
X1308617Y189933D01*
X1308492Y190183D01*
X1308325Y190392D01*
G01X1308700Y192950D02*
X1306200D01*
X1307992Y191408D01*
Y193492D01*
G01X1306617Y194758D02*
X1306367Y195008D01*
X1306242Y195300D01*
X1306200Y195633D01*
X1306283Y196050D01*
X1306492Y196342D01*
X1306742Y196425D01*
X1306992Y196383D01*
X1307200Y196217D01*
X1307617Y195383D01*
X1307908Y195008D01*
X1308325Y194758D01*
X1308700Y194675D01*
Y196425D01*
G01Y199150D02*
X1306200D01*
X1307992Y197608D01*
Y199692D01*
G01X1312047Y190267D02*
X1311922Y190017D01*
X1311839Y189725D01*
Y189392D01*
X1311964Y189017D01*
X1312172Y188725D01*
X1312422Y188517D01*
X1312839Y188350D01*
X1313214Y188308D01*
X1313589Y188392D01*
X1313839Y188517D01*
X1314089Y188767D01*
X1314256Y189058D01*
X1314339Y189350D01*
Y189642D01*
X1314256Y189933D01*
X1314131Y190183D01*
X1313964Y190392D01*
G01X1314339Y192950D02*
X1311839D01*
X1313631Y191408D01*
Y193492D01*
G01X1312256Y194758D02*
X1312006Y195008D01*
X1311881Y195300D01*
X1311839Y195633D01*
X1311922Y196050D01*
X1312131Y196342D01*
X1312381Y196425D01*
X1312631Y196383D01*
X1312839Y196217D01*
X1313256Y195383D01*
X1313547Y195008D01*
X1313964Y194758D01*
X1314339Y194675D01*
Y196425D01*
G01X1313964Y197733D02*
X1314172Y197983D01*
X1314297Y198275D01*
X1314339Y198650D01*
X1314256Y199025D01*
X1314089Y199317D01*
X1313797Y199525D01*
X1313464Y199567D01*
X1313131Y199483D01*
X1312922Y199275D01*
X1312756Y198983D01*
X1312714Y198692D01*
X1312756Y198400D01*
X1312922Y198025D01*
X1311839Y198150D01*
Y199275D01*
G01X1271775Y209000D02*
Y211500D01*
G01X1273525D02*
Y209000D01*
G01Y210250D02*
X1271775D01*
G01X1274833Y209000D02*
Y211500D01*
X1275667D01*
X1276000Y211375D01*
X1276250Y211208D01*
X1276458Y210958D01*
X1276625Y210667D01*
X1276667Y210250D01*
X1276625Y209833D01*
X1276458Y209542D01*
X1276250Y209292D01*
X1276000Y209125D01*
X1275667Y209000D01*
X1274833D01*
G01X1277933D02*
Y211500D01*
X1278767D01*
X1279100Y211375D01*
X1279350Y211208D01*
X1279558Y210958D01*
X1279725Y210667D01*
X1279767Y210250D01*
X1279725Y209833D01*
X1279558Y209542D01*
X1279350Y209292D01*
X1279100Y209125D01*
X1278767Y209000D01*
X1277933D01*
G01X1281075Y209333D02*
X1281408Y209125D01*
X1281783Y209000D01*
X1282117D01*
X1282450Y209125D01*
X1282700Y209333D01*
X1282825Y209625D01*
X1282742Y209917D01*
X1282533Y210167D01*
X1282158Y210333D01*
X1281658Y210417D01*
X1281367Y210583D01*
X1281242Y210875D01*
X1281325Y211167D01*
X1281533Y211375D01*
X1281825Y211500D01*
X1282117D01*
X1282408Y211417D01*
X1282658Y211208D01*
G01X1284008Y209000D02*
X1285050Y211500D01*
X1286092Y209000D01*
G01X1285717Y209875D02*
X1284383D01*
G01X1287275Y209333D02*
X1287608Y209125D01*
X1287983Y209000D01*
X1288317D01*
X1288650Y209125D01*
X1288900Y209333D01*
X1289025Y209625D01*
X1288942Y209917D01*
X1288733Y210167D01*
X1288358Y210333D01*
X1287858Y210417D01*
X1287567Y210583D01*
X1287442Y210875D01*
X1287525Y211167D01*
X1287733Y211375D01*
X1288025Y211500D01*
X1288317D01*
X1288608Y211417D01*
X1288858Y211208D01*
G01X1290333Y209500D02*
X1290583Y209208D01*
X1290917Y209042D01*
X1291292Y209000D01*
X1291625Y209042D01*
X1291958Y209250D01*
X1292167Y209500D01*
X1292208Y209750D01*
X1292125Y210042D01*
X1291833Y210250D01*
X1291542Y210333D01*
X1291167D01*
G01X1291542D02*
X1291792Y210458D01*
X1292000Y210667D01*
X1292083Y210917D01*
X1292000Y211167D01*
X1291792Y211375D01*
X1291417Y211500D01*
X1291042Y211458D01*
X1290667Y211292D01*
G01X1294350Y211500D02*
X1294017Y211417D01*
X1293767Y211208D01*
X1293600Y210958D01*
X1293475Y210625D01*
X1293433Y210250D01*
X1293475Y209875D01*
X1293600Y209542D01*
X1293767Y209292D01*
X1294017Y209083D01*
X1294350Y209000D01*
X1294683Y209083D01*
X1294933Y209292D01*
X1295100Y209542D01*
X1295225Y209875D01*
X1295267Y210250D01*
X1295225Y210625D01*
X1295100Y210958D01*
X1294933Y211208D01*
X1294683Y211417D01*
X1294350Y211500D01*
G01X1259217Y373600D02*
Y376100D01*
X1260258D01*
X1260592Y375975D01*
X1260800Y375808D01*
X1260883Y375475D01*
X1260800Y375142D01*
X1260550Y374933D01*
X1260258Y374808D01*
X1259217D01*
G01X1260258D02*
X1260883Y373600D01*
G01X1263650D02*
Y376100D01*
X1262108Y374308D01*
X1264192D01*
G01X1265458Y374642D02*
X1265750Y374933D01*
X1266000Y375100D01*
X1266333Y375183D01*
X1266625Y375100D01*
X1266833Y374933D01*
X1267000Y374683D01*
X1267042Y374392D01*
X1267000Y374142D01*
X1266833Y373892D01*
X1266583Y373683D01*
X1266292Y373600D01*
X1265958Y373683D01*
X1265667Y373933D01*
X1265500Y374308D01*
X1265458Y374725D01*
X1265542Y375267D01*
X1265667Y375558D01*
X1265875Y375850D01*
X1266167Y376058D01*
X1266458Y376100D01*
X1266750Y376017D01*
X1266958Y375808D01*
G01X1269267Y373600D02*
X1269350Y374142D01*
X1269475Y374600D01*
X1269642Y375017D01*
X1269850Y375475D01*
X1270183Y376100D01*
X1268517D01*
G01X1264793Y560075D02*
X1269843D01*
Y658775D01*
X1294493D01*
Y474375D01*
X1269843D01*
Y533075D01*
X1264793D01*
Y560075D01*
G01X1323017Y382500D02*
Y385000D01*
X1324058D01*
X1324392Y384875D01*
X1324600Y384708D01*
X1324683Y384375D01*
X1324600Y384042D01*
X1324350Y383833D01*
X1324058Y383708D01*
X1323017D01*
G01X1324058D02*
X1324683Y382500D01*
G01X1327450D02*
Y385000D01*
X1325908Y383208D01*
X1327992D01*
G01X1329967Y382500D02*
X1330050Y383042D01*
X1330175Y383500D01*
X1330342Y383917D01*
X1330550Y384375D01*
X1330883Y385000D01*
X1329217D01*
G01X1332358Y384583D02*
X1332608Y384833D01*
X1332900Y384958D01*
X1333233Y385000D01*
X1333650Y384917D01*
X1333942Y384708D01*
X1334025Y384458D01*
X1333983Y384208D01*
X1333817Y384000D01*
X1332983Y383583D01*
X1332608Y383292D01*
X1332358Y382875D01*
X1332275Y382500D01*
X1334025D01*
G01X1343274Y381426D02*
Y385426D01*
X1335874D01*
G01X1264895Y381269D02*
Y385269D01*
X1257495D01*
G01X1276718Y406299D02*
Y408799D01*
X1277759D01*
X1278093Y408674D01*
X1278301Y408507D01*
X1278384Y408174D01*
X1278301Y407841D01*
X1278051Y407632D01*
X1277759Y407507D01*
X1276718D01*
G01X1277759D02*
X1278384Y406299D01*
G01X1281151D02*
Y408799D01*
X1279609Y407007D01*
X1281693D01*
G01X1282959Y407341D02*
X1283251Y407632D01*
X1283501Y407799D01*
X1283834Y407882D01*
X1284126Y407799D01*
X1284334Y407632D01*
X1284501Y407382D01*
X1284543Y407091D01*
X1284501Y406841D01*
X1284334Y406591D01*
X1284084Y406382D01*
X1283793Y406299D01*
X1283459Y406382D01*
X1283168Y406632D01*
X1283001Y407007D01*
X1282959Y407424D01*
X1283043Y407966D01*
X1283168Y408257D01*
X1283376Y408549D01*
X1283668Y408757D01*
X1283959Y408799D01*
X1284251Y408716D01*
X1284459Y408507D01*
G01X1286059Y407341D02*
X1286351Y407632D01*
X1286601Y407799D01*
X1286934Y407882D01*
X1287226Y407799D01*
X1287434Y407632D01*
X1287601Y407382D01*
X1287643Y407091D01*
X1287601Y406841D01*
X1287434Y406591D01*
X1287184Y406382D01*
X1286893Y406299D01*
X1286559Y406382D01*
X1286268Y406632D01*
X1286101Y407007D01*
X1286059Y407424D01*
X1286143Y407966D01*
X1286268Y408257D01*
X1286476Y408549D01*
X1286768Y408757D01*
X1287059Y408799D01*
X1287351Y408716D01*
X1287559Y408507D01*
G01X1279628Y401046D02*
Y405046D01*
X1272228D01*
G01X1249500Y396517D02*
X1247000D01*
Y397558D01*
X1247125Y397892D01*
X1247292Y398100D01*
X1247625Y398183D01*
X1247958Y398100D01*
X1248167Y397850D01*
X1248292Y397558D01*
Y396517D01*
G01Y397558D02*
X1249500Y398183D01*
G01Y400950D02*
X1247000D01*
X1248792Y399408D01*
Y401492D01*
G01X1249000Y402633D02*
X1249292Y402883D01*
X1249458Y403217D01*
X1249500Y403592D01*
X1249458Y403925D01*
X1249250Y404258D01*
X1249000Y404467D01*
X1248750Y404508D01*
X1248458Y404425D01*
X1248250Y404133D01*
X1248167Y403842D01*
Y403467D01*
G01Y403842D02*
X1248042Y404092D01*
X1247833Y404300D01*
X1247583Y404383D01*
X1247333Y404300D01*
X1247125Y404092D01*
X1247000Y403717D01*
X1247042Y403342D01*
X1247208Y402967D01*
G01X1249000Y405733D02*
X1249292Y405983D01*
X1249458Y406317D01*
X1249500Y406692D01*
X1249458Y407025D01*
X1249250Y407358D01*
X1249000Y407567D01*
X1248750Y407608D01*
X1248458Y407525D01*
X1248250Y407233D01*
X1248167Y406942D01*
Y406567D01*
G01Y406942D02*
X1248042Y407192D01*
X1247833Y407400D01*
X1247583Y407483D01*
X1247333Y407400D01*
X1247125Y407192D01*
X1247000Y406817D01*
X1247042Y406442D01*
X1247208Y406067D01*
G01X1271350Y382000D02*
X1271017Y382042D01*
X1270725Y382208D01*
X1270475Y382458D01*
X1270308Y382750D01*
X1270225Y383083D01*
Y383417D01*
X1270308Y383750D01*
X1270475Y384042D01*
X1270725Y384292D01*
X1271017Y384458D01*
X1271350Y384500D01*
X1271683Y384458D01*
X1271975Y384292D01*
X1272225Y384042D01*
X1272392Y383750D01*
X1272475Y383417D01*
Y383083D01*
X1272392Y382750D01*
X1272225Y382458D01*
X1271975Y382208D01*
X1271683Y382042D01*
X1271350Y382000D01*
G01X1271683Y382667D02*
X1272183Y382000D01*
G01X1273658Y384083D02*
X1273908Y384333D01*
X1274200Y384458D01*
X1274533Y384500D01*
X1274950Y384417D01*
X1275242Y384208D01*
X1275325Y383958D01*
X1275283Y383708D01*
X1275117Y383500D01*
X1274283Y383083D01*
X1273908Y382792D01*
X1273658Y382375D01*
X1273575Y382000D01*
X1275325D01*
G01X1276633Y382500D02*
X1276883Y382208D01*
X1277217Y382042D01*
X1277592Y382000D01*
X1277925Y382042D01*
X1278258Y382250D01*
X1278467Y382500D01*
X1278508Y382750D01*
X1278425Y383042D01*
X1278133Y383250D01*
X1277842Y383333D01*
X1277467D01*
G01X1277842D02*
X1278092Y383458D01*
X1278300Y383667D01*
X1278383Y383917D01*
X1278300Y384167D01*
X1278092Y384375D01*
X1277717Y384500D01*
X1277342Y384458D01*
X1276967Y384292D01*
G01X1280567Y382000D02*
X1280650Y382542D01*
X1280775Y383000D01*
X1280942Y383417D01*
X1281150Y383875D01*
X1281483Y384500D01*
X1279817D01*
G01X1280303Y385587D02*
Y399587D01*
G01X1267303Y385587D02*
X1280303D01*
G01X1267303Y399587D02*
Y385587D01*
G01X1280303Y399587D02*
X1267303D01*
G01X1255850Y402500D02*
X1255517Y402542D01*
X1255225Y402708D01*
X1254975Y402958D01*
X1254808Y403250D01*
X1254725Y403583D01*
Y403917D01*
X1254808Y404250D01*
X1254975Y404542D01*
X1255225Y404792D01*
X1255517Y404958D01*
X1255850Y405000D01*
X1256183Y404958D01*
X1256475Y404792D01*
X1256725Y404542D01*
X1256892Y404250D01*
X1256975Y403917D01*
Y403583D01*
X1256892Y403250D01*
X1256725Y402958D01*
X1256475Y402708D01*
X1256183Y402542D01*
X1255850Y402500D01*
G01X1256183Y403167D02*
X1256683Y402500D01*
G01X1258158Y404583D02*
X1258408Y404833D01*
X1258700Y404958D01*
X1259033Y405000D01*
X1259450Y404917D01*
X1259742Y404708D01*
X1259825Y404458D01*
X1259783Y404208D01*
X1259617Y404000D01*
X1258783Y403583D01*
X1258408Y403292D01*
X1258158Y402875D01*
X1258075Y402500D01*
X1259825D01*
G01X1261258Y403542D02*
X1261550Y403833D01*
X1261800Y404000D01*
X1262133Y404083D01*
X1262425Y404000D01*
X1262633Y403833D01*
X1262800Y403583D01*
X1262842Y403292D01*
X1262800Y403042D01*
X1262633Y402792D01*
X1262383Y402583D01*
X1262092Y402500D01*
X1261758Y402583D01*
X1261467Y402833D01*
X1261300Y403208D01*
X1261258Y403625D01*
X1261342Y404167D01*
X1261467Y404458D01*
X1261675Y404750D01*
X1261967Y404958D01*
X1262258Y405000D01*
X1262550Y404917D01*
X1262758Y404708D01*
G01X1265150Y405000D02*
X1264817Y404917D01*
X1264567Y404708D01*
X1264400Y404458D01*
X1264275Y404125D01*
X1264233Y403750D01*
X1264275Y403375D01*
X1264400Y403042D01*
X1264567Y402792D01*
X1264817Y402583D01*
X1265150Y402500D01*
X1265483Y402583D01*
X1265733Y402792D01*
X1265900Y403042D01*
X1266025Y403375D01*
X1266067Y403750D01*
X1266025Y404125D01*
X1265900Y404458D01*
X1265733Y404708D01*
X1265483Y404917D01*
X1265150Y405000D01*
G01X1252195Y386494D02*
X1266195D01*
G01X1252195Y399494D02*
Y386494D01*
G01X1266195Y399494D02*
X1252195D01*
G01X1266195Y386494D02*
Y399494D01*
G01X1329350Y401000D02*
X1329017Y401042D01*
X1328725Y401208D01*
X1328475Y401458D01*
X1328308Y401750D01*
X1328225Y402083D01*
Y402417D01*
X1328308Y402750D01*
X1328475Y403042D01*
X1328725Y403292D01*
X1329017Y403458D01*
X1329350Y403500D01*
X1329683Y403458D01*
X1329975Y403292D01*
X1330225Y403042D01*
X1330392Y402750D01*
X1330475Y402417D01*
Y402083D01*
X1330392Y401750D01*
X1330225Y401458D01*
X1329975Y401208D01*
X1329683Y401042D01*
X1329350Y401000D01*
G01X1329683Y401667D02*
X1330183Y401000D01*
G01X1331658Y403083D02*
X1331908Y403333D01*
X1332200Y403458D01*
X1332533Y403500D01*
X1332950Y403417D01*
X1333242Y403208D01*
X1333325Y402958D01*
X1333283Y402708D01*
X1333117Y402500D01*
X1332283Y402083D01*
X1331908Y401792D01*
X1331658Y401375D01*
X1331575Y401000D01*
X1333325D01*
G01X1334758Y402042D02*
X1335050Y402333D01*
X1335300Y402500D01*
X1335633Y402583D01*
X1335925Y402500D01*
X1336133Y402333D01*
X1336300Y402083D01*
X1336342Y401792D01*
X1336300Y401542D01*
X1336133Y401292D01*
X1335883Y401083D01*
X1335592Y401000D01*
X1335258Y401083D01*
X1334967Y401333D01*
X1334800Y401708D01*
X1334758Y402125D01*
X1334842Y402667D01*
X1334967Y402958D01*
X1335175Y403250D01*
X1335467Y403458D01*
X1335758Y403500D01*
X1336050Y403417D01*
X1336258Y403208D01*
G01X1337858Y402042D02*
X1338150Y402333D01*
X1338400Y402500D01*
X1338733Y402583D01*
X1339025Y402500D01*
X1339233Y402333D01*
X1339400Y402083D01*
X1339442Y401792D01*
X1339400Y401542D01*
X1339233Y401292D01*
X1338983Y401083D01*
X1338692Y401000D01*
X1338358Y401083D01*
X1338067Y401333D01*
X1337900Y401708D01*
X1337858Y402125D01*
X1337942Y402667D01*
X1338067Y402958D01*
X1338275Y403250D01*
X1338567Y403458D01*
X1338858Y403500D01*
X1339150Y403417D01*
X1339358Y403208D01*
G01X1330574Y386651D02*
X1344574D01*
G01X1330574Y399651D02*
Y386651D01*
G01X1344574Y399651D02*
X1330574D01*
G01X1253176Y516190D02*
X1252926Y516315D01*
X1252634Y516398D01*
X1252301D01*
X1251926Y516273D01*
X1251634Y516065D01*
X1251426Y515815D01*
X1251259Y515398D01*
X1251217Y515023D01*
X1251301Y514648D01*
X1251426Y514398D01*
X1251676Y514148D01*
X1251967Y513981D01*
X1252259Y513898D01*
X1252551D01*
X1252842Y513981D01*
X1253092Y514106D01*
X1253301Y514273D01*
G01X1254567Y515981D02*
X1254817Y516231D01*
X1255109Y516356D01*
X1255442Y516398D01*
X1255859Y516315D01*
X1256151Y516106D01*
X1256234Y515856D01*
X1256192Y515606D01*
X1256026Y515398D01*
X1255192Y514981D01*
X1254817Y514690D01*
X1254567Y514273D01*
X1254484Y513898D01*
X1256234D01*
G01X1257667Y514940D02*
X1257959Y515231D01*
X1258209Y515398D01*
X1258542Y515481D01*
X1258834Y515398D01*
X1259042Y515231D01*
X1259209Y514981D01*
X1259251Y514690D01*
X1259209Y514440D01*
X1259042Y514190D01*
X1258792Y513981D01*
X1258501Y513898D01*
X1258167Y513981D01*
X1257876Y514231D01*
X1257709Y514606D01*
X1257667Y515023D01*
X1257751Y515565D01*
X1257876Y515856D01*
X1258084Y516148D01*
X1258376Y516356D01*
X1258667Y516398D01*
X1258959Y516315D01*
X1259167Y516106D01*
G01X1260642Y514398D02*
X1260892Y514106D01*
X1261226Y513940D01*
X1261601Y513898D01*
X1261934Y513940D01*
X1262267Y514148D01*
X1262476Y514398D01*
X1262517Y514648D01*
X1262434Y514940D01*
X1262142Y515148D01*
X1261851Y515231D01*
X1261476D01*
G01X1261851D02*
X1262101Y515356D01*
X1262309Y515565D01*
X1262392Y515815D01*
X1262309Y516065D01*
X1262101Y516273D01*
X1261726Y516398D01*
X1261351Y516356D01*
X1260976Y516190D01*
G01X1253067Y520392D02*
X1252817Y520517D01*
X1252525Y520600D01*
X1252192D01*
X1251817Y520475D01*
X1251525Y520267D01*
X1251317Y520017D01*
X1251150Y519600D01*
X1251108Y519225D01*
X1251192Y518850D01*
X1251317Y518600D01*
X1251567Y518350D01*
X1251858Y518183D01*
X1252150Y518100D01*
X1252442D01*
X1252733Y518183D01*
X1252983Y518308D01*
X1253192Y518475D01*
G01X1254458Y520183D02*
X1254708Y520433D01*
X1255000Y520558D01*
X1255333Y520600D01*
X1255750Y520517D01*
X1256042Y520308D01*
X1256125Y520058D01*
X1256083Y519808D01*
X1255917Y519600D01*
X1255083Y519183D01*
X1254708Y518892D01*
X1254458Y518475D01*
X1254375Y518100D01*
X1256125D01*
G01X1257558Y519142D02*
X1257850Y519433D01*
X1258100Y519600D01*
X1258433Y519683D01*
X1258725Y519600D01*
X1258933Y519433D01*
X1259100Y519183D01*
X1259142Y518892D01*
X1259100Y518642D01*
X1258933Y518392D01*
X1258683Y518183D01*
X1258392Y518100D01*
X1258058Y518183D01*
X1257767Y518433D01*
X1257600Y518808D01*
X1257558Y519225D01*
X1257642Y519767D01*
X1257767Y520058D01*
X1257975Y520350D01*
X1258267Y520558D01*
X1258558Y520600D01*
X1258850Y520517D01*
X1259058Y520308D01*
G01X1260658Y520183D02*
X1260908Y520433D01*
X1261200Y520558D01*
X1261533Y520600D01*
X1261950Y520517D01*
X1262242Y520308D01*
X1262325Y520058D01*
X1262283Y519808D01*
X1262117Y519600D01*
X1261283Y519183D01*
X1260908Y518892D01*
X1260658Y518475D01*
X1260575Y518100D01*
X1262325D01*
G01X1296208Y535767D02*
X1296083Y535517D01*
X1296000Y535225D01*
Y534892D01*
X1296125Y534517D01*
X1296333Y534225D01*
X1296583Y534017D01*
X1297000Y533850D01*
X1297375Y533808D01*
X1297750Y533892D01*
X1298000Y534017D01*
X1298250Y534267D01*
X1298417Y534558D01*
X1298500Y534850D01*
Y535142D01*
X1298417Y535433D01*
X1298292Y535683D01*
X1298125Y535892D01*
G01X1296417Y537158D02*
X1296167Y537408D01*
X1296042Y537700D01*
X1296000Y538033D01*
X1296083Y538450D01*
X1296292Y538742D01*
X1296542Y538825D01*
X1296792Y538783D01*
X1297000Y538617D01*
X1297417Y537783D01*
X1297708Y537408D01*
X1298125Y537158D01*
X1298500Y537075D01*
Y538825D01*
G01Y540967D02*
X1297958Y541050D01*
X1297500Y541175D01*
X1297083Y541342D01*
X1296625Y541550D01*
X1296000Y541883D01*
Y540217D01*
G01X1296417Y543358D02*
X1296167Y543608D01*
X1296042Y543900D01*
X1296000Y544233D01*
X1296083Y544650D01*
X1296292Y544942D01*
X1296542Y545025D01*
X1296792Y544983D01*
X1297000Y544817D01*
X1297417Y543983D01*
X1297708Y543608D01*
X1298125Y543358D01*
X1298500Y543275D01*
Y545025D01*
G01X1340767Y567453D02*
X1340517Y567578D01*
X1340225Y567661D01*
X1339892D01*
X1339517Y567536D01*
X1339225Y567328D01*
X1339017Y567078D01*
X1338850Y566661D01*
X1338808Y566286D01*
X1338892Y565911D01*
X1339017Y565661D01*
X1339267Y565411D01*
X1339558Y565244D01*
X1339850Y565161D01*
X1340142D01*
X1340433Y565244D01*
X1340683Y565369D01*
X1340892Y565536D01*
G01X1342158Y567244D02*
X1342408Y567494D01*
X1342700Y567619D01*
X1343033Y567661D01*
X1343450Y567578D01*
X1343742Y567369D01*
X1343825Y567119D01*
X1343783Y566869D01*
X1343617Y566661D01*
X1342783Y566244D01*
X1342408Y565953D01*
X1342158Y565536D01*
X1342075Y565161D01*
X1343825D01*
G01X1345967D02*
X1346050Y565703D01*
X1346175Y566161D01*
X1346342Y566578D01*
X1346550Y567036D01*
X1346883Y567661D01*
X1345217D01*
G01X1348233Y565661D02*
X1348483Y565369D01*
X1348817Y565203D01*
X1349192Y565161D01*
X1349525Y565203D01*
X1349858Y565411D01*
X1350067Y565661D01*
X1350108Y565911D01*
X1350025Y566203D01*
X1349733Y566411D01*
X1349442Y566494D01*
X1349067D01*
G01X1349442D02*
X1349692Y566619D01*
X1349900Y566828D01*
X1349983Y567078D01*
X1349900Y567328D01*
X1349692Y567536D01*
X1349317Y567661D01*
X1348942Y567619D01*
X1348567Y567453D01*
G01X1298500Y521517D02*
X1296000D01*
Y522558D01*
X1296125Y522892D01*
X1296292Y523100D01*
X1296625Y523183D01*
X1296958Y523100D01*
X1297167Y522850D01*
X1297292Y522558D01*
Y521517D01*
G01Y522558D02*
X1298500Y523183D01*
G01Y525950D02*
X1296000D01*
X1297792Y524408D01*
Y526492D01*
G01X1298208Y527842D02*
X1298417Y528133D01*
X1298500Y528467D01*
X1298417Y528800D01*
X1298167Y529092D01*
X1297792Y529300D01*
X1297417Y529383D01*
X1296958D01*
X1296583Y529300D01*
X1296250Y529092D01*
X1296083Y528842D01*
X1296000Y528550D01*
X1296083Y528217D01*
X1296250Y527967D01*
X1296500Y527800D01*
X1296833Y527717D01*
X1297125Y527800D01*
X1297417Y528008D01*
X1297583Y528258D01*
X1297625Y528550D01*
X1297542Y528883D01*
X1297333Y529133D01*
X1296958Y529383D01*
G01X1298500Y531650D02*
X1296000D01*
X1296500Y531150D01*
G01X1298500D02*
Y532150D01*
G01X1301400Y532000D02*
Y528000D01*
X1308800D01*
G01X1313339Y488017D02*
X1310839D01*
Y489058D01*
X1310964Y489392D01*
X1311131Y489600D01*
X1311464Y489683D01*
X1311797Y489600D01*
X1312006Y489350D01*
X1312131Y489058D01*
Y488017D01*
G01Y489058D02*
X1313339Y489683D01*
G01Y492450D02*
X1310839D01*
X1312631Y490908D01*
Y492992D01*
G01X1313047Y494342D02*
X1313256Y494633D01*
X1313339Y494967D01*
X1313256Y495300D01*
X1313006Y495592D01*
X1312631Y495800D01*
X1312256Y495883D01*
X1311797D01*
X1311422Y495800D01*
X1311089Y495592D01*
X1310922Y495342D01*
X1310839Y495050D01*
X1310922Y494717D01*
X1311089Y494467D01*
X1311339Y494300D01*
X1311672Y494217D01*
X1311964Y494300D01*
X1312256Y494508D01*
X1312422Y494758D01*
X1312464Y495050D01*
X1312381Y495383D01*
X1312172Y495633D01*
X1311797Y495883D01*
G01X1311256Y497358D02*
X1311006Y497608D01*
X1310881Y497900D01*
X1310839Y498233D01*
X1310922Y498650D01*
X1311131Y498942D01*
X1311381Y499025D01*
X1311631Y498983D01*
X1311839Y498817D01*
X1312256Y497983D01*
X1312547Y497608D01*
X1312964Y497358D01*
X1313339Y497275D01*
Y499025D01*
G01X1310000Y502800D02*
X1314000D01*
Y510200D01*
G01X1323500Y490517D02*
X1321000D01*
Y491558D01*
X1321125Y491892D01*
X1321292Y492100D01*
X1321625Y492183D01*
X1321958Y492100D01*
X1322167Y491850D01*
X1322292Y491558D01*
Y490517D01*
G01Y491558D02*
X1323500Y492183D01*
G01Y494950D02*
X1321000D01*
X1322792Y493408D01*
Y495492D01*
G01X1323208Y496842D02*
X1323417Y497133D01*
X1323500Y497467D01*
X1323417Y497800D01*
X1323167Y498092D01*
X1322792Y498300D01*
X1322417Y498383D01*
X1321958D01*
X1321583Y498300D01*
X1321250Y498092D01*
X1321083Y497842D01*
X1321000Y497550D01*
X1321083Y497217D01*
X1321250Y496967D01*
X1321500Y496800D01*
X1321833Y496717D01*
X1322125Y496800D01*
X1322417Y497008D01*
X1322583Y497258D01*
X1322625Y497550D01*
X1322542Y497883D01*
X1322333Y498133D01*
X1321958Y498383D01*
G01X1323125Y499733D02*
X1323333Y499983D01*
X1323458Y500275D01*
X1323500Y500650D01*
X1323417Y501025D01*
X1323250Y501317D01*
X1322958Y501525D01*
X1322625Y501567D01*
X1322292Y501483D01*
X1322083Y501275D01*
X1321917Y500983D01*
X1321875Y500692D01*
X1321917Y500400D01*
X1322083Y500025D01*
X1321000Y500150D01*
Y501275D01*
G01X1320000Y502800D02*
X1324000D01*
Y510200D01*
G01X1308839Y488017D02*
X1306339D01*
Y489058D01*
X1306464Y489392D01*
X1306631Y489600D01*
X1306964Y489683D01*
X1307297Y489600D01*
X1307506Y489350D01*
X1307631Y489058D01*
Y488017D01*
G01Y489058D02*
X1308839Y489683D01*
G01Y492450D02*
X1306339D01*
X1308131Y490908D01*
Y492992D01*
G01X1308547Y494342D02*
X1308756Y494633D01*
X1308839Y494967D01*
X1308756Y495300D01*
X1308506Y495592D01*
X1308131Y495800D01*
X1307756Y495883D01*
X1307297D01*
X1306922Y495800D01*
X1306589Y495592D01*
X1306422Y495342D01*
X1306339Y495050D01*
X1306422Y494717D01*
X1306589Y494467D01*
X1306839Y494300D01*
X1307172Y494217D01*
X1307464Y494300D01*
X1307756Y494508D01*
X1307922Y494758D01*
X1307964Y495050D01*
X1307881Y495383D01*
X1307672Y495633D01*
X1307297Y495883D01*
G01X1307797Y497358D02*
X1307506Y497650D01*
X1307339Y497900D01*
X1307256Y498233D01*
X1307339Y498525D01*
X1307506Y498733D01*
X1307756Y498900D01*
X1308047Y498942D01*
X1308297Y498900D01*
X1308547Y498733D01*
X1308756Y498483D01*
X1308839Y498192D01*
X1308756Y497858D01*
X1308506Y497567D01*
X1308131Y497400D01*
X1307714Y497358D01*
X1307172Y497442D01*
X1306881Y497567D01*
X1306589Y497775D01*
X1306381Y498067D01*
X1306339Y498358D01*
X1306422Y498650D01*
X1306631Y498858D01*
G01X1309500Y510200D02*
X1305500D01*
Y502800D01*
G01X1336500Y511017D02*
X1334000D01*
Y512058D01*
X1334125Y512392D01*
X1334292Y512600D01*
X1334625Y512683D01*
X1334958Y512600D01*
X1335167Y512350D01*
X1335292Y512058D01*
Y511017D01*
G01Y512058D02*
X1336500Y512683D01*
G01Y515450D02*
X1334000D01*
X1335792Y513908D01*
Y515992D01*
G01X1336208Y517342D02*
X1336417Y517633D01*
X1336500Y517967D01*
X1336417Y518300D01*
X1336167Y518592D01*
X1335792Y518800D01*
X1335417Y518883D01*
X1334958D01*
X1334583Y518800D01*
X1334250Y518592D01*
X1334083Y518342D01*
X1334000Y518050D01*
X1334083Y517717D01*
X1334250Y517467D01*
X1334500Y517300D01*
X1334833Y517217D01*
X1335125Y517300D01*
X1335417Y517508D01*
X1335583Y517758D01*
X1335625Y518050D01*
X1335542Y518383D01*
X1335333Y518633D01*
X1334958Y518883D01*
G01X1336500Y521150D02*
X1336458Y521442D01*
X1336333Y521775D01*
X1336125Y521983D01*
X1335833Y522067D01*
X1335542Y521983D01*
X1335292Y521733D01*
X1335167Y521358D01*
Y520942D01*
X1335083Y520692D01*
X1334875Y520483D01*
X1334583Y520400D01*
X1334292Y520525D01*
X1334083Y520817D01*
X1334000Y521150D01*
X1334083Y521483D01*
X1334292Y521775D01*
X1334583Y521900D01*
X1334875Y521817D01*
X1335083Y521608D01*
X1335167Y521358D01*
Y520942D01*
X1335292Y520567D01*
X1335542Y520317D01*
X1335833Y520233D01*
X1336125Y520317D01*
X1336333Y520525D01*
X1336458Y520858D01*
X1336500Y521150D01*
G01X1324500Y515300D02*
X1328500D01*
Y522700D01*
G01X1339017Y561161D02*
Y563661D01*
X1340058D01*
X1340392Y563536D01*
X1340600Y563369D01*
X1340683Y563036D01*
X1340600Y562703D01*
X1340350Y562494D01*
X1340058Y562369D01*
X1339017D01*
G01X1340058D02*
X1340683Y561161D01*
G01X1343450D02*
Y563661D01*
X1341908Y561869D01*
X1343992D01*
G01X1345342Y561453D02*
X1345633Y561244D01*
X1345967Y561161D01*
X1346300Y561244D01*
X1346592Y561494D01*
X1346800Y561869D01*
X1346883Y562244D01*
Y562703D01*
X1346800Y563078D01*
X1346592Y563411D01*
X1346342Y563578D01*
X1346050Y563661D01*
X1345717Y563578D01*
X1345467Y563411D01*
X1345300Y563161D01*
X1345217Y562828D01*
X1345300Y562536D01*
X1345508Y562244D01*
X1345758Y562078D01*
X1346050Y562036D01*
X1346383Y562119D01*
X1346633Y562328D01*
X1346883Y562703D01*
G01X1348442Y561453D02*
X1348733Y561244D01*
X1349067Y561161D01*
X1349400Y561244D01*
X1349692Y561494D01*
X1349900Y561869D01*
X1349983Y562244D01*
Y562703D01*
X1349900Y563078D01*
X1349692Y563411D01*
X1349442Y563578D01*
X1349150Y563661D01*
X1348817Y563578D01*
X1348567Y563411D01*
X1348400Y563161D01*
X1348317Y562828D01*
X1348400Y562536D01*
X1348608Y562244D01*
X1348858Y562078D01*
X1349150Y562036D01*
X1349483Y562119D01*
X1349733Y562328D01*
X1349983Y562703D01*
G01X1337200Y560500D02*
Y564500D01*
X1329800D01*
G01X1340017Y532500D02*
Y535000D01*
X1341058D01*
X1341392Y534875D01*
X1341600Y534708D01*
X1341683Y534375D01*
X1341600Y534042D01*
X1341350Y533833D01*
X1341058Y533708D01*
X1340017D01*
G01X1341058D02*
X1341683Y532500D01*
G01X1343033Y532875D02*
X1343283Y532667D01*
X1343575Y532542D01*
X1343950Y532500D01*
X1344325Y532583D01*
X1344617Y532750D01*
X1344825Y533042D01*
X1344867Y533375D01*
X1344783Y533708D01*
X1344575Y533917D01*
X1344283Y534083D01*
X1343992Y534125D01*
X1343700Y534083D01*
X1343325Y533917D01*
X1343450Y535000D01*
X1344575D01*
G01X1347050D02*
X1346717Y534917D01*
X1346467Y534708D01*
X1346300Y534458D01*
X1346175Y534125D01*
X1346133Y533750D01*
X1346175Y533375D01*
X1346300Y533042D01*
X1346467Y532792D01*
X1346717Y532583D01*
X1347050Y532500D01*
X1347383Y532583D01*
X1347633Y532792D01*
X1347800Y533042D01*
X1347925Y533375D01*
X1347967Y533750D01*
X1347925Y534125D01*
X1347800Y534458D01*
X1347633Y534708D01*
X1347383Y534917D01*
X1347050Y535000D01*
G01X1350150D02*
X1349817Y534917D01*
X1349567Y534708D01*
X1349400Y534458D01*
X1349275Y534125D01*
X1349233Y533750D01*
X1349275Y533375D01*
X1349400Y533042D01*
X1349567Y532792D01*
X1349817Y532583D01*
X1350150Y532500D01*
X1350483Y532583D01*
X1350733Y532792D01*
X1350900Y533042D01*
X1351025Y533375D01*
X1351067Y533750D01*
X1351025Y534125D01*
X1350900Y534458D01*
X1350733Y534708D01*
X1350483Y534917D01*
X1350150Y535000D01*
G01X1327300Y535500D02*
Y531500D01*
X1334700D01*
G01X1332500Y511017D02*
X1330000D01*
Y512058D01*
X1330125Y512392D01*
X1330292Y512600D01*
X1330625Y512683D01*
X1330958Y512600D01*
X1331167Y512350D01*
X1331292Y512058D01*
Y511017D01*
G01Y512058D02*
X1332500Y512683D01*
G01X1332125Y514033D02*
X1332333Y514283D01*
X1332458Y514575D01*
X1332500Y514950D01*
X1332417Y515325D01*
X1332250Y515617D01*
X1331958Y515825D01*
X1331625Y515867D01*
X1331292Y515783D01*
X1331083Y515575D01*
X1330917Y515283D01*
X1330875Y514992D01*
X1330917Y514700D01*
X1331083Y514325D01*
X1330000Y514450D01*
Y515575D01*
G01Y518050D02*
X1330083Y517717D01*
X1330292Y517467D01*
X1330542Y517300D01*
X1330875Y517175D01*
X1331250Y517133D01*
X1331625Y517175D01*
X1331958Y517300D01*
X1332208Y517467D01*
X1332417Y517717D01*
X1332500Y518050D01*
X1332417Y518383D01*
X1332208Y518633D01*
X1331958Y518800D01*
X1331625Y518925D01*
X1331250Y518967D01*
X1330875Y518925D01*
X1330542Y518800D01*
X1330292Y518633D01*
X1330083Y518383D01*
X1330000Y518050D01*
G01X1332500Y521150D02*
X1330000D01*
X1330500Y520650D01*
G01X1332500D02*
Y521650D01*
G01X1320000Y515300D02*
X1324000D01*
Y522700D01*
G01X1305400Y559500D02*
X1305067Y559542D01*
X1304775Y559708D01*
X1304525Y559958D01*
X1304358Y560250D01*
X1304275Y560583D01*
Y560917D01*
X1304358Y561250D01*
X1304525Y561542D01*
X1304775Y561792D01*
X1305067Y561958D01*
X1305400Y562000D01*
X1305733Y561958D01*
X1306025Y561792D01*
X1306275Y561542D01*
X1306442Y561250D01*
X1306525Y560917D01*
Y560583D01*
X1306442Y560250D01*
X1306275Y559958D01*
X1306025Y559708D01*
X1305733Y559542D01*
X1305400Y559500D01*
G01X1305733Y560167D02*
X1306233Y559500D01*
G01X1308500D02*
X1308792Y559542D01*
X1309125Y559667D01*
X1309333Y559875D01*
X1309417Y560167D01*
X1309333Y560458D01*
X1309083Y560708D01*
X1308708Y560833D01*
X1308292D01*
X1308042Y560917D01*
X1307833Y561125D01*
X1307750Y561417D01*
X1307875Y561708D01*
X1308167Y561917D01*
X1308500Y562000D01*
X1308833Y561917D01*
X1309125Y561708D01*
X1309250Y561417D01*
X1309167Y561125D01*
X1308958Y560917D01*
X1308708Y560833D01*
X1308292D01*
X1307917Y560708D01*
X1307667Y560458D01*
X1307583Y560167D01*
X1307667Y559875D01*
X1307875Y559667D01*
X1308208Y559542D01*
X1308500Y559500D01*
G01X1310808Y561583D02*
X1311058Y561833D01*
X1311350Y561958D01*
X1311683Y562000D01*
X1312100Y561917D01*
X1312392Y561708D01*
X1312475Y561458D01*
X1312433Y561208D01*
X1312267Y561000D01*
X1311433Y560583D01*
X1311058Y560292D01*
X1310808Y559875D01*
X1310725Y559500D01*
X1312475D01*
G01X1320500Y557700D02*
X1318700Y555600D01*
X1316500Y557700D01*
G01X1312900Y557800D02*
Y538600D01*
X1324100D01*
Y557800D01*
X1312900D01*
Y557400D01*
G01X1338983Y525500D02*
Y528000D01*
X1339817D01*
X1340150Y527875D01*
X1340400Y527708D01*
X1340608Y527458D01*
X1340775Y527167D01*
X1340817Y526750D01*
X1340775Y526333D01*
X1340608Y526042D01*
X1340400Y525792D01*
X1340150Y525625D01*
X1339817Y525500D01*
X1338983D01*
G01X1343000D02*
Y528000D01*
X1342500Y527500D01*
G01Y525500D02*
X1343500D01*
G01X1346100D02*
X1346392Y525542D01*
X1346725Y525667D01*
X1346933Y525875D01*
X1347017Y526167D01*
X1346933Y526458D01*
X1346683Y526708D01*
X1346308Y526833D01*
X1345892D01*
X1345642Y526917D01*
X1345433Y527125D01*
X1345350Y527417D01*
X1345475Y527708D01*
X1345767Y527917D01*
X1346100Y528000D01*
X1346433Y527917D01*
X1346725Y527708D01*
X1346850Y527417D01*
X1346767Y527125D01*
X1346558Y526917D01*
X1346308Y526833D01*
X1345892D01*
X1345517Y526708D01*
X1345267Y526458D01*
X1345183Y526167D01*
X1345267Y525875D01*
X1345475Y525667D01*
X1345808Y525542D01*
X1346100Y525500D01*
G01X1336500Y523500D02*
X1320400D01*
G01X1336500Y530500D02*
Y523500D01*
G01X1320400Y530500D02*
X1336500D01*
G01X1320400Y523500D02*
Y530500D01*
G01X1298500Y511900D02*
X1298458Y511567D01*
X1298292Y511275D01*
X1298042Y511025D01*
X1297750Y510858D01*
X1297417Y510775D01*
X1297083D01*
X1296750Y510858D01*
X1296458Y511025D01*
X1296208Y511275D01*
X1296042Y511567D01*
X1296000Y511900D01*
X1296042Y512233D01*
X1296208Y512525D01*
X1296458Y512775D01*
X1296750Y512942D01*
X1297083Y513025D01*
X1297417D01*
X1297750Y512942D01*
X1298042Y512775D01*
X1298292Y512525D01*
X1298458Y512233D01*
X1298500Y511900D01*
G01X1297833Y512233D02*
X1298500Y512733D01*
G01Y515000D02*
X1298458Y515292D01*
X1298333Y515625D01*
X1298125Y515833D01*
X1297833Y515917D01*
X1297542Y515833D01*
X1297292Y515583D01*
X1297167Y515208D01*
Y514792D01*
X1297083Y514542D01*
X1296875Y514333D01*
X1296583Y514250D01*
X1296292Y514375D01*
X1296083Y514667D01*
X1296000Y515000D01*
X1296083Y515333D01*
X1296292Y515625D01*
X1296583Y515750D01*
X1296875Y515667D01*
X1297083Y515458D01*
X1297167Y515208D01*
Y514792D01*
X1297292Y514417D01*
X1297542Y514167D01*
X1297833Y514083D01*
X1298125Y514167D01*
X1298333Y514375D01*
X1298458Y514708D01*
X1298500Y515000D01*
G01X1298000Y517183D02*
X1298292Y517433D01*
X1298458Y517767D01*
X1298500Y518142D01*
X1298458Y518475D01*
X1298250Y518808D01*
X1298000Y519017D01*
X1297750Y519058D01*
X1297458Y518975D01*
X1297250Y518683D01*
X1297167Y518392D01*
Y518017D01*
G01Y518392D02*
X1297042Y518642D01*
X1296833Y518850D01*
X1296583Y518933D01*
X1296333Y518850D01*
X1296125Y518642D01*
X1296000Y518267D01*
X1296042Y517892D01*
X1296208Y517517D01*
G01X1300800Y522700D02*
Y511300D01*
G01X1314200Y522700D02*
X1300800D01*
G01X1314200Y511300D02*
Y522700D01*
G01X1300800Y511300D02*
X1314200D01*
G01X1300017Y570000D02*
Y572500D01*
X1301058D01*
X1301392Y572375D01*
X1301600Y572208D01*
X1301683Y571875D01*
X1301600Y571542D01*
X1301350Y571333D01*
X1301058Y571208D01*
X1300017D01*
G01X1301058D02*
X1301683Y570000D01*
G01X1304450D02*
Y572500D01*
X1302908Y570708D01*
X1304992D01*
G01X1307050Y570000D02*
X1307342Y570042D01*
X1307675Y570167D01*
X1307883Y570375D01*
X1307967Y570667D01*
X1307883Y570958D01*
X1307633Y571208D01*
X1307258Y571333D01*
X1306842D01*
X1306592Y571417D01*
X1306383Y571625D01*
X1306300Y571917D01*
X1306425Y572208D01*
X1306717Y572417D01*
X1307050Y572500D01*
X1307383Y572417D01*
X1307675Y572208D01*
X1307800Y571917D01*
X1307717Y571625D01*
X1307508Y571417D01*
X1307258Y571333D01*
X1306842D01*
X1306467Y571208D01*
X1306217Y570958D01*
X1306133Y570667D01*
X1306217Y570375D01*
X1306425Y570167D01*
X1306758Y570042D01*
X1307050Y570000D01*
G01X1309233Y570500D02*
X1309483Y570208D01*
X1309817Y570042D01*
X1310192Y570000D01*
X1310525Y570042D01*
X1310858Y570250D01*
X1311067Y570500D01*
X1311108Y570750D01*
X1311025Y571042D01*
X1310733Y571250D01*
X1310442Y571333D01*
X1310067D01*
G01X1310442D02*
X1310692Y571458D01*
X1310900Y571667D01*
X1310983Y571917D01*
X1310900Y572167D01*
X1310692Y572375D01*
X1310317Y572500D01*
X1309942Y572458D01*
X1309567Y572292D01*
G01X1269275Y661000D02*
Y663500D01*
G01X1271025D02*
Y661000D01*
G01Y662250D02*
X1269275D01*
G01X1272333Y661000D02*
Y663500D01*
X1273167D01*
X1273500Y663375D01*
X1273750Y663208D01*
X1273958Y662958D01*
X1274125Y662667D01*
X1274167Y662250D01*
X1274125Y661833D01*
X1273958Y661542D01*
X1273750Y661292D01*
X1273500Y661125D01*
X1273167Y661000D01*
X1272333D01*
G01X1275433D02*
Y663500D01*
X1276267D01*
X1276600Y663375D01*
X1276850Y663208D01*
X1277058Y662958D01*
X1277225Y662667D01*
X1277267Y662250D01*
X1277225Y661833D01*
X1277058Y661542D01*
X1276850Y661292D01*
X1276600Y661125D01*
X1276267Y661000D01*
X1275433D01*
G01X1278575Y661333D02*
X1278908Y661125D01*
X1279283Y661000D01*
X1279617D01*
X1279950Y661125D01*
X1280200Y661333D01*
X1280325Y661625D01*
X1280242Y661917D01*
X1280033Y662167D01*
X1279658Y662333D01*
X1279158Y662417D01*
X1278867Y662583D01*
X1278742Y662875D01*
X1278825Y663167D01*
X1279033Y663375D01*
X1279325Y663500D01*
X1279617D01*
X1279908Y663417D01*
X1280158Y663208D01*
G01X1281508Y661000D02*
X1282550Y663500D01*
X1283592Y661000D01*
G01X1283217Y661875D02*
X1281883D01*
G01X1284775Y661333D02*
X1285108Y661125D01*
X1285483Y661000D01*
X1285817D01*
X1286150Y661125D01*
X1286400Y661333D01*
X1286525Y661625D01*
X1286442Y661917D01*
X1286233Y662167D01*
X1285858Y662333D01*
X1285358Y662417D01*
X1285067Y662583D01*
X1284942Y662875D01*
X1285025Y663167D01*
X1285233Y663375D01*
X1285525Y663500D01*
X1285817D01*
X1286108Y663417D01*
X1286358Y663208D01*
G01X1288750Y661000D02*
Y663500D01*
X1288250Y663000D01*
G01Y661000D02*
X1289250D01*
G01X1291850D02*
X1292142Y661042D01*
X1292475Y661167D01*
X1292683Y661375D01*
X1292767Y661667D01*
X1292683Y661958D01*
X1292433Y662208D01*
X1292058Y662333D01*
X1291642D01*
X1291392Y662417D01*
X1291183Y662625D01*
X1291100Y662917D01*
X1291225Y663208D01*
X1291517Y663417D01*
X1291850Y663500D01*
X1292183Y663417D01*
X1292475Y663208D01*
X1292600Y662917D01*
X1292517Y662625D01*
X1292308Y662417D01*
X1292058Y662333D01*
X1291642D01*
X1291267Y662208D01*
X1291017Y661958D01*
X1290933Y661667D01*
X1291017Y661375D01*
X1291225Y661167D01*
X1291558Y661042D01*
X1291850Y661000D01*
G01X1265147Y584067D02*
X1265022Y583817D01*
X1264939Y583525D01*
Y583192D01*
X1265064Y582817D01*
X1265272Y582525D01*
X1265522Y582317D01*
X1265939Y582150D01*
X1266314Y582108D01*
X1266689Y582192D01*
X1266939Y582317D01*
X1267189Y582567D01*
X1267356Y582858D01*
X1267439Y583150D01*
Y583442D01*
X1267356Y583733D01*
X1267231Y583983D01*
X1267064Y584192D01*
G01X1265356Y585458D02*
X1265106Y585708D01*
X1264981Y586000D01*
X1264939Y586333D01*
X1265022Y586750D01*
X1265231Y587042D01*
X1265481Y587125D01*
X1265731Y587083D01*
X1265939Y586917D01*
X1266356Y586083D01*
X1266647Y585708D01*
X1267064Y585458D01*
X1267439Y585375D01*
Y587125D01*
G01X1266397Y588558D02*
X1266106Y588850D01*
X1265939Y589100D01*
X1265856Y589433D01*
X1265939Y589725D01*
X1266106Y589933D01*
X1266356Y590100D01*
X1266647Y590142D01*
X1266897Y590100D01*
X1267147Y589933D01*
X1267356Y589683D01*
X1267439Y589392D01*
X1267356Y589058D01*
X1267106Y588767D01*
X1266731Y588600D01*
X1266314Y588558D01*
X1265772Y588642D01*
X1265481Y588767D01*
X1265189Y588975D01*
X1264981Y589267D01*
X1264939Y589558D01*
X1265022Y589850D01*
X1265231Y590058D01*
G01X1267147Y591742D02*
X1267356Y592033D01*
X1267439Y592367D01*
X1267356Y592700D01*
X1267106Y592992D01*
X1266731Y593200D01*
X1266356Y593283D01*
X1265897D01*
X1265522Y593200D01*
X1265189Y592992D01*
X1265022Y592742D01*
X1264939Y592450D01*
X1265022Y592117D01*
X1265189Y591867D01*
X1265439Y591700D01*
X1265772Y591617D01*
X1266064Y591700D01*
X1266356Y591908D01*
X1266522Y592158D01*
X1266564Y592450D01*
X1266481Y592783D01*
X1266272Y593033D01*
X1265897Y593283D01*
G01X1263439Y582317D02*
X1260939D01*
Y583358D01*
X1261064Y583692D01*
X1261231Y583900D01*
X1261564Y583983D01*
X1261897Y583900D01*
X1262106Y583650D01*
X1262231Y583358D01*
Y582317D01*
G01Y583358D02*
X1263439Y583983D01*
G01Y586750D02*
X1260939D01*
X1262731Y585208D01*
Y587292D01*
G01X1263439Y589350D02*
X1263397Y589642D01*
X1263272Y589975D01*
X1263064Y590183D01*
X1262772Y590267D01*
X1262481Y590183D01*
X1262231Y589933D01*
X1262106Y589558D01*
Y589142D01*
X1262022Y588892D01*
X1261814Y588683D01*
X1261522Y588600D01*
X1261231Y588725D01*
X1261022Y589017D01*
X1260939Y589350D01*
X1261022Y589683D01*
X1261231Y589975D01*
X1261522Y590100D01*
X1261814Y590017D01*
X1262022Y589808D01*
X1262106Y589558D01*
Y589142D01*
X1262231Y588767D01*
X1262481Y588517D01*
X1262772Y588433D01*
X1263064Y588517D01*
X1263272Y588725D01*
X1263397Y589058D01*
X1263439Y589350D01*
G01Y592950D02*
X1260939D01*
X1262731Y591408D01*
Y593492D01*
G01X1260600Y573600D02*
X1264600D01*
Y581000D01*
G01X1297208Y610267D02*
X1297083Y610017D01*
X1297000Y609725D01*
Y609392D01*
X1297125Y609017D01*
X1297333Y608725D01*
X1297583Y608517D01*
X1298000Y608350D01*
X1298375Y608308D01*
X1298750Y608392D01*
X1299000Y608517D01*
X1299250Y608767D01*
X1299417Y609058D01*
X1299500Y609350D01*
Y609642D01*
X1299417Y609933D01*
X1299292Y610183D01*
X1299125Y610392D01*
G01X1297417Y611658D02*
X1297167Y611908D01*
X1297042Y612200D01*
X1297000Y612533D01*
X1297083Y612950D01*
X1297292Y613242D01*
X1297542Y613325D01*
X1297792Y613283D01*
X1298000Y613117D01*
X1298417Y612283D01*
X1298708Y611908D01*
X1299125Y611658D01*
X1299500Y611575D01*
Y613325D01*
G01X1298458Y614758D02*
X1298167Y615050D01*
X1298000Y615300D01*
X1297917Y615633D01*
X1298000Y615925D01*
X1298167Y616133D01*
X1298417Y616300D01*
X1298708Y616342D01*
X1298958Y616300D01*
X1299208Y616133D01*
X1299417Y615883D01*
X1299500Y615592D01*
X1299417Y615258D01*
X1299167Y614967D01*
X1298792Y614800D01*
X1298375Y614758D01*
X1297833Y614842D01*
X1297542Y614967D01*
X1297250Y615175D01*
X1297042Y615467D01*
X1297000Y615758D01*
X1297083Y616050D01*
X1297292Y616258D01*
G01X1299500Y619150D02*
X1297000D01*
X1298792Y617608D01*
Y619692D01*
G01X1296708Y642767D02*
X1296583Y642517D01*
X1296500Y642225D01*
Y641892D01*
X1296625Y641517D01*
X1296833Y641225D01*
X1297083Y641017D01*
X1297500Y640850D01*
X1297875Y640808D01*
X1298250Y640892D01*
X1298500Y641017D01*
X1298750Y641267D01*
X1298917Y641558D01*
X1299000Y641850D01*
Y642142D01*
X1298917Y642433D01*
X1298792Y642683D01*
X1298625Y642892D01*
G01X1296917Y644158D02*
X1296667Y644408D01*
X1296542Y644700D01*
X1296500Y645033D01*
X1296583Y645450D01*
X1296792Y645742D01*
X1297042Y645825D01*
X1297292Y645783D01*
X1297500Y645617D01*
X1297917Y644783D01*
X1298208Y644408D01*
X1298625Y644158D01*
X1299000Y644075D01*
Y645825D01*
G01Y647967D02*
X1298458Y648050D01*
X1298000Y648175D01*
X1297583Y648342D01*
X1297125Y648550D01*
X1296500Y648883D01*
Y647217D01*
G01X1299000Y651150D02*
X1296500D01*
X1297000Y650650D01*
G01X1299000D02*
Y651650D01*
G01X1251300Y615000D02*
Y612500D01*
G01X1250342Y615000D02*
X1252258D01*
G01X1253567Y612500D02*
Y615000D01*
X1254567D01*
X1254900Y614875D01*
X1255150Y614583D01*
X1255233Y614250D01*
X1255150Y613917D01*
X1254942Y613667D01*
X1254567Y613542D01*
X1253567D01*
G01X1257500Y612500D02*
Y615000D01*
X1257000Y614500D01*
G01Y612500D02*
X1258000D01*
G01X1260600D02*
Y615000D01*
X1260100Y614500D01*
G01Y612500D02*
X1261100D01*
G01X1263700D02*
Y615000D01*
X1263200Y614500D01*
G01Y612500D02*
X1264200D01*
G01X1329900Y598000D02*
X1329567Y598042D01*
X1329275Y598208D01*
X1329025Y598458D01*
X1328858Y598750D01*
X1328775Y599083D01*
Y599417D01*
X1328858Y599750D01*
X1329025Y600042D01*
X1329275Y600292D01*
X1329567Y600458D01*
X1329900Y600500D01*
X1330233Y600458D01*
X1330525Y600292D01*
X1330775Y600042D01*
X1330942Y599750D01*
X1331025Y599417D01*
Y599083D01*
X1330942Y598750D01*
X1330775Y598458D01*
X1330525Y598208D01*
X1330233Y598042D01*
X1329900Y598000D01*
G01X1330233Y598667D02*
X1330733Y598000D01*
G01X1333000D02*
X1333292Y598042D01*
X1333625Y598167D01*
X1333833Y598375D01*
X1333917Y598667D01*
X1333833Y598958D01*
X1333583Y599208D01*
X1333208Y599333D01*
X1332792D01*
X1332542Y599417D01*
X1332333Y599625D01*
X1332250Y599917D01*
X1332375Y600208D01*
X1332667Y600417D01*
X1333000Y600500D01*
X1333333Y600417D01*
X1333625Y600208D01*
X1333750Y599917D01*
X1333667Y599625D01*
X1333458Y599417D01*
X1333208Y599333D01*
X1332792D01*
X1332417Y599208D01*
X1332167Y598958D01*
X1332083Y598667D01*
X1332167Y598375D01*
X1332375Y598167D01*
X1332708Y598042D01*
X1333000Y598000D01*
G01X1336600D02*
Y600500D01*
X1335058Y598708D01*
X1337142D01*
G01X1315300Y585000D02*
X1317400Y583200D01*
X1315300Y581000D01*
G01X1315200Y577400D02*
X1334400D01*
Y588600D01*
X1315200D01*
Y577400D01*
X1315600D01*
G01X1253800Y590017D02*
X1251300D01*
Y591058D01*
X1251425Y591392D01*
X1251592Y591600D01*
X1251925Y591683D01*
X1252258Y591600D01*
X1252467Y591350D01*
X1252592Y591058D01*
Y590017D01*
G01Y591058D02*
X1253800Y591683D01*
G01Y594450D02*
X1251300D01*
X1253092Y592908D01*
Y594992D01*
G01X1253800Y597050D02*
X1253758Y597342D01*
X1253633Y597675D01*
X1253425Y597883D01*
X1253133Y597967D01*
X1252842Y597883D01*
X1252592Y597633D01*
X1252467Y597258D01*
Y596842D01*
X1252383Y596592D01*
X1252175Y596383D01*
X1251883Y596300D01*
X1251592Y596425D01*
X1251383Y596717D01*
X1251300Y597050D01*
X1251383Y597383D01*
X1251592Y597675D01*
X1251883Y597800D01*
X1252175Y597717D01*
X1252383Y597508D01*
X1252467Y597258D01*
Y596842D01*
X1252592Y596467D01*
X1252842Y596217D01*
X1253133Y596133D01*
X1253425Y596217D01*
X1253633Y596425D01*
X1253758Y596758D01*
X1253800Y597050D01*
G01Y600150D02*
X1253758Y600442D01*
X1253633Y600775D01*
X1253425Y600983D01*
X1253133Y601067D01*
X1252842Y600983D01*
X1252592Y600733D01*
X1252467Y600358D01*
Y599942D01*
X1252383Y599692D01*
X1252175Y599483D01*
X1251883Y599400D01*
X1251592Y599525D01*
X1251383Y599817D01*
X1251300Y600150D01*
X1251383Y600483D01*
X1251592Y600775D01*
X1251883Y600900D01*
X1252175Y600817D01*
X1252383Y600608D01*
X1252467Y600358D01*
Y599942D01*
X1252592Y599567D01*
X1252842Y599317D01*
X1253133Y599233D01*
X1253425Y599317D01*
X1253633Y599525D01*
X1253758Y599858D01*
X1253800Y600150D01*
G01X1301208Y609267D02*
X1301083Y609017D01*
X1301000Y608725D01*
Y608392D01*
X1301125Y608017D01*
X1301333Y607725D01*
X1301583Y607517D01*
X1302000Y607350D01*
X1302375Y607308D01*
X1302750Y607392D01*
X1303000Y607517D01*
X1303250Y607767D01*
X1303417Y608058D01*
X1303500Y608350D01*
Y608642D01*
X1303417Y608933D01*
X1303292Y609183D01*
X1303125Y609392D01*
G01X1301417Y610658D02*
X1301167Y610908D01*
X1301042Y611200D01*
X1301000Y611533D01*
X1301083Y611950D01*
X1301292Y612242D01*
X1301542Y612325D01*
X1301792Y612283D01*
X1302000Y612117D01*
X1302417Y611283D01*
X1302708Y610908D01*
X1303125Y610658D01*
X1303500Y610575D01*
Y612325D01*
G01X1302458Y613758D02*
X1302167Y614050D01*
X1302000Y614300D01*
X1301917Y614633D01*
X1302000Y614925D01*
X1302167Y615133D01*
X1302417Y615300D01*
X1302708Y615342D01*
X1302958Y615300D01*
X1303208Y615133D01*
X1303417Y614883D01*
X1303500Y614592D01*
X1303417Y614258D01*
X1303167Y613967D01*
X1302792Y613800D01*
X1302375Y613758D01*
X1301833Y613842D01*
X1301542Y613967D01*
X1301250Y614175D01*
X1301042Y614467D01*
X1301000Y614758D01*
X1301083Y615050D01*
X1301292Y615258D01*
G01X1303125Y616733D02*
X1303333Y616983D01*
X1303458Y617275D01*
X1303500Y617650D01*
X1303417Y618025D01*
X1303250Y618317D01*
X1302958Y618525D01*
X1302625Y618567D01*
X1302292Y618483D01*
X1302083Y618275D01*
X1301917Y617983D01*
X1301875Y617692D01*
X1301917Y617400D01*
X1302083Y617025D01*
X1301000Y617150D01*
Y618275D01*
G01X1304500Y589200D02*
Y594700D01*
G01X1312500Y589200D02*
X1304500D01*
G01X1312500Y594700D02*
Y589200D01*
G01Y606800D02*
Y601300D01*
G01X1304500Y606800D02*
X1312500D01*
G01X1304500Y601300D02*
Y606800D01*
G01X1313800Y583000D02*
Y575000D01*
X1296200D01*
Y583000D01*
X1313800D01*
G01X1313217Y618600D02*
Y621100D01*
X1314258D01*
X1314592Y620975D01*
X1314800Y620808D01*
X1314883Y620475D01*
X1314800Y620142D01*
X1314550Y619933D01*
X1314258Y619808D01*
X1313217D01*
G01X1314258D02*
X1314883Y618600D01*
G01X1317650D02*
Y621100D01*
X1316108Y619308D01*
X1318192D01*
G01X1320250Y618600D02*
X1320542Y618642D01*
X1320875Y618767D01*
X1321083Y618975D01*
X1321167Y619267D01*
X1321083Y619558D01*
X1320833Y619808D01*
X1320458Y619933D01*
X1320042D01*
X1319792Y620017D01*
X1319583Y620225D01*
X1319500Y620517D01*
X1319625Y620808D01*
X1319917Y621017D01*
X1320250Y621100D01*
X1320583Y621017D01*
X1320875Y620808D01*
X1321000Y620517D01*
X1320917Y620225D01*
X1320708Y620017D01*
X1320458Y619933D01*
X1320042D01*
X1319667Y619808D01*
X1319417Y619558D01*
X1319333Y619267D01*
X1319417Y618975D01*
X1319625Y618767D01*
X1319958Y618642D01*
X1320250Y618600D01*
G01X1322433Y618975D02*
X1322683Y618767D01*
X1322975Y618642D01*
X1323350Y618600D01*
X1323725Y618683D01*
X1324017Y618850D01*
X1324225Y619142D01*
X1324267Y619475D01*
X1324183Y619808D01*
X1323975Y620017D01*
X1323683Y620183D01*
X1323392Y620225D01*
X1323100Y620183D01*
X1322725Y620017D01*
X1322850Y621100D01*
X1323975D01*
G01X1322000Y616600D02*
Y608600D01*
X1304400D01*
Y616600D01*
X1322000D01*
G01X1303547Y642767D02*
X1303422Y642517D01*
X1303339Y642225D01*
Y641892D01*
X1303464Y641517D01*
X1303672Y641225D01*
X1303922Y641017D01*
X1304339Y640850D01*
X1304714Y640808D01*
X1305089Y640892D01*
X1305339Y641017D01*
X1305589Y641267D01*
X1305756Y641558D01*
X1305839Y641850D01*
Y642142D01*
X1305756Y642433D01*
X1305631Y642683D01*
X1305464Y642892D01*
G01X1303756Y644158D02*
X1303506Y644408D01*
X1303381Y644700D01*
X1303339Y645033D01*
X1303422Y645450D01*
X1303631Y645742D01*
X1303881Y645825D01*
X1304131Y645783D01*
X1304339Y645617D01*
X1304756Y644783D01*
X1305047Y644408D01*
X1305464Y644158D01*
X1305839Y644075D01*
Y645825D01*
G01X1304797Y647258D02*
X1304506Y647550D01*
X1304339Y647800D01*
X1304256Y648133D01*
X1304339Y648425D01*
X1304506Y648633D01*
X1304756Y648800D01*
X1305047Y648842D01*
X1305297Y648800D01*
X1305547Y648633D01*
X1305756Y648383D01*
X1305839Y648092D01*
X1305756Y647758D01*
X1305506Y647467D01*
X1305131Y647300D01*
X1304714Y647258D01*
X1304172Y647342D01*
X1303881Y647467D01*
X1303589Y647675D01*
X1303381Y647967D01*
X1303339Y648258D01*
X1303422Y648550D01*
X1303631Y648758D01*
G01X1305839Y651150D02*
X1305797Y651442D01*
X1305672Y651775D01*
X1305464Y651983D01*
X1305172Y652067D01*
X1304881Y651983D01*
X1304631Y651733D01*
X1304506Y651358D01*
Y650942D01*
X1304422Y650692D01*
X1304214Y650483D01*
X1303922Y650400D01*
X1303631Y650525D01*
X1303422Y650817D01*
X1303339Y651150D01*
X1303422Y651483D01*
X1303631Y651775D01*
X1303922Y651900D01*
X1304214Y651817D01*
X1304422Y651608D01*
X1304506Y651358D01*
Y650942D01*
X1304631Y650567D01*
X1304881Y650317D01*
X1305172Y650233D01*
X1305464Y650317D01*
X1305672Y650525D01*
X1305797Y650858D01*
X1305839Y651150D01*
G01X1308708Y642267D02*
X1308583Y642017D01*
X1308500Y641725D01*
Y641392D01*
X1308625Y641017D01*
X1308833Y640725D01*
X1309083Y640517D01*
X1309500Y640350D01*
X1309875Y640308D01*
X1310250Y640392D01*
X1310500Y640517D01*
X1310750Y640767D01*
X1310917Y641058D01*
X1311000Y641350D01*
Y641642D01*
X1310917Y641933D01*
X1310792Y642183D01*
X1310625Y642392D01*
G01X1308917Y643658D02*
X1308667Y643908D01*
X1308542Y644200D01*
X1308500Y644533D01*
X1308583Y644950D01*
X1308792Y645242D01*
X1309042Y645325D01*
X1309292Y645283D01*
X1309500Y645117D01*
X1309917Y644283D01*
X1310208Y643908D01*
X1310625Y643658D01*
X1311000Y643575D01*
Y645325D01*
G01Y647467D02*
X1310458Y647550D01*
X1310000Y647675D01*
X1309583Y647842D01*
X1309125Y648050D01*
X1308500Y648383D01*
Y646717D01*
G01Y650650D02*
X1308583Y650317D01*
X1308792Y650067D01*
X1309042Y649900D01*
X1309375Y649775D01*
X1309750Y649733D01*
X1310125Y649775D01*
X1310458Y649900D01*
X1310708Y650067D01*
X1310917Y650317D01*
X1311000Y650650D01*
X1310917Y650983D01*
X1310708Y651233D01*
X1310458Y651400D01*
X1310125Y651525D01*
X1309750Y651567D01*
X1309375Y651525D01*
X1309042Y651400D01*
X1308792Y651233D01*
X1308583Y650983D01*
X1308500Y650650D01*
G01X1324017Y835000D02*
Y837500D01*
X1325058D01*
X1325392Y837375D01*
X1325600Y837208D01*
X1325683Y836875D01*
X1325600Y836542D01*
X1325350Y836333D01*
X1325058Y836208D01*
X1324017D01*
G01X1325058D02*
X1325683Y835000D01*
G01X1327158Y837083D02*
X1327408Y837333D01*
X1327700Y837458D01*
X1328033Y837500D01*
X1328450Y837417D01*
X1328742Y837208D01*
X1328825Y836958D01*
X1328783Y836708D01*
X1328617Y836500D01*
X1327783Y836083D01*
X1327408Y835792D01*
X1327158Y835375D01*
X1327075Y835000D01*
X1328825D01*
G01X1330258Y836042D02*
X1330550Y836333D01*
X1330800Y836500D01*
X1331133Y836583D01*
X1331425Y836500D01*
X1331633Y836333D01*
X1331800Y836083D01*
X1331842Y835792D01*
X1331800Y835542D01*
X1331633Y835292D01*
X1331383Y835083D01*
X1331092Y835000D01*
X1330758Y835083D01*
X1330467Y835333D01*
X1330300Y835708D01*
X1330258Y836125D01*
X1330342Y836667D01*
X1330467Y836958D01*
X1330675Y837250D01*
X1330967Y837458D01*
X1331258Y837500D01*
X1331550Y837417D01*
X1331758Y837208D01*
G01X1334150Y835000D02*
Y837500D01*
X1333650Y837000D01*
G01Y835000D02*
X1334650D01*
G01X1343274Y834182D02*
Y838182D01*
X1335874D01*
G01X1333550Y856200D02*
X1333217Y856242D01*
X1332925Y856408D01*
X1332675Y856658D01*
X1332508Y856950D01*
X1332425Y857283D01*
Y857617D01*
X1332508Y857950D01*
X1332675Y858242D01*
X1332925Y858492D01*
X1333217Y858658D01*
X1333550Y858700D01*
X1333883Y858658D01*
X1334175Y858492D01*
X1334425Y858242D01*
X1334592Y857950D01*
X1334675Y857617D01*
Y857283D01*
X1334592Y856950D01*
X1334425Y856658D01*
X1334175Y856408D01*
X1333883Y856242D01*
X1333550Y856200D01*
G01X1333883Y856867D02*
X1334383Y856200D01*
G01X1335858Y858283D02*
X1336108Y858533D01*
X1336400Y858658D01*
X1336733Y858700D01*
X1337150Y858617D01*
X1337442Y858408D01*
X1337525Y858158D01*
X1337483Y857908D01*
X1337317Y857700D01*
X1336483Y857283D01*
X1336108Y856992D01*
X1335858Y856575D01*
X1335775Y856200D01*
X1337525D01*
G01X1338833Y856575D02*
X1339083Y856367D01*
X1339375Y856242D01*
X1339750Y856200D01*
X1340125Y856283D01*
X1340417Y856450D01*
X1340625Y856742D01*
X1340667Y857075D01*
X1340583Y857408D01*
X1340375Y857617D01*
X1340083Y857783D01*
X1339792Y857825D01*
X1339500Y857783D01*
X1339125Y857617D01*
X1339250Y858700D01*
X1340375D01*
G01X1342850D02*
X1342517Y858617D01*
X1342267Y858408D01*
X1342100Y858158D01*
X1341975Y857825D01*
X1341933Y857450D01*
X1341975Y857075D01*
X1342100Y856742D01*
X1342267Y856492D01*
X1342517Y856283D01*
X1342850Y856200D01*
X1343183Y856283D01*
X1343433Y856492D01*
X1343600Y856742D01*
X1343725Y857075D01*
X1343767Y857450D01*
X1343725Y857825D01*
X1343600Y858158D01*
X1343433Y858408D01*
X1343183Y858617D01*
X1342850Y858700D01*
G01X1330574Y839407D02*
X1344574D01*
G01X1330574Y852407D02*
Y839407D01*
G01X1344574Y852407D02*
X1330574D01*
G01X1264793Y1012831D02*
X1269843D01*
Y1111531D01*
X1294493D01*
Y927131D01*
X1269843D01*
Y985831D01*
X1264793D01*
Y1012831D01*
G01X1258267Y951292D02*
X1258017Y951417D01*
X1257725Y951500D01*
X1257392D01*
X1257017Y951375D01*
X1256725Y951167D01*
X1256517Y950917D01*
X1256350Y950500D01*
X1256308Y950125D01*
X1256392Y949750D01*
X1256517Y949500D01*
X1256767Y949250D01*
X1257058Y949083D01*
X1257350Y949000D01*
X1257642D01*
X1257933Y949083D01*
X1258183Y949208D01*
X1258392Y949375D01*
G01X1260450Y949000D02*
Y951500D01*
X1259950Y951000D01*
G01Y949000D02*
X1260950D01*
G01X1263550Y951500D02*
X1263217Y951417D01*
X1262967Y951208D01*
X1262800Y950958D01*
X1262675Y950625D01*
X1262633Y950250D01*
X1262675Y949875D01*
X1262800Y949542D01*
X1262967Y949292D01*
X1263217Y949083D01*
X1263550Y949000D01*
X1263883Y949083D01*
X1264133Y949292D01*
X1264300Y949542D01*
X1264425Y949875D01*
X1264467Y950250D01*
X1264425Y950625D01*
X1264300Y950958D01*
X1264133Y951208D01*
X1263883Y951417D01*
X1263550Y951500D01*
G01X1266567Y949000D02*
X1266650Y949542D01*
X1266775Y950000D01*
X1266942Y950417D01*
X1267150Y950875D01*
X1267483Y951500D01*
X1265817D01*
G01X1304500Y950017D02*
X1302000D01*
Y951058D01*
X1302125Y951392D01*
X1302292Y951600D01*
X1302625Y951683D01*
X1302958Y951600D01*
X1303167Y951350D01*
X1303292Y951058D01*
Y950017D01*
G01Y951058D02*
X1304500Y951683D01*
G01X1302417Y953158D02*
X1302167Y953408D01*
X1302042Y953700D01*
X1302000Y954033D01*
X1302083Y954450D01*
X1302292Y954742D01*
X1302542Y954825D01*
X1302792Y954783D01*
X1303000Y954617D01*
X1303417Y953783D01*
X1303708Y953408D01*
X1304125Y953158D01*
X1304500Y953075D01*
Y954825D01*
G01X1303458Y956258D02*
X1303167Y956550D01*
X1303000Y956800D01*
X1302917Y957133D01*
X1303000Y957425D01*
X1303167Y957633D01*
X1303417Y957800D01*
X1303708Y957842D01*
X1303958Y957800D01*
X1304208Y957633D01*
X1304417Y957383D01*
X1304500Y957092D01*
X1304417Y956758D01*
X1304167Y956467D01*
X1303792Y956300D01*
X1303375Y956258D01*
X1302833Y956342D01*
X1302542Y956467D01*
X1302250Y956675D01*
X1302042Y956967D01*
X1302000Y957258D01*
X1302083Y957550D01*
X1302292Y957758D01*
G01X1302000Y960150D02*
X1302083Y959817D01*
X1302292Y959567D01*
X1302542Y959400D01*
X1302875Y959275D01*
X1303250Y959233D01*
X1303625Y959275D01*
X1303958Y959400D01*
X1304208Y959567D01*
X1304417Y959817D01*
X1304500Y960150D01*
X1304417Y960483D01*
X1304208Y960733D01*
X1303958Y960900D01*
X1303625Y961025D01*
X1303250Y961067D01*
X1302875Y961025D01*
X1302542Y960900D01*
X1302292Y960733D01*
X1302083Y960483D01*
X1302000Y960150D01*
G01X1330000Y950517D02*
X1327500D01*
Y951558D01*
X1327625Y951892D01*
X1327792Y952100D01*
X1328125Y952183D01*
X1328458Y952100D01*
X1328667Y951850D01*
X1328792Y951558D01*
Y950517D01*
G01Y951558D02*
X1330000Y952183D01*
G01X1327917Y953658D02*
X1327667Y953908D01*
X1327542Y954200D01*
X1327500Y954533D01*
X1327583Y954950D01*
X1327792Y955242D01*
X1328042Y955325D01*
X1328292Y955283D01*
X1328500Y955117D01*
X1328917Y954283D01*
X1329208Y953908D01*
X1329625Y953658D01*
X1330000Y953575D01*
Y955325D01*
G01X1328958Y956758D02*
X1328667Y957050D01*
X1328500Y957300D01*
X1328417Y957633D01*
X1328500Y957925D01*
X1328667Y958133D01*
X1328917Y958300D01*
X1329208Y958342D01*
X1329458Y958300D01*
X1329708Y958133D01*
X1329917Y957883D01*
X1330000Y957592D01*
X1329917Y957258D01*
X1329667Y956967D01*
X1329292Y956800D01*
X1328875Y956758D01*
X1328333Y956842D01*
X1328042Y956967D01*
X1327750Y957175D01*
X1327542Y957467D01*
X1327500Y957758D01*
X1327583Y958050D01*
X1327792Y958258D01*
G01X1327917Y959858D02*
X1327667Y960108D01*
X1327542Y960400D01*
X1327500Y960733D01*
X1327583Y961150D01*
X1327792Y961442D01*
X1328042Y961525D01*
X1328292Y961483D01*
X1328500Y961317D01*
X1328917Y960483D01*
X1329208Y960108D01*
X1329625Y959858D01*
X1330000Y959775D01*
Y961525D01*
G01X1300500Y950017D02*
X1298000D01*
Y951058D01*
X1298125Y951392D01*
X1298292Y951600D01*
X1298625Y951683D01*
X1298958Y951600D01*
X1299167Y951350D01*
X1299292Y951058D01*
Y950017D01*
G01Y951058D02*
X1300500Y951683D01*
G01X1298417Y953158D02*
X1298167Y953408D01*
X1298042Y953700D01*
X1298000Y954033D01*
X1298083Y954450D01*
X1298292Y954742D01*
X1298542Y954825D01*
X1298792Y954783D01*
X1299000Y954617D01*
X1299417Y953783D01*
X1299708Y953408D01*
X1300125Y953158D01*
X1300500Y953075D01*
Y954825D01*
G01X1299458Y956258D02*
X1299167Y956550D01*
X1299000Y956800D01*
X1298917Y957133D01*
X1299000Y957425D01*
X1299167Y957633D01*
X1299417Y957800D01*
X1299708Y957842D01*
X1299958Y957800D01*
X1300208Y957633D01*
X1300417Y957383D01*
X1300500Y957092D01*
X1300417Y956758D01*
X1300167Y956467D01*
X1299792Y956300D01*
X1299375Y956258D01*
X1298833Y956342D01*
X1298542Y956467D01*
X1298250Y956675D01*
X1298042Y956967D01*
X1298000Y957258D01*
X1298083Y957550D01*
X1298292Y957758D01*
G01X1300000Y959233D02*
X1300292Y959483D01*
X1300458Y959817D01*
X1300500Y960192D01*
X1300458Y960525D01*
X1300250Y960858D01*
X1300000Y961067D01*
X1299750Y961108D01*
X1299458Y961025D01*
X1299250Y960733D01*
X1299167Y960442D01*
Y960067D01*
G01Y960442D02*
X1299042Y960692D01*
X1298833Y960900D01*
X1298583Y960983D01*
X1298333Y960900D01*
X1298125Y960692D01*
X1298000Y960317D01*
X1298042Y959942D01*
X1298208Y959567D01*
G01X1258267Y955292D02*
X1258017Y955417D01*
X1257725Y955500D01*
X1257392D01*
X1257017Y955375D01*
X1256725Y955167D01*
X1256517Y954917D01*
X1256350Y954500D01*
X1256308Y954125D01*
X1256392Y953750D01*
X1256517Y953500D01*
X1256767Y953250D01*
X1257058Y953083D01*
X1257350Y953000D01*
X1257642D01*
X1257933Y953083D01*
X1258183Y953208D01*
X1258392Y953375D01*
G01X1260450Y953000D02*
Y955500D01*
X1259950Y955000D01*
G01Y953000D02*
X1260950D01*
G01X1263550Y955500D02*
X1263217Y955417D01*
X1262967Y955208D01*
X1262800Y954958D01*
X1262675Y954625D01*
X1262633Y954250D01*
X1262675Y953875D01*
X1262800Y953542D01*
X1262967Y953292D01*
X1263217Y953083D01*
X1263550Y953000D01*
X1263883Y953083D01*
X1264133Y953292D01*
X1264300Y953542D01*
X1264425Y953875D01*
X1264467Y954250D01*
X1264425Y954625D01*
X1264300Y954958D01*
X1264133Y955208D01*
X1263883Y955417D01*
X1263550Y955500D01*
G01X1265858Y954042D02*
X1266150Y954333D01*
X1266400Y954500D01*
X1266733Y954583D01*
X1267025Y954500D01*
X1267233Y954333D01*
X1267400Y954083D01*
X1267442Y953792D01*
X1267400Y953542D01*
X1267233Y953292D01*
X1266983Y953083D01*
X1266692Y953000D01*
X1266358Y953083D01*
X1266067Y953333D01*
X1265900Y953708D01*
X1265858Y954125D01*
X1265942Y954667D01*
X1266067Y954958D01*
X1266275Y955250D01*
X1266567Y955458D01*
X1266858Y955500D01*
X1267150Y955417D01*
X1267358Y955208D01*
G01X1264947Y1037267D02*
X1264822Y1037017D01*
X1264739Y1036725D01*
Y1036392D01*
X1264864Y1036017D01*
X1265072Y1035725D01*
X1265322Y1035517D01*
X1265739Y1035350D01*
X1266114Y1035308D01*
X1266489Y1035392D01*
X1266739Y1035517D01*
X1266989Y1035767D01*
X1267156Y1036058D01*
X1267239Y1036350D01*
Y1036642D01*
X1267156Y1036933D01*
X1267031Y1037183D01*
X1266864Y1037392D01*
G01X1267239Y1039450D02*
X1264739D01*
X1265239Y1038950D01*
G01X1267239D02*
Y1039950D01*
G01Y1042550D02*
X1264739D01*
X1265239Y1042050D01*
G01X1267239D02*
Y1043050D01*
G01X1266864Y1044733D02*
X1267072Y1044983D01*
X1267197Y1045275D01*
X1267239Y1045650D01*
X1267156Y1046025D01*
X1266989Y1046317D01*
X1266697Y1046525D01*
X1266364Y1046567D01*
X1266031Y1046483D01*
X1265822Y1046275D01*
X1265656Y1045983D01*
X1265614Y1045692D01*
X1265656Y1045400D01*
X1265822Y1045025D01*
X1264739Y1045150D01*
Y1046275D01*
G01X1296708Y988767D02*
X1296583Y988517D01*
X1296500Y988225D01*
Y987892D01*
X1296625Y987517D01*
X1296833Y987225D01*
X1297083Y987017D01*
X1297500Y986850D01*
X1297875Y986808D01*
X1298250Y986892D01*
X1298500Y987017D01*
X1298750Y987267D01*
X1298917Y987558D01*
X1299000Y987850D01*
Y988142D01*
X1298917Y988433D01*
X1298792Y988683D01*
X1298625Y988892D01*
G01X1299000Y990950D02*
X1296500D01*
X1297000Y990450D01*
G01X1299000D02*
Y991450D01*
G01Y994050D02*
X1296500D01*
X1297000Y993550D01*
G01X1299000D02*
Y994550D01*
G01X1297958Y996358D02*
X1297667Y996650D01*
X1297500Y996900D01*
X1297417Y997233D01*
X1297500Y997525D01*
X1297667Y997733D01*
X1297917Y997900D01*
X1298208Y997942D01*
X1298458Y997900D01*
X1298708Y997733D01*
X1298917Y997483D01*
X1299000Y997192D01*
X1298917Y996858D01*
X1298667Y996567D01*
X1298292Y996400D01*
X1297875Y996358D01*
X1297333Y996442D01*
X1297042Y996567D01*
X1296750Y996775D01*
X1296542Y997067D01*
X1296500Y997358D01*
X1296583Y997650D01*
X1296792Y997858D01*
G01X1263239Y1035517D02*
X1260739D01*
Y1036558D01*
X1260864Y1036892D01*
X1261031Y1037100D01*
X1261364Y1037183D01*
X1261697Y1037100D01*
X1261906Y1036850D01*
X1262031Y1036558D01*
Y1035517D01*
G01Y1036558D02*
X1263239Y1037183D01*
G01X1261156Y1038658D02*
X1260906Y1038908D01*
X1260781Y1039200D01*
X1260739Y1039533D01*
X1260822Y1039950D01*
X1261031Y1040242D01*
X1261281Y1040325D01*
X1261531Y1040283D01*
X1261739Y1040117D01*
X1262156Y1039283D01*
X1262447Y1038908D01*
X1262864Y1038658D01*
X1263239Y1038575D01*
Y1040325D01*
G01X1262864Y1041633D02*
X1263072Y1041883D01*
X1263197Y1042175D01*
X1263239Y1042550D01*
X1263156Y1042925D01*
X1262989Y1043217D01*
X1262697Y1043425D01*
X1262364Y1043467D01*
X1262031Y1043383D01*
X1261822Y1043175D01*
X1261656Y1042883D01*
X1261614Y1042592D01*
X1261656Y1042300D01*
X1261822Y1041925D01*
X1260739Y1042050D01*
Y1043175D01*
G01X1262864Y1044733D02*
X1263072Y1044983D01*
X1263197Y1045275D01*
X1263239Y1045650D01*
X1263156Y1046025D01*
X1262989Y1046317D01*
X1262697Y1046525D01*
X1262364Y1046567D01*
X1262031Y1046483D01*
X1261822Y1046275D01*
X1261656Y1045983D01*
X1261614Y1045692D01*
X1261656Y1045400D01*
X1261822Y1045025D01*
X1260739Y1045150D01*
Y1046275D01*
G01X1260400Y1026300D02*
X1264400D01*
Y1033700D01*
G01X1299000Y974017D02*
X1296500D01*
Y975058D01*
X1296625Y975392D01*
X1296792Y975600D01*
X1297125Y975683D01*
X1297458Y975600D01*
X1297667Y975350D01*
X1297792Y975058D01*
Y974017D01*
G01Y975058D02*
X1299000Y975683D01*
G01X1296917Y977158D02*
X1296667Y977408D01*
X1296542Y977700D01*
X1296500Y978033D01*
X1296583Y978450D01*
X1296792Y978742D01*
X1297042Y978825D01*
X1297292Y978783D01*
X1297500Y978617D01*
X1297917Y977783D01*
X1298208Y977408D01*
X1298625Y977158D01*
X1299000Y977075D01*
Y978825D01*
G01X1298625Y980133D02*
X1298833Y980383D01*
X1298958Y980675D01*
X1299000Y981050D01*
X1298917Y981425D01*
X1298750Y981717D01*
X1298458Y981925D01*
X1298125Y981967D01*
X1297792Y981883D01*
X1297583Y981675D01*
X1297417Y981383D01*
X1297375Y981092D01*
X1297417Y980800D01*
X1297583Y980425D01*
X1296500Y980550D01*
Y981675D01*
G01X1298708Y983442D02*
X1298917Y983733D01*
X1299000Y984067D01*
X1298917Y984400D01*
X1298667Y984692D01*
X1298292Y984900D01*
X1297917Y984983D01*
X1297458D01*
X1297083Y984900D01*
X1296750Y984692D01*
X1296583Y984442D01*
X1296500Y984150D01*
X1296583Y983817D01*
X1296750Y983567D01*
X1297000Y983400D01*
X1297333Y983317D01*
X1297625Y983400D01*
X1297917Y983608D01*
X1298083Y983858D01*
X1298125Y984150D01*
X1298042Y984483D01*
X1297833Y984733D01*
X1297458Y984983D01*
G01X1302400Y984200D02*
Y980200D01*
X1309800D01*
G01X1310000Y955300D02*
X1314000D01*
Y962700D01*
G01X1320000Y955300D02*
X1324000D01*
Y962700D01*
G01X1309500D02*
X1305500D01*
Y955300D01*
G01X1336500Y963517D02*
X1334000D01*
Y964558D01*
X1334125Y964892D01*
X1334292Y965100D01*
X1334625Y965183D01*
X1334958Y965100D01*
X1335167Y964850D01*
X1335292Y964558D01*
Y963517D01*
G01Y964558D02*
X1336500Y965183D01*
G01X1334417Y966658D02*
X1334167Y966908D01*
X1334042Y967200D01*
X1334000Y967533D01*
X1334083Y967950D01*
X1334292Y968242D01*
X1334542Y968325D01*
X1334792Y968283D01*
X1335000Y968117D01*
X1335417Y967283D01*
X1335708Y966908D01*
X1336125Y966658D01*
X1336500Y966575D01*
Y968325D01*
G01X1335458Y969758D02*
X1335167Y970050D01*
X1335000Y970300D01*
X1334917Y970633D01*
X1335000Y970925D01*
X1335167Y971133D01*
X1335417Y971300D01*
X1335708Y971342D01*
X1335958Y971300D01*
X1336208Y971133D01*
X1336417Y970883D01*
X1336500Y970592D01*
X1336417Y970258D01*
X1336167Y969967D01*
X1335792Y969800D01*
X1335375Y969758D01*
X1334833Y969842D01*
X1334542Y969967D01*
X1334250Y970175D01*
X1334042Y970467D01*
X1334000Y970758D01*
X1334083Y971050D01*
X1334292Y971258D01*
G01X1336500Y974150D02*
X1334000D01*
X1335792Y972608D01*
Y974692D01*
G01X1324500Y967800D02*
X1328500D01*
Y975200D01*
G01X1337200Y1013000D02*
Y1017000D01*
X1329800D01*
G01X1327300Y988000D02*
Y984000D01*
X1334700D01*
G01X1332500Y963517D02*
X1330000D01*
Y964558D01*
X1330125Y964892D01*
X1330292Y965100D01*
X1330625Y965183D01*
X1330958Y965100D01*
X1331167Y964850D01*
X1331292Y964558D01*
Y963517D01*
G01Y964558D02*
X1332500Y965183D01*
G01X1330417Y966658D02*
X1330167Y966908D01*
X1330042Y967200D01*
X1330000Y967533D01*
X1330083Y967950D01*
X1330292Y968242D01*
X1330542Y968325D01*
X1330792Y968283D01*
X1331000Y968117D01*
X1331417Y967283D01*
X1331708Y966908D01*
X1332125Y966658D01*
X1332500Y966575D01*
Y968325D01*
G01X1331458Y969758D02*
X1331167Y970050D01*
X1331000Y970300D01*
X1330917Y970633D01*
X1331000Y970925D01*
X1331167Y971133D01*
X1331417Y971300D01*
X1331708Y971342D01*
X1331958Y971300D01*
X1332208Y971133D01*
X1332417Y970883D01*
X1332500Y970592D01*
X1332417Y970258D01*
X1332167Y969967D01*
X1331792Y969800D01*
X1331375Y969758D01*
X1330833Y969842D01*
X1330542Y969967D01*
X1330250Y970175D01*
X1330042Y970467D01*
X1330000Y970758D01*
X1330083Y971050D01*
X1330292Y971258D01*
G01X1332500Y973567D02*
X1331958Y973650D01*
X1331500Y973775D01*
X1331083Y973942D01*
X1330625Y974150D01*
X1330000Y974483D01*
Y972817D01*
G01X1320000Y967800D02*
X1324000D01*
Y975200D01*
G01X1305900Y1012500D02*
X1305567Y1012542D01*
X1305275Y1012708D01*
X1305025Y1012958D01*
X1304858Y1013250D01*
X1304775Y1013583D01*
Y1013917D01*
X1304858Y1014250D01*
X1305025Y1014542D01*
X1305275Y1014792D01*
X1305567Y1014958D01*
X1305900Y1015000D01*
X1306233Y1014958D01*
X1306525Y1014792D01*
X1306775Y1014542D01*
X1306942Y1014250D01*
X1307025Y1013917D01*
Y1013583D01*
X1306942Y1013250D01*
X1306775Y1012958D01*
X1306525Y1012708D01*
X1306233Y1012542D01*
X1305900Y1012500D01*
G01X1306233Y1013167D02*
X1306733Y1012500D01*
G01X1308208Y1014583D02*
X1308458Y1014833D01*
X1308750Y1014958D01*
X1309083Y1015000D01*
X1309500Y1014917D01*
X1309792Y1014708D01*
X1309875Y1014458D01*
X1309833Y1014208D01*
X1309667Y1014000D01*
X1308833Y1013583D01*
X1308458Y1013292D01*
X1308208Y1012875D01*
X1308125Y1012500D01*
X1309875D01*
G01X1311308Y1014583D02*
X1311558Y1014833D01*
X1311850Y1014958D01*
X1312183Y1015000D01*
X1312600Y1014917D01*
X1312892Y1014708D01*
X1312975Y1014458D01*
X1312933Y1014208D01*
X1312767Y1014000D01*
X1311933Y1013583D01*
X1311558Y1013292D01*
X1311308Y1012875D01*
X1311225Y1012500D01*
X1312975D01*
G01X1320500Y1010200D02*
X1318700Y1008100D01*
X1316500Y1010200D01*
G01X1312900Y1010300D02*
Y991100D01*
X1324100D01*
Y1010300D01*
X1312900D01*
Y1009900D01*
G01X1341000Y1032400D02*
X1340958Y1032067D01*
X1340792Y1031775D01*
X1340542Y1031525D01*
X1340250Y1031358D01*
X1339917Y1031275D01*
X1339583D01*
X1339250Y1031358D01*
X1338958Y1031525D01*
X1338708Y1031775D01*
X1338542Y1032067D01*
X1338500Y1032400D01*
X1338542Y1032733D01*
X1338708Y1033025D01*
X1338958Y1033275D01*
X1339250Y1033442D01*
X1339583Y1033525D01*
X1339917D01*
X1340250Y1033442D01*
X1340542Y1033275D01*
X1340792Y1033025D01*
X1340958Y1032733D01*
X1341000Y1032400D01*
G01X1340333Y1032733D02*
X1341000Y1033233D01*
G01X1338917Y1034708D02*
X1338667Y1034958D01*
X1338542Y1035250D01*
X1338500Y1035583D01*
X1338583Y1036000D01*
X1338792Y1036292D01*
X1339042Y1036375D01*
X1339292Y1036333D01*
X1339500Y1036167D01*
X1339917Y1035333D01*
X1340208Y1034958D01*
X1340625Y1034708D01*
X1341000Y1034625D01*
Y1036375D01*
G01Y1039100D02*
X1338500D01*
X1340292Y1037558D01*
Y1039642D01*
G01X1315300Y1037500D02*
X1317400Y1035700D01*
X1315300Y1033500D01*
G01X1315200Y1029900D02*
X1334400D01*
Y1041100D01*
X1315200D01*
Y1029900D01*
X1315600D01*
G01X1253166Y1041017D02*
X1250666D01*
Y1042058D01*
X1250791Y1042392D01*
X1250958Y1042600D01*
X1251291Y1042683D01*
X1251624Y1042600D01*
X1251833Y1042350D01*
X1251958Y1042058D01*
Y1041017D01*
G01Y1042058D02*
X1253166Y1042683D01*
G01X1251083Y1044158D02*
X1250833Y1044408D01*
X1250708Y1044700D01*
X1250666Y1045033D01*
X1250749Y1045450D01*
X1250958Y1045742D01*
X1251208Y1045825D01*
X1251458Y1045783D01*
X1251666Y1045617D01*
X1252083Y1044783D01*
X1252374Y1044408D01*
X1252791Y1044158D01*
X1253166Y1044075D01*
Y1045825D01*
G01X1252791Y1047133D02*
X1252999Y1047383D01*
X1253124Y1047675D01*
X1253166Y1048050D01*
X1253083Y1048425D01*
X1252916Y1048717D01*
X1252624Y1048925D01*
X1252291Y1048967D01*
X1251958Y1048883D01*
X1251749Y1048675D01*
X1251583Y1048383D01*
X1251541Y1048092D01*
X1251583Y1047800D01*
X1251749Y1047425D01*
X1250666Y1047550D01*
Y1048675D01*
G01X1253166Y1051067D02*
X1252624Y1051150D01*
X1252166Y1051275D01*
X1251749Y1051442D01*
X1251291Y1051650D01*
X1250666Y1051983D01*
Y1050317D01*
G01X1304500Y1041700D02*
Y1047200D01*
G01X1312500Y1041700D02*
X1304500D01*
G01X1312500Y1047200D02*
Y1041700D01*
G01X1338533Y978500D02*
Y981000D01*
X1339367D01*
X1339700Y980875D01*
X1339950Y980708D01*
X1340158Y980458D01*
X1340325Y980167D01*
X1340367Y979750D01*
X1340325Y979333D01*
X1340158Y979042D01*
X1339950Y978792D01*
X1339700Y978625D01*
X1339367Y978500D01*
X1338533D01*
G01X1341758Y979542D02*
X1342050Y979833D01*
X1342300Y980000D01*
X1342633Y980083D01*
X1342925Y980000D01*
X1343133Y979833D01*
X1343300Y979583D01*
X1343342Y979292D01*
X1343300Y979042D01*
X1343133Y978792D01*
X1342883Y978583D01*
X1342592Y978500D01*
X1342258Y978583D01*
X1341967Y978833D01*
X1341800Y979208D01*
X1341758Y979625D01*
X1341842Y980167D01*
X1341967Y980458D01*
X1342175Y980750D01*
X1342467Y980958D01*
X1342758Y981000D01*
X1343050Y980917D01*
X1343258Y980708D01*
G01X1336500Y976000D02*
X1320400D01*
G01X1336500Y983000D02*
Y976000D01*
G01X1320400Y983000D02*
X1336500D01*
G01X1320400Y976000D02*
Y983000D01*
G01X1299000Y964400D02*
X1298958Y964067D01*
X1298792Y963775D01*
X1298542Y963525D01*
X1298250Y963358D01*
X1297917Y963275D01*
X1297583D01*
X1297250Y963358D01*
X1296958Y963525D01*
X1296708Y963775D01*
X1296542Y964067D01*
X1296500Y964400D01*
X1296542Y964733D01*
X1296708Y965025D01*
X1296958Y965275D01*
X1297250Y965442D01*
X1297583Y965525D01*
X1297917D01*
X1298250Y965442D01*
X1298542Y965275D01*
X1298792Y965025D01*
X1298958Y964733D01*
X1299000Y964400D01*
G01X1298333Y964733D02*
X1299000Y965233D01*
G01X1296917Y966708D02*
X1296667Y966958D01*
X1296542Y967250D01*
X1296500Y967583D01*
X1296583Y968000D01*
X1296792Y968292D01*
X1297042Y968375D01*
X1297292Y968333D01*
X1297500Y968167D01*
X1297917Y967333D01*
X1298208Y966958D01*
X1298625Y966708D01*
X1299000Y966625D01*
Y968375D01*
G01X1298500Y969683D02*
X1298792Y969933D01*
X1298958Y970267D01*
X1299000Y970642D01*
X1298958Y970975D01*
X1298750Y971308D01*
X1298500Y971517D01*
X1298250Y971558D01*
X1297958Y971475D01*
X1297750Y971183D01*
X1297667Y970892D01*
Y970517D01*
G01Y970892D02*
X1297542Y971142D01*
X1297333Y971350D01*
X1297083Y971433D01*
X1296833Y971350D01*
X1296625Y971142D01*
X1296500Y970767D01*
X1296542Y970392D01*
X1296708Y970017D01*
G01X1300800Y975200D02*
Y963800D01*
G01X1314200Y975200D02*
X1300800D01*
G01X1314200Y963800D02*
Y975200D01*
G01X1300800Y963800D02*
X1314200D01*
G01X1299517Y1023000D02*
Y1025500D01*
X1300558D01*
X1300892Y1025375D01*
X1301100Y1025208D01*
X1301183Y1024875D01*
X1301100Y1024542D01*
X1300850Y1024333D01*
X1300558Y1024208D01*
X1299517D01*
G01X1300558D02*
X1301183Y1023000D01*
G01X1302658Y1025083D02*
X1302908Y1025333D01*
X1303200Y1025458D01*
X1303533Y1025500D01*
X1303950Y1025417D01*
X1304242Y1025208D01*
X1304325Y1024958D01*
X1304283Y1024708D01*
X1304117Y1024500D01*
X1303283Y1024083D01*
X1302908Y1023792D01*
X1302658Y1023375D01*
X1302575Y1023000D01*
X1304325D01*
G01X1305633Y1023375D02*
X1305883Y1023167D01*
X1306175Y1023042D01*
X1306550Y1023000D01*
X1306925Y1023083D01*
X1307217Y1023250D01*
X1307425Y1023542D01*
X1307467Y1023875D01*
X1307383Y1024208D01*
X1307175Y1024417D01*
X1306883Y1024583D01*
X1306592Y1024625D01*
X1306300Y1024583D01*
X1305925Y1024417D01*
X1306050Y1025500D01*
X1307175D01*
G01X1310150Y1023000D02*
Y1025500D01*
X1308608Y1023708D01*
X1310692D01*
G01X1313800Y1035500D02*
Y1027500D01*
X1296200D01*
Y1035500D01*
X1313800D01*
G01X1272325Y1114500D02*
Y1117000D01*
G01X1274075D02*
Y1114500D01*
G01Y1115750D02*
X1272325D01*
G01X1275383Y1114500D02*
Y1117000D01*
X1276217D01*
X1276550Y1116875D01*
X1276800Y1116708D01*
X1277008Y1116458D01*
X1277175Y1116167D01*
X1277217Y1115750D01*
X1277175Y1115333D01*
X1277008Y1115042D01*
X1276800Y1114792D01*
X1276550Y1114625D01*
X1276217Y1114500D01*
X1275383D01*
G01X1278483D02*
Y1117000D01*
X1279317D01*
X1279650Y1116875D01*
X1279900Y1116708D01*
X1280108Y1116458D01*
X1280275Y1116167D01*
X1280317Y1115750D01*
X1280275Y1115333D01*
X1280108Y1115042D01*
X1279900Y1114792D01*
X1279650Y1114625D01*
X1279317Y1114500D01*
X1278483D01*
G01X1281625Y1114833D02*
X1281958Y1114625D01*
X1282333Y1114500D01*
X1282667D01*
X1283000Y1114625D01*
X1283250Y1114833D01*
X1283375Y1115125D01*
X1283292Y1115417D01*
X1283083Y1115667D01*
X1282708Y1115833D01*
X1282208Y1115917D01*
X1281917Y1116083D01*
X1281792Y1116375D01*
X1281875Y1116667D01*
X1282083Y1116875D01*
X1282375Y1117000D01*
X1282667D01*
X1282958Y1116917D01*
X1283208Y1116708D01*
G01X1284558Y1114500D02*
X1285600Y1117000D01*
X1286642Y1114500D01*
G01X1286267Y1115375D02*
X1284933D01*
G01X1287825Y1114833D02*
X1288158Y1114625D01*
X1288533Y1114500D01*
X1288867D01*
X1289200Y1114625D01*
X1289450Y1114833D01*
X1289575Y1115125D01*
X1289492Y1115417D01*
X1289283Y1115667D01*
X1288908Y1115833D01*
X1288408Y1115917D01*
X1288117Y1116083D01*
X1287992Y1116375D01*
X1288075Y1116667D01*
X1288283Y1116875D01*
X1288575Y1117000D01*
X1288867D01*
X1289158Y1116917D01*
X1289408Y1116708D01*
G01X1291008Y1115542D02*
X1291300Y1115833D01*
X1291550Y1116000D01*
X1291883Y1116083D01*
X1292175Y1116000D01*
X1292383Y1115833D01*
X1292550Y1115583D01*
X1292592Y1115292D01*
X1292550Y1115042D01*
X1292383Y1114792D01*
X1292133Y1114583D01*
X1291842Y1114500D01*
X1291508Y1114583D01*
X1291217Y1114833D01*
X1291050Y1115208D01*
X1291008Y1115625D01*
X1291092Y1116167D01*
X1291217Y1116458D01*
X1291425Y1116750D01*
X1291717Y1116958D01*
X1292008Y1117000D01*
X1292300Y1116917D01*
X1292508Y1116708D01*
G01X1297208Y1062767D02*
X1297083Y1062517D01*
X1297000Y1062225D01*
Y1061892D01*
X1297125Y1061517D01*
X1297333Y1061225D01*
X1297583Y1061017D01*
X1298000Y1060850D01*
X1298375Y1060808D01*
X1298750Y1060892D01*
X1299000Y1061017D01*
X1299250Y1061267D01*
X1299417Y1061558D01*
X1299500Y1061850D01*
Y1062142D01*
X1299417Y1062433D01*
X1299292Y1062683D01*
X1299125Y1062892D01*
G01X1299500Y1064950D02*
X1297000D01*
X1297500Y1064450D01*
G01X1299500D02*
Y1065450D01*
G01X1297000Y1068050D02*
X1297083Y1067717D01*
X1297292Y1067467D01*
X1297542Y1067300D01*
X1297875Y1067175D01*
X1298250Y1067133D01*
X1298625Y1067175D01*
X1298958Y1067300D01*
X1299208Y1067467D01*
X1299417Y1067717D01*
X1299500Y1068050D01*
X1299417Y1068383D01*
X1299208Y1068633D01*
X1298958Y1068800D01*
X1298625Y1068925D01*
X1298250Y1068967D01*
X1297875Y1068925D01*
X1297542Y1068800D01*
X1297292Y1068633D01*
X1297083Y1068383D01*
X1297000Y1068050D01*
G01X1299500Y1071150D02*
X1299458Y1071442D01*
X1299333Y1071775D01*
X1299125Y1071983D01*
X1298833Y1072067D01*
X1298542Y1071983D01*
X1298292Y1071733D01*
X1298167Y1071358D01*
Y1070942D01*
X1298083Y1070692D01*
X1297875Y1070483D01*
X1297583Y1070400D01*
X1297292Y1070525D01*
X1297083Y1070817D01*
X1297000Y1071150D01*
X1297083Y1071483D01*
X1297292Y1071775D01*
X1297583Y1071900D01*
X1297875Y1071817D01*
X1298083Y1071608D01*
X1298167Y1071358D01*
Y1070942D01*
X1298292Y1070567D01*
X1298542Y1070317D01*
X1298833Y1070233D01*
X1299125Y1070317D01*
X1299333Y1070525D01*
X1299458Y1070858D01*
X1299500Y1071150D01*
G01X1297208Y1095267D02*
X1297083Y1095017D01*
X1297000Y1094725D01*
Y1094392D01*
X1297125Y1094017D01*
X1297333Y1093725D01*
X1297583Y1093517D01*
X1298000Y1093350D01*
X1298375Y1093308D01*
X1298750Y1093392D01*
X1299000Y1093517D01*
X1299250Y1093767D01*
X1299417Y1094058D01*
X1299500Y1094350D01*
Y1094642D01*
X1299417Y1094933D01*
X1299292Y1095183D01*
X1299125Y1095392D01*
G01X1299500Y1097450D02*
X1297000D01*
X1297500Y1096950D01*
G01X1299500D02*
Y1097950D01*
G01Y1100550D02*
X1297000D01*
X1297500Y1100050D01*
G01X1299500D02*
Y1101050D01*
G01Y1104150D02*
X1297000D01*
X1298792Y1102608D01*
Y1104692D01*
G01X1251350Y1068000D02*
Y1065500D01*
G01X1250392Y1068000D02*
X1252308D01*
G01X1253617Y1065500D02*
Y1068000D01*
X1254617D01*
X1254950Y1067875D01*
X1255200Y1067583D01*
X1255283Y1067250D01*
X1255200Y1066917D01*
X1254992Y1066667D01*
X1254617Y1066542D01*
X1253617D01*
G01X1256633Y1065875D02*
X1256883Y1065667D01*
X1257175Y1065542D01*
X1257550Y1065500D01*
X1257925Y1065583D01*
X1258217Y1065750D01*
X1258425Y1066042D01*
X1258467Y1066375D01*
X1258383Y1066708D01*
X1258175Y1066917D01*
X1257883Y1067083D01*
X1257592Y1067125D01*
X1257300Y1067083D01*
X1256925Y1066917D01*
X1257050Y1068000D01*
X1258175D01*
G01X1260650Y1065500D02*
Y1068000D01*
X1260150Y1067500D01*
G01Y1065500D02*
X1261150D01*
G01X1301208Y1061267D02*
X1301083Y1061017D01*
X1301000Y1060725D01*
Y1060392D01*
X1301125Y1060017D01*
X1301333Y1059725D01*
X1301583Y1059517D01*
X1302000Y1059350D01*
X1302375Y1059308D01*
X1302750Y1059392D01*
X1303000Y1059517D01*
X1303250Y1059767D01*
X1303417Y1060058D01*
X1303500Y1060350D01*
Y1060642D01*
X1303417Y1060933D01*
X1303292Y1061183D01*
X1303125Y1061392D01*
G01X1303500Y1063450D02*
X1301000D01*
X1301500Y1062950D01*
G01X1303500D02*
Y1063950D01*
G01X1301000Y1066550D02*
X1301083Y1066217D01*
X1301292Y1065967D01*
X1301542Y1065800D01*
X1301875Y1065675D01*
X1302250Y1065633D01*
X1302625Y1065675D01*
X1302958Y1065800D01*
X1303208Y1065967D01*
X1303417Y1066217D01*
X1303500Y1066550D01*
X1303417Y1066883D01*
X1303208Y1067133D01*
X1302958Y1067300D01*
X1302625Y1067425D01*
X1302250Y1067467D01*
X1301875Y1067425D01*
X1301542Y1067300D01*
X1301292Y1067133D01*
X1301083Y1066883D01*
X1301000Y1066550D01*
G01X1303208Y1068942D02*
X1303417Y1069233D01*
X1303500Y1069567D01*
X1303417Y1069900D01*
X1303167Y1070192D01*
X1302792Y1070400D01*
X1302417Y1070483D01*
X1301958D01*
X1301583Y1070400D01*
X1301250Y1070192D01*
X1301083Y1069942D01*
X1301000Y1069650D01*
X1301083Y1069317D01*
X1301250Y1069067D01*
X1301500Y1068900D01*
X1301833Y1068817D01*
X1302125Y1068900D01*
X1302417Y1069108D01*
X1302583Y1069358D01*
X1302625Y1069650D01*
X1302542Y1069983D01*
X1302333Y1070233D01*
X1301958Y1070483D01*
G01X1312500Y1059300D02*
Y1053800D01*
G01X1304500Y1059300D02*
X1312500D01*
G01X1304500Y1053800D02*
Y1059300D01*
G01X1311017Y1070800D02*
Y1073300D01*
X1312058D01*
X1312392Y1073175D01*
X1312600Y1073008D01*
X1312683Y1072675D01*
X1312600Y1072342D01*
X1312350Y1072133D01*
X1312058Y1072008D01*
X1311017D01*
G01X1312058D02*
X1312683Y1070800D01*
G01X1314158Y1072883D02*
X1314408Y1073133D01*
X1314700Y1073258D01*
X1315033Y1073300D01*
X1315450Y1073217D01*
X1315742Y1073008D01*
X1315825Y1072758D01*
X1315783Y1072508D01*
X1315617Y1072300D01*
X1314783Y1071883D01*
X1314408Y1071592D01*
X1314158Y1071175D01*
X1314075Y1070800D01*
X1315825D01*
G01X1317133Y1071175D02*
X1317383Y1070967D01*
X1317675Y1070842D01*
X1318050Y1070800D01*
X1318425Y1070883D01*
X1318717Y1071050D01*
X1318925Y1071342D01*
X1318967Y1071675D01*
X1318883Y1072008D01*
X1318675Y1072217D01*
X1318383Y1072383D01*
X1318092Y1072425D01*
X1317800Y1072383D01*
X1317425Y1072217D01*
X1317550Y1073300D01*
X1318675D01*
G01X1320358Y1071842D02*
X1320650Y1072133D01*
X1320900Y1072300D01*
X1321233Y1072383D01*
X1321525Y1072300D01*
X1321733Y1072133D01*
X1321900Y1071883D01*
X1321942Y1071592D01*
X1321900Y1071342D01*
X1321733Y1071092D01*
X1321483Y1070883D01*
X1321192Y1070800D01*
X1320858Y1070883D01*
X1320567Y1071133D01*
X1320400Y1071508D01*
X1320358Y1071925D01*
X1320442Y1072467D01*
X1320567Y1072758D01*
X1320775Y1073050D01*
X1321067Y1073258D01*
X1321358Y1073300D01*
X1321650Y1073217D01*
X1321858Y1073008D01*
G01X1322300Y1069300D02*
Y1061300D01*
X1304700D01*
Y1069300D01*
X1322300D01*
G01X1304047Y1095267D02*
X1303922Y1095017D01*
X1303839Y1094725D01*
Y1094392D01*
X1303964Y1094017D01*
X1304172Y1093725D01*
X1304422Y1093517D01*
X1304839Y1093350D01*
X1305214Y1093308D01*
X1305589Y1093392D01*
X1305839Y1093517D01*
X1306089Y1093767D01*
X1306256Y1094058D01*
X1306339Y1094350D01*
Y1094642D01*
X1306256Y1094933D01*
X1306131Y1095183D01*
X1305964Y1095392D01*
G01X1306339Y1097450D02*
X1303839D01*
X1304339Y1096950D01*
G01X1306339D02*
Y1097950D01*
G01Y1100550D02*
X1303839D01*
X1304339Y1100050D01*
G01X1306339D02*
Y1101050D01*
G01X1304256Y1102858D02*
X1304006Y1103108D01*
X1303881Y1103400D01*
X1303839Y1103733D01*
X1303922Y1104150D01*
X1304131Y1104442D01*
X1304381Y1104525D01*
X1304631Y1104483D01*
X1304839Y1104317D01*
X1305256Y1103483D01*
X1305547Y1103108D01*
X1305964Y1102858D01*
X1306339Y1102775D01*
Y1104525D01*
G01X1312047Y1095267D02*
X1311922Y1095017D01*
X1311839Y1094725D01*
Y1094392D01*
X1311964Y1094017D01*
X1312172Y1093725D01*
X1312422Y1093517D01*
X1312839Y1093350D01*
X1313214Y1093308D01*
X1313589Y1093392D01*
X1313839Y1093517D01*
X1314089Y1093767D01*
X1314256Y1094058D01*
X1314339Y1094350D01*
Y1094642D01*
X1314256Y1094933D01*
X1314131Y1095183D01*
X1313964Y1095392D01*
G01X1314339Y1097450D02*
X1311839D01*
X1312339Y1096950D01*
G01X1314339D02*
Y1097950D01*
G01Y1100550D02*
X1311839D01*
X1312339Y1100050D01*
G01X1314339D02*
Y1101050D01*
G01X1313839Y1102733D02*
X1314131Y1102983D01*
X1314297Y1103317D01*
X1314339Y1103692D01*
X1314297Y1104025D01*
X1314089Y1104358D01*
X1313839Y1104567D01*
X1313589Y1104608D01*
X1313297Y1104525D01*
X1313089Y1104233D01*
X1313006Y1103942D01*
Y1103567D01*
G01Y1103942D02*
X1312881Y1104192D01*
X1312672Y1104400D01*
X1312422Y1104483D01*
X1312172Y1104400D01*
X1311964Y1104192D01*
X1311839Y1103817D01*
X1311881Y1103442D01*
X1312047Y1103067D01*
G01X1295208Y1419267D02*
X1295083Y1419017D01*
X1295000Y1418725D01*
Y1418392D01*
X1295125Y1418017D01*
X1295333Y1417725D01*
X1295583Y1417517D01*
X1296000Y1417350D01*
X1296375Y1417308D01*
X1296750Y1417392D01*
X1297000Y1417517D01*
X1297250Y1417767D01*
X1297417Y1418058D01*
X1297500Y1418350D01*
Y1418642D01*
X1297417Y1418933D01*
X1297292Y1419183D01*
X1297125Y1419392D01*
G01Y1420533D02*
X1297333Y1420783D01*
X1297458Y1421075D01*
X1297500Y1421450D01*
X1297417Y1421825D01*
X1297250Y1422117D01*
X1296958Y1422325D01*
X1296625Y1422367D01*
X1296292Y1422283D01*
X1296083Y1422075D01*
X1295917Y1421783D01*
X1295875Y1421492D01*
X1295917Y1421200D01*
X1296083Y1420825D01*
X1295000Y1420950D01*
Y1422075D01*
G01X1297000Y1423633D02*
X1297292Y1423883D01*
X1297458Y1424217D01*
X1297500Y1424592D01*
X1297458Y1424925D01*
X1297250Y1425258D01*
X1297000Y1425467D01*
X1296750Y1425508D01*
X1296458Y1425425D01*
X1296250Y1425133D01*
X1296167Y1424842D01*
Y1424467D01*
G01Y1424842D02*
X1296042Y1425092D01*
X1295833Y1425300D01*
X1295583Y1425383D01*
X1295333Y1425300D01*
X1295125Y1425092D01*
X1295000Y1424717D01*
X1295042Y1424342D01*
X1295208Y1423967D01*
G01X1297000Y1426733D02*
X1297292Y1426983D01*
X1297458Y1427317D01*
X1297500Y1427692D01*
X1297458Y1428025D01*
X1297250Y1428358D01*
X1297000Y1428567D01*
X1296750Y1428608D01*
X1296458Y1428525D01*
X1296250Y1428233D01*
X1296167Y1427942D01*
Y1427567D01*
G01Y1427942D02*
X1296042Y1428192D01*
X1295833Y1428400D01*
X1295583Y1428483D01*
X1295333Y1428400D01*
X1295125Y1428192D01*
X1295000Y1427817D01*
X1295042Y1427442D01*
X1295208Y1427067D01*
G01X1322708Y1396167D02*
X1322583Y1395917D01*
X1322500Y1395625D01*
Y1395292D01*
X1322625Y1394917D01*
X1322833Y1394625D01*
X1323083Y1394417D01*
X1323500Y1394250D01*
X1323875Y1394208D01*
X1324250Y1394292D01*
X1324500Y1394417D01*
X1324750Y1394667D01*
X1324917Y1394958D01*
X1325000Y1395250D01*
Y1395542D01*
X1324917Y1395833D01*
X1324792Y1396083D01*
X1324625Y1396292D01*
G01X1324500Y1397433D02*
X1324792Y1397683D01*
X1324958Y1398017D01*
X1325000Y1398392D01*
X1324958Y1398725D01*
X1324750Y1399058D01*
X1324500Y1399267D01*
X1324250Y1399308D01*
X1323958Y1399225D01*
X1323750Y1398933D01*
X1323667Y1398642D01*
Y1398267D01*
G01Y1398642D02*
X1323542Y1398892D01*
X1323333Y1399100D01*
X1323083Y1399183D01*
X1322833Y1399100D01*
X1322625Y1398892D01*
X1322500Y1398517D01*
X1322542Y1398142D01*
X1322708Y1397767D01*
G01X1324708Y1400742D02*
X1324917Y1401033D01*
X1325000Y1401367D01*
X1324917Y1401700D01*
X1324667Y1401992D01*
X1324292Y1402200D01*
X1323917Y1402283D01*
X1323458D01*
X1323083Y1402200D01*
X1322750Y1401992D01*
X1322583Y1401742D01*
X1322500Y1401450D01*
X1322583Y1401117D01*
X1322750Y1400867D01*
X1323000Y1400700D01*
X1323333Y1400617D01*
X1323625Y1400700D01*
X1323917Y1400908D01*
X1324083Y1401158D01*
X1324125Y1401450D01*
X1324042Y1401783D01*
X1323833Y1402033D01*
X1323458Y1402283D01*
G01X1325000Y1404550D02*
X1322500D01*
X1323000Y1404050D01*
G01X1325000D02*
Y1405050D01*
G01X1293500Y1417517D02*
X1291000D01*
Y1418558D01*
X1291125Y1418892D01*
X1291292Y1419100D01*
X1291625Y1419183D01*
X1291958Y1419100D01*
X1292167Y1418850D01*
X1292292Y1418558D01*
Y1417517D01*
G01Y1418558D02*
X1293500Y1419183D01*
G01X1293208Y1420742D02*
X1293417Y1421033D01*
X1293500Y1421367D01*
X1293417Y1421700D01*
X1293167Y1421992D01*
X1292792Y1422200D01*
X1292417Y1422283D01*
X1291958D01*
X1291583Y1422200D01*
X1291250Y1421992D01*
X1291083Y1421742D01*
X1291000Y1421450D01*
X1291083Y1421117D01*
X1291250Y1420867D01*
X1291500Y1420700D01*
X1291833Y1420617D01*
X1292125Y1420700D01*
X1292417Y1420908D01*
X1292583Y1421158D01*
X1292625Y1421450D01*
X1292542Y1421783D01*
X1292333Y1422033D01*
X1291958Y1422283D01*
G01X1293500Y1425050D02*
X1291000D01*
X1292792Y1423508D01*
Y1425592D01*
G01X1293500Y1427650D02*
X1293458Y1427942D01*
X1293333Y1428275D01*
X1293125Y1428483D01*
X1292833Y1428567D01*
X1292542Y1428483D01*
X1292292Y1428233D01*
X1292167Y1427858D01*
Y1427442D01*
X1292083Y1427192D01*
X1291875Y1426983D01*
X1291583Y1426900D01*
X1291292Y1427025D01*
X1291083Y1427317D01*
X1291000Y1427650D01*
X1291083Y1427983D01*
X1291292Y1428275D01*
X1291583Y1428400D01*
X1291875Y1428317D01*
X1292083Y1428108D01*
X1292167Y1427858D01*
Y1427442D01*
X1292292Y1427067D01*
X1292542Y1426817D01*
X1292833Y1426733D01*
X1293125Y1426817D01*
X1293333Y1427025D01*
X1293458Y1427358D01*
X1293500Y1427650D01*
G01X1261391Y1426300D02*
Y1428800D01*
X1262432D01*
X1262766Y1428675D01*
X1262974Y1428508D01*
X1263057Y1428175D01*
X1262974Y1427842D01*
X1262724Y1427633D01*
X1262432Y1427508D01*
X1261391D01*
G01X1262432D02*
X1263057Y1426300D01*
G01X1264616Y1426592D02*
X1264907Y1426383D01*
X1265241Y1426300D01*
X1265574Y1426383D01*
X1265866Y1426633D01*
X1266074Y1427008D01*
X1266157Y1427383D01*
Y1427842D01*
X1266074Y1428217D01*
X1265866Y1428550D01*
X1265616Y1428717D01*
X1265324Y1428800D01*
X1264991Y1428717D01*
X1264741Y1428550D01*
X1264574Y1428300D01*
X1264491Y1427967D01*
X1264574Y1427675D01*
X1264782Y1427383D01*
X1265032Y1427217D01*
X1265324Y1427175D01*
X1265657Y1427258D01*
X1265907Y1427467D01*
X1266157Y1427842D01*
G01X1267507Y1426675D02*
X1267757Y1426467D01*
X1268049Y1426342D01*
X1268424Y1426300D01*
X1268799Y1426383D01*
X1269091Y1426550D01*
X1269299Y1426842D01*
X1269341Y1427175D01*
X1269257Y1427508D01*
X1269049Y1427717D01*
X1268757Y1427883D01*
X1268466Y1427925D01*
X1268174Y1427883D01*
X1267799Y1427717D01*
X1267924Y1428800D01*
X1269049D01*
G01X1271524Y1426300D02*
Y1428800D01*
X1271024Y1428300D01*
G01Y1426300D02*
X1272024D01*
G01X1321000Y1394417D02*
X1318500D01*
Y1395458D01*
X1318625Y1395792D01*
X1318792Y1396000D01*
X1319125Y1396083D01*
X1319458Y1396000D01*
X1319667Y1395750D01*
X1319792Y1395458D01*
Y1394417D01*
G01Y1395458D02*
X1321000Y1396083D01*
G01X1320708Y1397642D02*
X1320917Y1397933D01*
X1321000Y1398267D01*
X1320917Y1398600D01*
X1320667Y1398892D01*
X1320292Y1399100D01*
X1319917Y1399183D01*
X1319458D01*
X1319083Y1399100D01*
X1318750Y1398892D01*
X1318583Y1398642D01*
X1318500Y1398350D01*
X1318583Y1398017D01*
X1318750Y1397767D01*
X1319000Y1397600D01*
X1319333Y1397517D01*
X1319625Y1397600D01*
X1319917Y1397808D01*
X1320083Y1398058D01*
X1320125Y1398350D01*
X1320042Y1398683D01*
X1319833Y1398933D01*
X1319458Y1399183D01*
G01X1319958Y1400658D02*
X1319667Y1400950D01*
X1319500Y1401200D01*
X1319417Y1401533D01*
X1319500Y1401825D01*
X1319667Y1402033D01*
X1319917Y1402200D01*
X1320208Y1402242D01*
X1320458Y1402200D01*
X1320708Y1402033D01*
X1320917Y1401783D01*
X1321000Y1401492D01*
X1320917Y1401158D01*
X1320667Y1400867D01*
X1320292Y1400700D01*
X1319875Y1400658D01*
X1319333Y1400742D01*
X1319042Y1400867D01*
X1318750Y1401075D01*
X1318542Y1401367D01*
X1318500Y1401658D01*
X1318583Y1401950D01*
X1318792Y1402158D01*
G01X1321000Y1404550D02*
X1320958Y1404842D01*
X1320833Y1405175D01*
X1320625Y1405383D01*
X1320333Y1405467D01*
X1320042Y1405383D01*
X1319792Y1405133D01*
X1319667Y1404758D01*
Y1404342D01*
X1319583Y1404092D01*
X1319375Y1403883D01*
X1319083Y1403800D01*
X1318792Y1403925D01*
X1318583Y1404217D01*
X1318500Y1404550D01*
X1318583Y1404883D01*
X1318792Y1405175D01*
X1319083Y1405300D01*
X1319375Y1405217D01*
X1319583Y1405008D01*
X1319667Y1404758D01*
Y1404342D01*
X1319792Y1403967D01*
X1320042Y1403717D01*
X1320333Y1403633D01*
X1320625Y1403717D01*
X1320833Y1403925D01*
X1320958Y1404258D01*
X1321000Y1404550D01*
G01X1321500Y1422200D02*
X1317500D01*
Y1414800D01*
G01X1321000Y1381017D02*
X1318500D01*
Y1382058D01*
X1318625Y1382392D01*
X1318792Y1382600D01*
X1319125Y1382683D01*
X1319458Y1382600D01*
X1319667Y1382350D01*
X1319792Y1382058D01*
Y1381017D01*
G01Y1382058D02*
X1321000Y1382683D01*
G01Y1384950D02*
X1318500D01*
X1319000Y1384450D01*
G01X1321000D02*
Y1385450D01*
G01Y1388550D02*
X1318500D01*
X1320292Y1387008D01*
Y1389092D01*
G01X1320625Y1390233D02*
X1320833Y1390483D01*
X1320958Y1390775D01*
X1321000Y1391150D01*
X1320917Y1391525D01*
X1320750Y1391817D01*
X1320458Y1392025D01*
X1320125Y1392067D01*
X1319792Y1391983D01*
X1319583Y1391775D01*
X1319417Y1391483D01*
X1319375Y1391192D01*
X1319417Y1390900D01*
X1319583Y1390525D01*
X1318500Y1390650D01*
Y1391775D01*
G01X1321500Y1414550D02*
X1317500D01*
Y1407150D01*
G01X1325500Y1381017D02*
X1323000D01*
Y1382058D01*
X1323125Y1382392D01*
X1323292Y1382600D01*
X1323625Y1382683D01*
X1323958Y1382600D01*
X1324167Y1382350D01*
X1324292Y1382058D01*
Y1381017D01*
G01Y1382058D02*
X1325500Y1382683D01*
G01Y1384950D02*
X1323000D01*
X1323500Y1384450D01*
G01X1325500D02*
Y1385450D01*
G01Y1388550D02*
X1323000D01*
X1324792Y1387008D01*
Y1389092D01*
G01X1325500Y1391150D02*
X1325458Y1391442D01*
X1325333Y1391775D01*
X1325125Y1391983D01*
X1324833Y1392067D01*
X1324542Y1391983D01*
X1324292Y1391733D01*
X1324167Y1391358D01*
Y1390942D01*
X1324083Y1390692D01*
X1323875Y1390483D01*
X1323583Y1390400D01*
X1323292Y1390525D01*
X1323083Y1390817D01*
X1323000Y1391150D01*
X1323083Y1391483D01*
X1323292Y1391775D01*
X1323583Y1391900D01*
X1323875Y1391817D01*
X1324083Y1391608D01*
X1324167Y1391358D01*
Y1390942D01*
X1324292Y1390567D01*
X1324542Y1390317D01*
X1324833Y1390233D01*
X1325125Y1390317D01*
X1325333Y1390525D01*
X1325458Y1390858D01*
X1325500Y1391150D01*
G01X1321950Y1410400D02*
Y1406400D01*
X1329350D01*
G01X1335750Y1402500D02*
X1335417Y1402542D01*
X1335125Y1402708D01*
X1334875Y1402958D01*
X1334708Y1403250D01*
X1334625Y1403583D01*
Y1403917D01*
X1334708Y1404250D01*
X1334875Y1404542D01*
X1335125Y1404792D01*
X1335417Y1404958D01*
X1335750Y1405000D01*
X1336083Y1404958D01*
X1336375Y1404792D01*
X1336625Y1404542D01*
X1336792Y1404250D01*
X1336875Y1403917D01*
Y1403583D01*
X1336792Y1403250D01*
X1336625Y1402958D01*
X1336375Y1402708D01*
X1336083Y1402542D01*
X1335750Y1402500D01*
G01X1336083Y1403167D02*
X1336583Y1402500D01*
G01X1338850D02*
Y1405000D01*
X1338350Y1404500D01*
G01Y1402500D02*
X1339350D01*
G01X1341033Y1403000D02*
X1341283Y1402708D01*
X1341617Y1402542D01*
X1341992Y1402500D01*
X1342325Y1402542D01*
X1342658Y1402750D01*
X1342867Y1403000D01*
X1342908Y1403250D01*
X1342825Y1403542D01*
X1342533Y1403750D01*
X1342242Y1403833D01*
X1341867D01*
G01X1342242D02*
X1342492Y1403958D01*
X1342700Y1404167D01*
X1342783Y1404417D01*
X1342700Y1404667D01*
X1342492Y1404875D01*
X1342117Y1405000D01*
X1341742Y1404958D01*
X1341367Y1404792D01*
G01X1345050Y1405000D02*
X1344717Y1404917D01*
X1344467Y1404708D01*
X1344300Y1404458D01*
X1344175Y1404125D01*
X1344133Y1403750D01*
X1344175Y1403375D01*
X1344300Y1403042D01*
X1344467Y1402792D01*
X1344717Y1402583D01*
X1345050Y1402500D01*
X1345383Y1402583D01*
X1345633Y1402792D01*
X1345800Y1403042D01*
X1345925Y1403375D01*
X1345967Y1403750D01*
X1345925Y1404125D01*
X1345800Y1404458D01*
X1345633Y1404708D01*
X1345383Y1404917D01*
X1345050Y1405000D01*
G01X1329900Y1422700D02*
X1332000Y1420900D01*
X1329900Y1418700D01*
G01X1329800Y1415100D02*
X1349000D01*
Y1426300D01*
X1329800D01*
Y1415100D01*
X1330200D01*
G01X1308000Y1399483D02*
X1305500D01*
Y1400317D01*
X1305625Y1400650D01*
X1305792Y1400900D01*
X1306042Y1401108D01*
X1306333Y1401275D01*
X1306750Y1401317D01*
X1307167Y1401275D01*
X1307458Y1401108D01*
X1307708Y1400900D01*
X1307875Y1400650D01*
X1308000Y1400317D01*
Y1399483D01*
G01Y1404000D02*
X1305500D01*
X1307292Y1402458D01*
Y1404542D01*
G01X1308000Y1406517D02*
X1307458Y1406600D01*
X1307000Y1406725D01*
X1306583Y1406892D01*
X1306125Y1407100D01*
X1305500Y1407433D01*
Y1405767D01*
G01X1310000Y1397900D02*
Y1414000D01*
G01X1317000Y1397900D02*
X1310000D01*
G01X1317000Y1414000D02*
Y1397900D01*
G01X1310000Y1414000D02*
X1317000D01*
G01X1302500Y1418350D02*
X1302458Y1418017D01*
X1302292Y1417725D01*
X1302042Y1417475D01*
X1301750Y1417308D01*
X1301417Y1417225D01*
X1301083D01*
X1300750Y1417308D01*
X1300458Y1417475D01*
X1300208Y1417725D01*
X1300042Y1418017D01*
X1300000Y1418350D01*
X1300042Y1418683D01*
X1300208Y1418975D01*
X1300458Y1419225D01*
X1300750Y1419392D01*
X1301083Y1419475D01*
X1301417D01*
X1301750Y1419392D01*
X1302042Y1419225D01*
X1302292Y1418975D01*
X1302458Y1418683D01*
X1302500Y1418350D01*
G01X1301833Y1418683D02*
X1302500Y1419183D01*
G01X1300417Y1420658D02*
X1300167Y1420908D01*
X1300042Y1421200D01*
X1300000Y1421533D01*
X1300083Y1421950D01*
X1300292Y1422242D01*
X1300542Y1422325D01*
X1300792Y1422283D01*
X1301000Y1422117D01*
X1301417Y1421283D01*
X1301708Y1420908D01*
X1302125Y1420658D01*
X1302500Y1420575D01*
Y1422325D01*
G01Y1424550D02*
X1300000D01*
X1300500Y1424050D01*
G01X1302500D02*
Y1425050D01*
G01X1302000Y1426733D02*
X1302292Y1426983D01*
X1302458Y1427317D01*
X1302500Y1427692D01*
X1302458Y1428025D01*
X1302250Y1428358D01*
X1302000Y1428567D01*
X1301750Y1428608D01*
X1301458Y1428525D01*
X1301250Y1428233D01*
X1301167Y1427942D01*
Y1427567D01*
G01Y1427942D02*
X1301042Y1428192D01*
X1300833Y1428400D01*
X1300583Y1428483D01*
X1300333Y1428400D01*
X1300125Y1428192D01*
X1300000Y1427817D01*
X1300042Y1427442D01*
X1300208Y1427067D01*
G01X1317000Y1418500D02*
Y1432500D01*
G01X1304000Y1418500D02*
X1317000D01*
G01X1304000Y1432500D02*
Y1418500D01*
G01X1403331Y1527769D02*
Y1470269D01*
X1387131D01*
Y1439269D01*
X1308931D01*
Y1470269D01*
X1292731D01*
Y1527769D01*
X1403331D01*
G01X1278021Y1449867D02*
X1277896Y1449617D01*
X1277813Y1449325D01*
Y1448992D01*
X1277938Y1448617D01*
X1278146Y1448325D01*
X1278396Y1448117D01*
X1278813Y1447950D01*
X1279188Y1447908D01*
X1279563Y1447992D01*
X1279813Y1448117D01*
X1280063Y1448367D01*
X1280230Y1448658D01*
X1280313Y1448950D01*
Y1449242D01*
X1280230Y1449533D01*
X1280105Y1449783D01*
X1279938Y1449992D01*
G01Y1451133D02*
X1280146Y1451383D01*
X1280271Y1451675D01*
X1280313Y1452050D01*
X1280230Y1452425D01*
X1280063Y1452717D01*
X1279771Y1452925D01*
X1279438Y1452967D01*
X1279105Y1452883D01*
X1278896Y1452675D01*
X1278730Y1452383D01*
X1278688Y1452092D01*
X1278730Y1451800D01*
X1278896Y1451425D01*
X1277813Y1451550D01*
Y1452675D01*
G01X1278230Y1454358D02*
X1277980Y1454608D01*
X1277855Y1454900D01*
X1277813Y1455233D01*
X1277896Y1455650D01*
X1278105Y1455942D01*
X1278355Y1456025D01*
X1278605Y1455983D01*
X1278813Y1455817D01*
X1279230Y1454983D01*
X1279521Y1454608D01*
X1279938Y1454358D01*
X1280313Y1454275D01*
Y1456025D01*
G01X1280021Y1457542D02*
X1280230Y1457833D01*
X1280313Y1458167D01*
X1280230Y1458500D01*
X1279980Y1458792D01*
X1279605Y1459000D01*
X1279230Y1459083D01*
X1278771D01*
X1278396Y1459000D01*
X1278063Y1458792D01*
X1277896Y1458542D01*
X1277813Y1458250D01*
X1277896Y1457917D01*
X1278063Y1457667D01*
X1278313Y1457500D01*
X1278646Y1457417D01*
X1278938Y1457500D01*
X1279230Y1457708D01*
X1279396Y1457958D01*
X1279438Y1458250D01*
X1279355Y1458583D01*
X1279146Y1458833D01*
X1278771Y1459083D01*
G01X1247782Y1460867D02*
X1247657Y1460617D01*
X1247574Y1460325D01*
Y1459992D01*
X1247699Y1459617D01*
X1247907Y1459325D01*
X1248157Y1459117D01*
X1248574Y1458950D01*
X1248949Y1458908D01*
X1249324Y1458992D01*
X1249574Y1459117D01*
X1249824Y1459367D01*
X1249991Y1459658D01*
X1250074Y1459950D01*
Y1460242D01*
X1249991Y1460533D01*
X1249866Y1460783D01*
X1249699Y1460992D01*
G01X1250074Y1462967D02*
X1249532Y1463050D01*
X1249074Y1463175D01*
X1248657Y1463342D01*
X1248199Y1463550D01*
X1247574Y1463883D01*
Y1462217D01*
G01X1250074Y1466150D02*
X1247574D01*
X1248074Y1465650D01*
G01X1250074D02*
Y1466650D01*
G01X1247991Y1468458D02*
X1247741Y1468708D01*
X1247616Y1469000D01*
X1247574Y1469333D01*
X1247657Y1469750D01*
X1247866Y1470042D01*
X1248116Y1470125D01*
X1248366Y1470083D01*
X1248574Y1469917D01*
X1248991Y1469083D01*
X1249282Y1468708D01*
X1249699Y1468458D01*
X1250074Y1468375D01*
Y1470125D01*
G01X1255291Y1503800D02*
Y1506300D01*
X1256332D01*
X1256666Y1506175D01*
X1256874Y1506008D01*
X1256957Y1505675D01*
X1256874Y1505342D01*
X1256624Y1505133D01*
X1256332Y1505008D01*
X1255291D01*
G01X1256332D02*
X1256957Y1503800D01*
G01X1259224D02*
Y1506300D01*
X1258724Y1505800D01*
G01Y1503800D02*
X1259724D01*
G01X1262324D02*
X1262616Y1503842D01*
X1262949Y1503967D01*
X1263157Y1504175D01*
X1263241Y1504467D01*
X1263157Y1504758D01*
X1262907Y1505008D01*
X1262532Y1505133D01*
X1262116D01*
X1261866Y1505217D01*
X1261657Y1505425D01*
X1261574Y1505717D01*
X1261699Y1506008D01*
X1261991Y1506217D01*
X1262324Y1506300D01*
X1262657Y1506217D01*
X1262949Y1506008D01*
X1263074Y1505717D01*
X1262991Y1505425D01*
X1262782Y1505217D01*
X1262532Y1505133D01*
X1262116D01*
X1261741Y1505008D01*
X1261491Y1504758D01*
X1261407Y1504467D01*
X1261491Y1504175D01*
X1261699Y1503967D01*
X1262032Y1503842D01*
X1262324Y1503800D01*
G01X1265424D02*
Y1506300D01*
X1264924Y1505800D01*
G01Y1503800D02*
X1265924D01*
G01X1257974Y1486900D02*
Y1482900D01*
X1265374D01*
G01X1276313Y1448117D02*
X1273813D01*
Y1449158D01*
X1273938Y1449492D01*
X1274105Y1449700D01*
X1274438Y1449783D01*
X1274771Y1449700D01*
X1274980Y1449450D01*
X1275105Y1449158D01*
Y1448117D01*
G01Y1449158D02*
X1276313Y1449783D01*
G01X1276021Y1451342D02*
X1276230Y1451633D01*
X1276313Y1451967D01*
X1276230Y1452300D01*
X1275980Y1452592D01*
X1275605Y1452800D01*
X1275230Y1452883D01*
X1274771D01*
X1274396Y1452800D01*
X1274063Y1452592D01*
X1273896Y1452342D01*
X1273813Y1452050D01*
X1273896Y1451717D01*
X1274063Y1451467D01*
X1274313Y1451300D01*
X1274646Y1451217D01*
X1274938Y1451300D01*
X1275230Y1451508D01*
X1275396Y1451758D01*
X1275438Y1452050D01*
X1275355Y1452383D01*
X1275146Y1452633D01*
X1274771Y1452883D01*
G01X1276313Y1455650D02*
X1273813D01*
X1275605Y1454108D01*
Y1456192D01*
G01X1274230Y1457458D02*
X1273980Y1457708D01*
X1273855Y1458000D01*
X1273813Y1458333D01*
X1273896Y1458750D01*
X1274105Y1459042D01*
X1274355Y1459125D01*
X1274605Y1459083D01*
X1274813Y1458917D01*
X1275230Y1458083D01*
X1275521Y1457708D01*
X1275938Y1457458D01*
X1276313Y1457375D01*
Y1459125D01*
G01X1294374Y1451800D02*
X1298374D01*
Y1459200D01*
G01X1279491Y1489900D02*
Y1492400D01*
X1280532D01*
X1280866Y1492275D01*
X1281074Y1492108D01*
X1281157Y1491775D01*
X1281074Y1491442D01*
X1280824Y1491233D01*
X1280532Y1491108D01*
X1279491D01*
G01X1280532D02*
X1281157Y1489900D01*
G01X1282716Y1490192D02*
X1283007Y1489983D01*
X1283341Y1489900D01*
X1283674Y1489983D01*
X1283966Y1490233D01*
X1284174Y1490608D01*
X1284257Y1490983D01*
Y1491442D01*
X1284174Y1491817D01*
X1283966Y1492150D01*
X1283716Y1492317D01*
X1283424Y1492400D01*
X1283091Y1492317D01*
X1282841Y1492150D01*
X1282674Y1491900D01*
X1282591Y1491567D01*
X1282674Y1491275D01*
X1282882Y1490983D01*
X1283132Y1490817D01*
X1283424Y1490775D01*
X1283757Y1490858D01*
X1284007Y1491067D01*
X1284257Y1491442D01*
G01X1287024Y1489900D02*
Y1492400D01*
X1285482Y1490608D01*
X1287566D01*
G01X1290124Y1489900D02*
Y1492400D01*
X1288582Y1490608D01*
X1290666D01*
G01X1282674Y1482000D02*
Y1478000D01*
X1290074D01*
G01X1279491Y1485700D02*
Y1488200D01*
X1280532D01*
X1280866Y1488075D01*
X1281074Y1487908D01*
X1281157Y1487575D01*
X1281074Y1487242D01*
X1280824Y1487033D01*
X1280532Y1486908D01*
X1279491D01*
G01X1280532D02*
X1281157Y1485700D01*
G01X1282716Y1485992D02*
X1283007Y1485783D01*
X1283341Y1485700D01*
X1283674Y1485783D01*
X1283966Y1486033D01*
X1284174Y1486408D01*
X1284257Y1486783D01*
Y1487242D01*
X1284174Y1487617D01*
X1283966Y1487950D01*
X1283716Y1488117D01*
X1283424Y1488200D01*
X1283091Y1488117D01*
X1282841Y1487950D01*
X1282674Y1487700D01*
X1282591Y1487367D01*
X1282674Y1487075D01*
X1282882Y1486783D01*
X1283132Y1486617D01*
X1283424Y1486575D01*
X1283757Y1486658D01*
X1284007Y1486867D01*
X1284257Y1487242D01*
G01X1287024Y1485700D02*
Y1488200D01*
X1285482Y1486408D01*
X1287566D01*
G01X1288832Y1486742D02*
X1289124Y1487033D01*
X1289374Y1487200D01*
X1289707Y1487283D01*
X1289999Y1487200D01*
X1290207Y1487033D01*
X1290374Y1486783D01*
X1290416Y1486492D01*
X1290374Y1486242D01*
X1290207Y1485992D01*
X1289957Y1485783D01*
X1289666Y1485700D01*
X1289332Y1485783D01*
X1289041Y1486033D01*
X1288874Y1486408D01*
X1288832Y1486825D01*
X1288916Y1487367D01*
X1289041Y1487658D01*
X1289249Y1487950D01*
X1289541Y1488158D01*
X1289832Y1488200D01*
X1290124Y1488117D01*
X1290332Y1487908D01*
G01X1290074Y1469500D02*
Y1473500D01*
X1282674D01*
G01X1262191Y1440500D02*
Y1443000D01*
X1263232D01*
X1263566Y1442875D01*
X1263774Y1442708D01*
X1263857Y1442375D01*
X1263774Y1442042D01*
X1263524Y1441833D01*
X1263232Y1441708D01*
X1262191D01*
G01X1263232D02*
X1263857Y1440500D01*
G01X1265416Y1440792D02*
X1265707Y1440583D01*
X1266041Y1440500D01*
X1266374Y1440583D01*
X1266666Y1440833D01*
X1266874Y1441208D01*
X1266957Y1441583D01*
Y1442042D01*
X1266874Y1442417D01*
X1266666Y1442750D01*
X1266416Y1442917D01*
X1266124Y1443000D01*
X1265791Y1442917D01*
X1265541Y1442750D01*
X1265374Y1442500D01*
X1265291Y1442167D01*
X1265374Y1441875D01*
X1265582Y1441583D01*
X1265832Y1441417D01*
X1266124Y1441375D01*
X1266457Y1441458D01*
X1266707Y1441667D01*
X1266957Y1442042D01*
G01X1269724Y1440500D02*
Y1443000D01*
X1268182Y1441208D01*
X1270266D01*
G01X1272241Y1440500D02*
X1272324Y1441042D01*
X1272449Y1441500D01*
X1272616Y1441917D01*
X1272824Y1442375D01*
X1273157Y1443000D01*
X1271491D01*
G01X1291074Y1450500D02*
Y1454500D01*
X1283674D01*
G01X1294374Y1433300D02*
X1298374D01*
Y1440700D01*
G01X1291074Y1432000D02*
Y1436000D01*
X1283674D01*
G01X1269841Y1499300D02*
Y1501800D01*
X1270882D01*
X1271216Y1501675D01*
X1271424Y1501508D01*
X1271507Y1501175D01*
X1271424Y1500842D01*
X1271174Y1500633D01*
X1270882Y1500508D01*
X1269841D01*
G01X1270882D02*
X1271507Y1499300D01*
G01X1273774D02*
Y1501800D01*
X1273274Y1501300D01*
G01Y1499300D02*
X1274274D01*
G01X1276082Y1501383D02*
X1276332Y1501633D01*
X1276624Y1501758D01*
X1276957Y1501800D01*
X1277374Y1501717D01*
X1277666Y1501508D01*
X1277749Y1501258D01*
X1277707Y1501008D01*
X1277541Y1500800D01*
X1276707Y1500383D01*
X1276332Y1500092D01*
X1276082Y1499675D01*
X1275999Y1499300D01*
X1277749D01*
G01X1279266Y1499592D02*
X1279557Y1499383D01*
X1279891Y1499300D01*
X1280224Y1499383D01*
X1280516Y1499633D01*
X1280724Y1500008D01*
X1280807Y1500383D01*
Y1500842D01*
X1280724Y1501217D01*
X1280516Y1501550D01*
X1280266Y1501717D01*
X1279974Y1501800D01*
X1279641Y1501717D01*
X1279391Y1501550D01*
X1279224Y1501300D01*
X1279141Y1500967D01*
X1279224Y1500675D01*
X1279432Y1500383D01*
X1279682Y1500217D01*
X1279974Y1500175D01*
X1280307Y1500258D01*
X1280557Y1500467D01*
X1280807Y1500842D01*
G01X1282366Y1499592D02*
X1282657Y1499383D01*
X1282991Y1499300D01*
X1283324Y1499383D01*
X1283616Y1499633D01*
X1283824Y1500008D01*
X1283907Y1500383D01*
Y1500842D01*
X1283824Y1501217D01*
X1283616Y1501550D01*
X1283366Y1501717D01*
X1283074Y1501800D01*
X1282741Y1501717D01*
X1282491Y1501550D01*
X1282324Y1501300D01*
X1282241Y1500967D01*
X1282324Y1500675D01*
X1282532Y1500383D01*
X1282782Y1500217D01*
X1283074Y1500175D01*
X1283407Y1500258D01*
X1283657Y1500467D01*
X1283907Y1500842D01*
G01X1269374Y1490600D02*
Y1486600D01*
X1276774D01*
G01X1249874Y1488067D02*
X1247374D01*
Y1489108D01*
X1247499Y1489442D01*
X1247666Y1489650D01*
X1247999Y1489733D01*
X1248332Y1489650D01*
X1248541Y1489400D01*
X1248666Y1489108D01*
Y1488067D01*
G01Y1489108D02*
X1249874Y1489733D01*
G01Y1492000D02*
X1247374D01*
X1247874Y1491500D01*
G01X1249874D02*
Y1492500D01*
G01X1249374Y1494183D02*
X1249666Y1494433D01*
X1249832Y1494767D01*
X1249874Y1495142D01*
X1249832Y1495475D01*
X1249624Y1495808D01*
X1249374Y1496017D01*
X1249124Y1496058D01*
X1248832Y1495975D01*
X1248624Y1495683D01*
X1248541Y1495392D01*
Y1495017D01*
G01Y1495392D02*
X1248416Y1495642D01*
X1248207Y1495850D01*
X1247957Y1495933D01*
X1247707Y1495850D01*
X1247499Y1495642D01*
X1247374Y1495267D01*
X1247416Y1494892D01*
X1247582Y1494517D01*
G01X1247374Y1498200D02*
X1247457Y1497867D01*
X1247666Y1497617D01*
X1247916Y1497450D01*
X1248249Y1497325D01*
X1248624Y1497283D01*
X1248999Y1497325D01*
X1249332Y1497450D01*
X1249582Y1497617D01*
X1249791Y1497867D01*
X1249874Y1498200D01*
X1249791Y1498533D01*
X1249582Y1498783D01*
X1249332Y1498950D01*
X1248999Y1499075D01*
X1248624Y1499117D01*
X1248249Y1499075D01*
X1247916Y1498950D01*
X1247666Y1498783D01*
X1247457Y1498533D01*
X1247374Y1498200D01*
G01X1249374Y1500383D02*
X1249666Y1500633D01*
X1249832Y1500967D01*
X1249874Y1501342D01*
X1249832Y1501675D01*
X1249624Y1502008D01*
X1249374Y1502217D01*
X1249124Y1502258D01*
X1248832Y1502175D01*
X1248624Y1501883D01*
X1248541Y1501592D01*
Y1501217D01*
G01Y1501592D02*
X1248416Y1501842D01*
X1248207Y1502050D01*
X1247957Y1502133D01*
X1247707Y1502050D01*
X1247499Y1501842D01*
X1247374Y1501467D01*
X1247416Y1501092D01*
X1247582Y1500717D01*
G01X1253874Y1486385D02*
X1249874D01*
Y1478985D01*
G01X1269741Y1495600D02*
Y1498100D01*
X1270782D01*
X1271116Y1497975D01*
X1271324Y1497808D01*
X1271407Y1497475D01*
X1271324Y1497142D01*
X1271074Y1496933D01*
X1270782Y1496808D01*
X1269741D01*
G01X1270782D02*
X1271407Y1495600D01*
G01X1273674D02*
Y1498100D01*
X1273174Y1497600D01*
G01Y1495600D02*
X1274174D01*
G01X1275857Y1496100D02*
X1276107Y1495808D01*
X1276441Y1495642D01*
X1276816Y1495600D01*
X1277149Y1495642D01*
X1277482Y1495850D01*
X1277691Y1496100D01*
X1277732Y1496350D01*
X1277649Y1496642D01*
X1277357Y1496850D01*
X1277066Y1496933D01*
X1276691D01*
G01X1277066D02*
X1277316Y1497058D01*
X1277524Y1497267D01*
X1277607Y1497517D01*
X1277524Y1497767D01*
X1277316Y1497975D01*
X1276941Y1498100D01*
X1276566Y1498058D01*
X1276191Y1497892D01*
G01X1279874Y1498100D02*
X1279541Y1498017D01*
X1279291Y1497808D01*
X1279124Y1497558D01*
X1278999Y1497225D01*
X1278957Y1496850D01*
X1278999Y1496475D01*
X1279124Y1496142D01*
X1279291Y1495892D01*
X1279541Y1495683D01*
X1279874Y1495600D01*
X1280207Y1495683D01*
X1280457Y1495892D01*
X1280624Y1496142D01*
X1280749Y1496475D01*
X1280791Y1496850D01*
X1280749Y1497225D01*
X1280624Y1497558D01*
X1280457Y1497808D01*
X1280207Y1498017D01*
X1279874Y1498100D01*
G01X1282891Y1495600D02*
X1282974Y1496142D01*
X1283099Y1496600D01*
X1283266Y1497017D01*
X1283474Y1497475D01*
X1283807Y1498100D01*
X1282141D01*
G01X1276789Y1481400D02*
Y1485400D01*
X1269389D01*
G01X1262191Y1444661D02*
Y1447161D01*
X1263232D01*
X1263566Y1447036D01*
X1263774Y1446869D01*
X1263857Y1446536D01*
X1263774Y1446203D01*
X1263524Y1445994D01*
X1263232Y1445869D01*
X1262191D01*
G01X1263232D02*
X1263857Y1444661D01*
G01X1265416Y1444953D02*
X1265707Y1444744D01*
X1266041Y1444661D01*
X1266374Y1444744D01*
X1266666Y1444994D01*
X1266874Y1445369D01*
X1266957Y1445744D01*
Y1446203D01*
X1266874Y1446578D01*
X1266666Y1446911D01*
X1266416Y1447078D01*
X1266124Y1447161D01*
X1265791Y1447078D01*
X1265541Y1446911D01*
X1265374Y1446661D01*
X1265291Y1446328D01*
X1265374Y1446036D01*
X1265582Y1445744D01*
X1265832Y1445578D01*
X1266124Y1445536D01*
X1266457Y1445619D01*
X1266707Y1445828D01*
X1266957Y1446203D01*
G01X1269724Y1444661D02*
Y1447161D01*
X1268182Y1445369D01*
X1270266D01*
G01X1271407Y1445036D02*
X1271657Y1444828D01*
X1271949Y1444703D01*
X1272324Y1444661D01*
X1272699Y1444744D01*
X1272991Y1444911D01*
X1273199Y1445203D01*
X1273241Y1445536D01*
X1273157Y1445869D01*
X1272949Y1446078D01*
X1272657Y1446244D01*
X1272366Y1446286D01*
X1272074Y1446244D01*
X1271699Y1446078D01*
X1271824Y1447161D01*
X1272949D01*
G01X1261391Y1430300D02*
Y1432800D01*
X1262432D01*
X1262766Y1432675D01*
X1262974Y1432508D01*
X1263057Y1432175D01*
X1262974Y1431842D01*
X1262724Y1431633D01*
X1262432Y1431508D01*
X1261391D01*
G01X1262432D02*
X1263057Y1430300D01*
G01X1264616Y1430592D02*
X1264907Y1430383D01*
X1265241Y1430300D01*
X1265574Y1430383D01*
X1265866Y1430633D01*
X1266074Y1431008D01*
X1266157Y1431383D01*
Y1431842D01*
X1266074Y1432217D01*
X1265866Y1432550D01*
X1265616Y1432717D01*
X1265324Y1432800D01*
X1264991Y1432717D01*
X1264741Y1432550D01*
X1264574Y1432300D01*
X1264491Y1431967D01*
X1264574Y1431675D01*
X1264782Y1431383D01*
X1265032Y1431217D01*
X1265324Y1431175D01*
X1265657Y1431258D01*
X1265907Y1431467D01*
X1266157Y1431842D01*
G01X1267507Y1430675D02*
X1267757Y1430467D01*
X1268049Y1430342D01*
X1268424Y1430300D01*
X1268799Y1430383D01*
X1269091Y1430550D01*
X1269299Y1430842D01*
X1269341Y1431175D01*
X1269257Y1431508D01*
X1269049Y1431717D01*
X1268757Y1431883D01*
X1268466Y1431925D01*
X1268174Y1431883D01*
X1267799Y1431717D01*
X1267924Y1432800D01*
X1269049D01*
G01X1271524D02*
X1271191Y1432717D01*
X1270941Y1432508D01*
X1270774Y1432258D01*
X1270649Y1431925D01*
X1270607Y1431550D01*
X1270649Y1431175D01*
X1270774Y1430842D01*
X1270941Y1430592D01*
X1271191Y1430383D01*
X1271524Y1430300D01*
X1271857Y1430383D01*
X1272107Y1430592D01*
X1272274Y1430842D01*
X1272399Y1431175D01*
X1272441Y1431550D01*
X1272399Y1431925D01*
X1272274Y1432258D01*
X1272107Y1432508D01*
X1271857Y1432717D01*
X1271524Y1432800D01*
G01X1270324Y1474100D02*
X1269991Y1474142D01*
X1269699Y1474308D01*
X1269449Y1474558D01*
X1269282Y1474850D01*
X1269199Y1475183D01*
Y1475517D01*
X1269282Y1475850D01*
X1269449Y1476142D01*
X1269699Y1476392D01*
X1269991Y1476558D01*
X1270324Y1476600D01*
X1270657Y1476558D01*
X1270949Y1476392D01*
X1271199Y1476142D01*
X1271366Y1475850D01*
X1271449Y1475517D01*
Y1475183D01*
X1271366Y1474850D01*
X1271199Y1474558D01*
X1270949Y1474308D01*
X1270657Y1474142D01*
X1270324Y1474100D01*
G01X1270657Y1474767D02*
X1271157Y1474100D01*
G01X1272632Y1476183D02*
X1272882Y1476433D01*
X1273174Y1476558D01*
X1273507Y1476600D01*
X1273924Y1476517D01*
X1274216Y1476308D01*
X1274299Y1476058D01*
X1274257Y1475808D01*
X1274091Y1475600D01*
X1273257Y1475183D01*
X1272882Y1474892D01*
X1272632Y1474475D01*
X1272549Y1474100D01*
X1274299D01*
G01X1276524D02*
Y1476600D01*
X1276024Y1476100D01*
G01Y1474100D02*
X1277024D01*
G01X1279541D02*
X1279624Y1474642D01*
X1279749Y1475100D01*
X1279916Y1475517D01*
X1280124Y1475975D01*
X1280457Y1476600D01*
X1278791D01*
G01X1254374Y1482100D02*
Y1470700D01*
G01X1267774Y1482100D02*
X1254374D01*
G01X1267774Y1470700D02*
Y1482100D01*
G01X1254374Y1470700D02*
X1267774D01*
G01X1271657Y1462900D02*
Y1465400D01*
X1272491D01*
X1272824Y1465275D01*
X1273074Y1465108D01*
X1273282Y1464858D01*
X1273449Y1464567D01*
X1273491Y1464150D01*
X1273449Y1463733D01*
X1273282Y1463442D01*
X1273074Y1463192D01*
X1272824Y1463025D01*
X1272491Y1462900D01*
X1271657D01*
G01X1276174D02*
Y1465400D01*
X1274632Y1463608D01*
X1276716D01*
G01X1278774Y1462900D02*
Y1465400D01*
X1278274Y1464900D01*
G01Y1462900D02*
X1279274D01*
G01X1283374Y1460000D02*
X1304374D01*
G01D02*
Y1468000D01*
G01D02*
X1283374D01*
G01D02*
Y1460000D01*
G01X1261483Y1435000D02*
Y1437500D01*
X1262317D01*
X1262650Y1437375D01*
X1262900Y1437208D01*
X1263108Y1436958D01*
X1263275Y1436667D01*
X1263317Y1436250D01*
X1263275Y1435833D01*
X1263108Y1435542D01*
X1262900Y1435292D01*
X1262650Y1435125D01*
X1262317Y1435000D01*
X1261483D01*
G01X1266000D02*
Y1437500D01*
X1264458Y1435708D01*
X1266542D01*
G01X1267808Y1437083D02*
X1268058Y1437333D01*
X1268350Y1437458D01*
X1268683Y1437500D01*
X1269100Y1437417D01*
X1269392Y1437208D01*
X1269475Y1436958D01*
X1269433Y1436708D01*
X1269267Y1436500D01*
X1268433Y1436083D01*
X1268058Y1435792D01*
X1267808Y1435375D01*
X1267725Y1435000D01*
X1269475D01*
G01X1283374Y1441500D02*
X1304374D01*
G01D02*
Y1449500D01*
G01D02*
X1283374D01*
G01D02*
Y1441500D01*
G01X1317000Y1432500D02*
X1304000D01*
G01X1247057Y1456200D02*
Y1454408D01*
X1247224Y1454033D01*
X1247557Y1453783D01*
X1247974Y1453700D01*
X1248391Y1453783D01*
X1248724Y1454033D01*
X1248891Y1454408D01*
Y1456200D01*
G01X1250157Y1454075D02*
X1250407Y1453867D01*
X1250699Y1453742D01*
X1251074Y1453700D01*
X1251449Y1453783D01*
X1251741Y1453950D01*
X1251949Y1454242D01*
X1251991Y1454575D01*
X1251907Y1454908D01*
X1251699Y1455117D01*
X1251407Y1455283D01*
X1251116Y1455325D01*
X1250824Y1455283D01*
X1250449Y1455117D01*
X1250574Y1456200D01*
X1251699D01*
G01X1254174Y1453700D02*
Y1456200D01*
X1253674Y1455700D01*
G01Y1453700D02*
X1254674D01*
G01X1267174Y1467500D02*
Y1454100D01*
G01X1257174Y1467500D02*
X1267174D01*
G01X1257174Y1454100D02*
Y1467500D01*
G01X1267174Y1454100D02*
X1257174D01*
G01X1245374Y1462000D02*
Y1469000D01*
G01Y1469700D02*
Y1476700D01*
G01X1270622Y1504098D02*
X1270289Y1504140D01*
X1269997Y1504306D01*
X1269747Y1504556D01*
X1269580Y1504848D01*
X1269497Y1505181D01*
Y1505515D01*
X1269580Y1505848D01*
X1269747Y1506140D01*
X1269997Y1506390D01*
X1270289Y1506556D01*
X1270622Y1506598D01*
X1270955Y1506556D01*
X1271247Y1506390D01*
X1271497Y1506140D01*
X1271664Y1505848D01*
X1271747Y1505515D01*
Y1505181D01*
X1271664Y1504848D01*
X1271497Y1504556D01*
X1271247Y1504306D01*
X1270955Y1504140D01*
X1270622Y1504098D01*
G01X1270955Y1504765D02*
X1271455Y1504098D01*
G01X1272930Y1506181D02*
X1273180Y1506431D01*
X1273472Y1506556D01*
X1273805Y1506598D01*
X1274222Y1506515D01*
X1274514Y1506306D01*
X1274597Y1506056D01*
X1274555Y1505806D01*
X1274389Y1505598D01*
X1273555Y1505181D01*
X1273180Y1504890D01*
X1272930Y1504473D01*
X1272847Y1504098D01*
X1274597D01*
G01X1276822Y1506598D02*
X1276489Y1506515D01*
X1276239Y1506306D01*
X1276072Y1506056D01*
X1275947Y1505723D01*
X1275905Y1505348D01*
X1275947Y1504973D01*
X1276072Y1504640D01*
X1276239Y1504390D01*
X1276489Y1504181D01*
X1276822Y1504098D01*
X1277155Y1504181D01*
X1277405Y1504390D01*
X1277572Y1504640D01*
X1277697Y1504973D01*
X1277739Y1505348D01*
X1277697Y1505723D01*
X1277572Y1506056D01*
X1277405Y1506306D01*
X1277155Y1506515D01*
X1276822Y1506598D01*
G01X1279130Y1505140D02*
X1279422Y1505431D01*
X1279672Y1505598D01*
X1280005Y1505681D01*
X1280297Y1505598D01*
X1280505Y1505431D01*
X1280672Y1505181D01*
X1280714Y1504890D01*
X1280672Y1504640D01*
X1280505Y1504390D01*
X1280255Y1504181D01*
X1279964Y1504098D01*
X1279630Y1504181D01*
X1279339Y1504431D01*
X1279172Y1504806D01*
X1279130Y1505223D01*
X1279214Y1505765D01*
X1279339Y1506056D01*
X1279547Y1506348D01*
X1279839Y1506556D01*
X1280130Y1506598D01*
X1280422Y1506515D01*
X1280630Y1506306D01*
G01X1262409Y1487400D02*
Y1487660D01*
X1260974Y1489095D01*
X1259539Y1487660D01*
G01X1262409Y1487400D02*
X1259539D01*
Y1498400D01*
G01X1262409D02*
Y1487400D01*
G01Y1498400D02*
X1259539D01*
G01X1389006Y107319D02*
X1394056D01*
Y206019D01*
X1418706D01*
Y21619D01*
X1394056D01*
Y80319D01*
X1389006D01*
Y107319D01*
G01X1376258Y63472D02*
X1376008Y63597D01*
X1375716Y63680D01*
X1375383D01*
X1375008Y63555D01*
X1374716Y63347D01*
X1374508Y63097D01*
X1374341Y62680D01*
X1374299Y62305D01*
X1374383Y61930D01*
X1374508Y61680D01*
X1374758Y61430D01*
X1375049Y61263D01*
X1375341Y61180D01*
X1375633D01*
X1375924Y61263D01*
X1376174Y61388D01*
X1376383Y61555D01*
G01X1378941Y61180D02*
Y63680D01*
X1377399Y61888D01*
X1379483D01*
G01X1380624Y61680D02*
X1380874Y61388D01*
X1381208Y61222D01*
X1381583Y61180D01*
X1381916Y61222D01*
X1382249Y61430D01*
X1382458Y61680D01*
X1382499Y61930D01*
X1382416Y62222D01*
X1382124Y62430D01*
X1381833Y62513D01*
X1381458D01*
G01X1381833D02*
X1382083Y62638D01*
X1382291Y62847D01*
X1382374Y63097D01*
X1382291Y63347D01*
X1382083Y63555D01*
X1381708Y63680D01*
X1381333Y63638D01*
X1380958Y63472D01*
G01X1383849Y63263D02*
X1384099Y63513D01*
X1384391Y63638D01*
X1384724Y63680D01*
X1385141Y63597D01*
X1385433Y63388D01*
X1385516Y63138D01*
X1385474Y62888D01*
X1385308Y62680D01*
X1384474Y62263D01*
X1384099Y61972D01*
X1383849Y61555D01*
X1383766Y61180D01*
X1385516D01*
G01X1376267Y67592D02*
X1376017Y67717D01*
X1375725Y67800D01*
X1375392D01*
X1375017Y67675D01*
X1374725Y67467D01*
X1374517Y67217D01*
X1374350Y66800D01*
X1374308Y66425D01*
X1374392Y66050D01*
X1374517Y65800D01*
X1374767Y65550D01*
X1375058Y65383D01*
X1375350Y65300D01*
X1375642D01*
X1375933Y65383D01*
X1376183Y65508D01*
X1376392Y65675D01*
G01X1378950Y65300D02*
Y67800D01*
X1377408Y66008D01*
X1379492D01*
G01X1380633Y65800D02*
X1380883Y65508D01*
X1381217Y65342D01*
X1381592Y65300D01*
X1381925Y65342D01*
X1382258Y65550D01*
X1382467Y65800D01*
X1382508Y66050D01*
X1382425Y66342D01*
X1382133Y66550D01*
X1381842Y66633D01*
X1381467D01*
G01X1381842D02*
X1382092Y66758D01*
X1382300Y66967D01*
X1382383Y67217D01*
X1382300Y67467D01*
X1382092Y67675D01*
X1381717Y67800D01*
X1381342Y67758D01*
X1380967Y67592D01*
G01X1384650Y65300D02*
Y67800D01*
X1384150Y67300D01*
G01Y65300D02*
X1385150D01*
G01X1421208Y82767D02*
X1421083Y82517D01*
X1421000Y82225D01*
Y81892D01*
X1421125Y81517D01*
X1421333Y81225D01*
X1421583Y81017D01*
X1422000Y80850D01*
X1422375Y80808D01*
X1422750Y80892D01*
X1423000Y81017D01*
X1423250Y81267D01*
X1423417Y81558D01*
X1423500Y81850D01*
Y82142D01*
X1423417Y82433D01*
X1423292Y82683D01*
X1423125Y82892D01*
G01X1423500Y85450D02*
X1421000D01*
X1422792Y83908D01*
Y85992D01*
G01X1423500Y88550D02*
X1421000D01*
X1422792Y87008D01*
Y89092D01*
G01X1423500Y91150D02*
X1421000D01*
X1421500Y90650D01*
G01X1423500D02*
Y91650D01*
G01Y68017D02*
X1421000D01*
Y69058D01*
X1421125Y69392D01*
X1421292Y69600D01*
X1421625Y69683D01*
X1421958Y69600D01*
X1422167Y69350D01*
X1422292Y69058D01*
Y68017D01*
G01Y69058D02*
X1423500Y69683D01*
G01Y71867D02*
X1422958Y71950D01*
X1422500Y72075D01*
X1422083Y72242D01*
X1421625Y72450D01*
X1421000Y72783D01*
Y71117D01*
G01X1423208Y74342D02*
X1423417Y74633D01*
X1423500Y74967D01*
X1423417Y75300D01*
X1423167Y75592D01*
X1422792Y75800D01*
X1422417Y75883D01*
X1421958D01*
X1421583Y75800D01*
X1421250Y75592D01*
X1421083Y75342D01*
X1421000Y75050D01*
X1421083Y74717D01*
X1421250Y74467D01*
X1421500Y74300D01*
X1421833Y74217D01*
X1422125Y74300D01*
X1422417Y74508D01*
X1422583Y74758D01*
X1422625Y75050D01*
X1422542Y75383D01*
X1422333Y75633D01*
X1421958Y75883D01*
G01X1421000Y78150D02*
X1421083Y77817D01*
X1421292Y77567D01*
X1421542Y77400D01*
X1421875Y77275D01*
X1422250Y77233D01*
X1422625Y77275D01*
X1422958Y77400D01*
X1423208Y77567D01*
X1423417Y77817D01*
X1423500Y78150D01*
X1423417Y78483D01*
X1423208Y78733D01*
X1422958Y78900D01*
X1422625Y79025D01*
X1422250Y79067D01*
X1421875Y79025D01*
X1421542Y78900D01*
X1421292Y78733D01*
X1421083Y78483D01*
X1421000Y78150D01*
G01X1437700Y75000D02*
Y79000D01*
X1430300D01*
G01X1428500Y42017D02*
X1426000D01*
Y43058D01*
X1426125Y43392D01*
X1426292Y43600D01*
X1426625Y43683D01*
X1426958Y43600D01*
X1427167Y43350D01*
X1427292Y43058D01*
Y42017D01*
G01Y43058D02*
X1428500Y43683D01*
G01Y45867D02*
X1427958Y45950D01*
X1427500Y46075D01*
X1427083Y46242D01*
X1426625Y46450D01*
X1426000Y46783D01*
Y45117D01*
G01X1428208Y48342D02*
X1428417Y48633D01*
X1428500Y48967D01*
X1428417Y49300D01*
X1428167Y49592D01*
X1427792Y49800D01*
X1427417Y49883D01*
X1426958D01*
X1426583Y49800D01*
X1426250Y49592D01*
X1426083Y49342D01*
X1426000Y49050D01*
X1426083Y48717D01*
X1426250Y48467D01*
X1426500Y48300D01*
X1426833Y48217D01*
X1427125Y48300D01*
X1427417Y48508D01*
X1427583Y48758D01*
X1427625Y49050D01*
X1427542Y49383D01*
X1427333Y49633D01*
X1426958Y49883D01*
G01X1428500Y52150D02*
X1426000D01*
X1426500Y51650D01*
G01X1428500D02*
Y52650D01*
G01X1434000Y49800D02*
X1438000D01*
Y57200D01*
G01X1424500Y42017D02*
X1422000D01*
Y43058D01*
X1422125Y43392D01*
X1422292Y43600D01*
X1422625Y43683D01*
X1422958Y43600D01*
X1423167Y43350D01*
X1423292Y43058D01*
Y42017D01*
G01Y43058D02*
X1424500Y43683D01*
G01Y45867D02*
X1423958Y45950D01*
X1423500Y46075D01*
X1423083Y46242D01*
X1422625Y46450D01*
X1422000Y46783D01*
Y45117D01*
G01X1424208Y48342D02*
X1424417Y48633D01*
X1424500Y48967D01*
X1424417Y49300D01*
X1424167Y49592D01*
X1423792Y49800D01*
X1423417Y49883D01*
X1422958D01*
X1422583Y49800D01*
X1422250Y49592D01*
X1422083Y49342D01*
X1422000Y49050D01*
X1422083Y48717D01*
X1422250Y48467D01*
X1422500Y48300D01*
X1422833Y48217D01*
X1423125Y48300D01*
X1423417Y48508D01*
X1423583Y48758D01*
X1423625Y49050D01*
X1423542Y49383D01*
X1423333Y49633D01*
X1422958Y49883D01*
G01X1424125Y51233D02*
X1424333Y51483D01*
X1424458Y51775D01*
X1424500Y52150D01*
X1424417Y52525D01*
X1424250Y52817D01*
X1423958Y53025D01*
X1423625Y53067D01*
X1423292Y52983D01*
X1423083Y52775D01*
X1422917Y52483D01*
X1422875Y52192D01*
X1422917Y51900D01*
X1423083Y51525D01*
X1422000Y51650D01*
Y52775D01*
G01X1433500Y57200D02*
X1429500D01*
Y49800D01*
G01X1423500Y55850D02*
X1423458Y55517D01*
X1423292Y55225D01*
X1423042Y54975D01*
X1422750Y54808D01*
X1422417Y54725D01*
X1422083D01*
X1421750Y54808D01*
X1421458Y54975D01*
X1421208Y55225D01*
X1421042Y55517D01*
X1421000Y55850D01*
X1421042Y56183D01*
X1421208Y56475D01*
X1421458Y56725D01*
X1421750Y56892D01*
X1422083Y56975D01*
X1422417D01*
X1422750Y56892D01*
X1423042Y56725D01*
X1423292Y56475D01*
X1423458Y56183D01*
X1423500Y55850D01*
G01X1422833Y56183D02*
X1423500Y56683D01*
G01Y58950D02*
X1421000D01*
X1421500Y58450D01*
G01X1423500D02*
Y59450D01*
G01X1422458Y61258D02*
X1422167Y61550D01*
X1422000Y61800D01*
X1421917Y62133D01*
X1422000Y62425D01*
X1422167Y62633D01*
X1422417Y62800D01*
X1422708Y62842D01*
X1422958Y62800D01*
X1423208Y62633D01*
X1423417Y62383D01*
X1423500Y62092D01*
X1423417Y61758D01*
X1423167Y61467D01*
X1422792Y61300D01*
X1422375Y61258D01*
X1421833Y61342D01*
X1421542Y61467D01*
X1421250Y61675D01*
X1421042Y61967D01*
X1421000Y62258D01*
X1421083Y62550D01*
X1421292Y62758D01*
G01X1423500Y65150D02*
X1421000D01*
X1421500Y64650D01*
G01X1423500D02*
Y65650D01*
G01X1424800Y69700D02*
Y58300D01*
G01X1438200Y69700D02*
X1424800D01*
G01Y58300D02*
X1438200D01*
G01X1346167Y112553D02*
X1345917Y112678D01*
X1345625Y112761D01*
X1345292D01*
X1344917Y112636D01*
X1344625Y112428D01*
X1344417Y112178D01*
X1344250Y111761D01*
X1344208Y111386D01*
X1344292Y111011D01*
X1344417Y110761D01*
X1344667Y110511D01*
X1344958Y110344D01*
X1345250Y110261D01*
X1345542D01*
X1345833Y110344D01*
X1346083Y110469D01*
X1346292Y110636D01*
G01X1348850Y110261D02*
Y112761D01*
X1347308Y110969D01*
X1349392D01*
G01X1350658Y112344D02*
X1350908Y112594D01*
X1351200Y112719D01*
X1351533Y112761D01*
X1351950Y112678D01*
X1352242Y112469D01*
X1352325Y112219D01*
X1352283Y111969D01*
X1352117Y111761D01*
X1351283Y111344D01*
X1350908Y111053D01*
X1350658Y110636D01*
X1350575Y110261D01*
X1352325D01*
G01X1353842Y110553D02*
X1354133Y110344D01*
X1354467Y110261D01*
X1354800Y110344D01*
X1355092Y110594D01*
X1355300Y110969D01*
X1355383Y111344D01*
Y111803D01*
X1355300Y112178D01*
X1355092Y112511D01*
X1354842Y112678D01*
X1354550Y112761D01*
X1354217Y112678D01*
X1353967Y112511D01*
X1353800Y112261D01*
X1353717Y111928D01*
X1353800Y111636D01*
X1354008Y111344D01*
X1354258Y111178D01*
X1354550Y111136D01*
X1354883Y111219D01*
X1355133Y111428D01*
X1355383Y111803D01*
G01X1389747Y131367D02*
X1389622Y131117D01*
X1389539Y130825D01*
Y130492D01*
X1389664Y130117D01*
X1389872Y129825D01*
X1390122Y129617D01*
X1390539Y129450D01*
X1390914Y129408D01*
X1391289Y129492D01*
X1391539Y129617D01*
X1391789Y129867D01*
X1391956Y130158D01*
X1392039Y130450D01*
Y130742D01*
X1391956Y131033D01*
X1391831Y131283D01*
X1391664Y131492D01*
G01X1392039Y134050D02*
X1389539D01*
X1391331Y132508D01*
Y134592D01*
G01X1392039Y137150D02*
X1389539D01*
X1391331Y135608D01*
Y137692D01*
G01X1389539Y139750D02*
X1389622Y139417D01*
X1389831Y139167D01*
X1390081Y139000D01*
X1390414Y138875D01*
X1390789Y138833D01*
X1391164Y138875D01*
X1391497Y139000D01*
X1391747Y139167D01*
X1391956Y139417D01*
X1392039Y139750D01*
X1391956Y140083D01*
X1391747Y140333D01*
X1391497Y140500D01*
X1391164Y140625D01*
X1390789Y140667D01*
X1390414Y140625D01*
X1390081Y140500D01*
X1389831Y140333D01*
X1389622Y140083D01*
X1389539Y139750D01*
G01X1344417Y106261D02*
Y108761D01*
X1345458D01*
X1345792Y108636D01*
X1346000Y108469D01*
X1346083Y108136D01*
X1346000Y107803D01*
X1345750Y107594D01*
X1345458Y107469D01*
X1344417D01*
G01X1345458D02*
X1346083Y106261D01*
G01X1348267D02*
X1348350Y106803D01*
X1348475Y107261D01*
X1348642Y107678D01*
X1348850Y108136D01*
X1349183Y108761D01*
X1347517D01*
G01X1351367Y106261D02*
X1351450Y106803D01*
X1351575Y107261D01*
X1351742Y107678D01*
X1351950Y108136D01*
X1352283Y108761D01*
X1350617D01*
G01X1353633Y106636D02*
X1353883Y106428D01*
X1354175Y106303D01*
X1354550Y106261D01*
X1354925Y106344D01*
X1355217Y106511D01*
X1355425Y106803D01*
X1355467Y107136D01*
X1355383Y107469D01*
X1355175Y107678D01*
X1354883Y107844D01*
X1354592Y107886D01*
X1354300Y107844D01*
X1353925Y107678D01*
X1354050Y108761D01*
X1355175D01*
G01X1388039Y129617D02*
X1385539D01*
Y130658D01*
X1385664Y130992D01*
X1385831Y131200D01*
X1386164Y131283D01*
X1386497Y131200D01*
X1386706Y130950D01*
X1386831Y130658D01*
Y129617D01*
G01Y130658D02*
X1388039Y131283D01*
G01Y133467D02*
X1387497Y133550D01*
X1387039Y133675D01*
X1386622Y133842D01*
X1386164Y134050D01*
X1385539Y134383D01*
Y132717D01*
G01X1388039Y136650D02*
X1387997Y136942D01*
X1387872Y137275D01*
X1387664Y137483D01*
X1387372Y137567D01*
X1387081Y137483D01*
X1386831Y137233D01*
X1386706Y136858D01*
Y136442D01*
X1386622Y136192D01*
X1386414Y135983D01*
X1386122Y135900D01*
X1385831Y136025D01*
X1385622Y136317D01*
X1385539Y136650D01*
X1385622Y136983D01*
X1385831Y137275D01*
X1386122Y137400D01*
X1386414Y137317D01*
X1386622Y137108D01*
X1386706Y136858D01*
Y136442D01*
X1386831Y136067D01*
X1387081Y135817D01*
X1387372Y135733D01*
X1387664Y135817D01*
X1387872Y136025D01*
X1387997Y136358D01*
X1388039Y136650D01*
G01X1387539Y138833D02*
X1387831Y139083D01*
X1387997Y139417D01*
X1388039Y139792D01*
X1387997Y140125D01*
X1387789Y140458D01*
X1387539Y140667D01*
X1387289Y140708D01*
X1386997Y140625D01*
X1386789Y140333D01*
X1386706Y140042D01*
Y139667D01*
G01Y140042D02*
X1386581Y140292D01*
X1386372Y140500D01*
X1386122Y140583D01*
X1385872Y140500D01*
X1385664Y140292D01*
X1385539Y139917D01*
X1385581Y139542D01*
X1385747Y139167D01*
G01X1385200Y120900D02*
X1389200D01*
Y128300D01*
G01X1420547Y157267D02*
X1420422Y157017D01*
X1420339Y156725D01*
Y156392D01*
X1420464Y156017D01*
X1420672Y155725D01*
X1420922Y155517D01*
X1421339Y155350D01*
X1421714Y155308D01*
X1422089Y155392D01*
X1422339Y155517D01*
X1422589Y155767D01*
X1422756Y156058D01*
X1422839Y156350D01*
Y156642D01*
X1422756Y156933D01*
X1422631Y157183D01*
X1422464Y157392D01*
G01X1422839Y159950D02*
X1420339D01*
X1422131Y158408D01*
Y160492D01*
G01X1422339Y161633D02*
X1422631Y161883D01*
X1422797Y162217D01*
X1422839Y162592D01*
X1422797Y162925D01*
X1422589Y163258D01*
X1422339Y163467D01*
X1422089Y163508D01*
X1421797Y163425D01*
X1421589Y163133D01*
X1421506Y162842D01*
Y162467D01*
G01Y162842D02*
X1421381Y163092D01*
X1421172Y163300D01*
X1420922Y163383D01*
X1420672Y163300D01*
X1420464Y163092D01*
X1420339Y162717D01*
X1420381Y162342D01*
X1420547Y161967D01*
G01X1422339Y164733D02*
X1422631Y164983D01*
X1422797Y165317D01*
X1422839Y165692D01*
X1422797Y166025D01*
X1422589Y166358D01*
X1422339Y166567D01*
X1422089Y166608D01*
X1421797Y166525D01*
X1421589Y166233D01*
X1421506Y165942D01*
Y165567D01*
G01Y165942D02*
X1421381Y166192D01*
X1421172Y166400D01*
X1420922Y166483D01*
X1420672Y166400D01*
X1420464Y166192D01*
X1420339Y165817D01*
X1420381Y165442D01*
X1420547Y165067D01*
G01X1421708Y190267D02*
X1421583Y190017D01*
X1421500Y189725D01*
Y189392D01*
X1421625Y189017D01*
X1421833Y188725D01*
X1422083Y188517D01*
X1422500Y188350D01*
X1422875Y188308D01*
X1423250Y188392D01*
X1423500Y188517D01*
X1423750Y188767D01*
X1423917Y189058D01*
X1424000Y189350D01*
Y189642D01*
X1423917Y189933D01*
X1423792Y190183D01*
X1423625Y190392D01*
G01X1424000Y192950D02*
X1421500D01*
X1423292Y191408D01*
Y193492D01*
G01X1423500Y194633D02*
X1423792Y194883D01*
X1423958Y195217D01*
X1424000Y195592D01*
X1423958Y195925D01*
X1423750Y196258D01*
X1423500Y196467D01*
X1423250Y196508D01*
X1422958Y196425D01*
X1422750Y196133D01*
X1422667Y195842D01*
Y195467D01*
G01Y195842D02*
X1422542Y196092D01*
X1422333Y196300D01*
X1422083Y196383D01*
X1421833Y196300D01*
X1421625Y196092D01*
X1421500Y195717D01*
X1421542Y195342D01*
X1421708Y194967D01*
G01X1423708Y197942D02*
X1423917Y198233D01*
X1424000Y198567D01*
X1423917Y198900D01*
X1423667Y199192D01*
X1423292Y199400D01*
X1422917Y199483D01*
X1422458D01*
X1422083Y199400D01*
X1421750Y199192D01*
X1421583Y198942D01*
X1421500Y198650D01*
X1421583Y198317D01*
X1421750Y198067D01*
X1422000Y197900D01*
X1422333Y197817D01*
X1422625Y197900D01*
X1422917Y198108D01*
X1423083Y198358D01*
X1423125Y198650D01*
X1423042Y198983D01*
X1422833Y199233D01*
X1422458Y199483D01*
G01X1373800Y163000D02*
Y160500D01*
G01X1372842Y163000D02*
X1374758D01*
G01X1376067Y160500D02*
Y163000D01*
X1377067D01*
X1377400Y162875D01*
X1377650Y162583D01*
X1377733Y162250D01*
X1377650Y161917D01*
X1377442Y161667D01*
X1377067Y161542D01*
X1376067D01*
G01X1380000Y160500D02*
Y163000D01*
X1379500Y162500D01*
G01Y160500D02*
X1380500D01*
G01X1383017D02*
X1383100Y161042D01*
X1383225Y161500D01*
X1383392Y161917D01*
X1383600Y162375D01*
X1383933Y163000D01*
X1382267D01*
G01X1385408Y161542D02*
X1385700Y161833D01*
X1385950Y162000D01*
X1386283Y162083D01*
X1386575Y162000D01*
X1386783Y161833D01*
X1386950Y161583D01*
X1386992Y161292D01*
X1386950Y161042D01*
X1386783Y160792D01*
X1386533Y160583D01*
X1386242Y160500D01*
X1385908Y160583D01*
X1385617Y160833D01*
X1385450Y161208D01*
X1385408Y161625D01*
X1385492Y162167D01*
X1385617Y162458D01*
X1385825Y162750D01*
X1386117Y162958D01*
X1386408Y163000D01*
X1386700Y162917D01*
X1386908Y162708D01*
G01X1429850Y106500D02*
X1429517Y106542D01*
X1429225Y106708D01*
X1428975Y106958D01*
X1428808Y107250D01*
X1428725Y107583D01*
Y107917D01*
X1428808Y108250D01*
X1428975Y108542D01*
X1429225Y108792D01*
X1429517Y108958D01*
X1429850Y109000D01*
X1430183Y108958D01*
X1430475Y108792D01*
X1430725Y108542D01*
X1430892Y108250D01*
X1430975Y107917D01*
Y107583D01*
X1430892Y107250D01*
X1430725Y106958D01*
X1430475Y106708D01*
X1430183Y106542D01*
X1429850Y106500D01*
G01X1430183Y107167D02*
X1430683Y106500D01*
G01X1432950D02*
Y109000D01*
X1432450Y108500D01*
G01Y106500D02*
X1433450D01*
G01X1435133Y106875D02*
X1435383Y106667D01*
X1435675Y106542D01*
X1436050Y106500D01*
X1436425Y106583D01*
X1436717Y106750D01*
X1436925Y107042D01*
X1436967Y107375D01*
X1436883Y107708D01*
X1436675Y107917D01*
X1436383Y108083D01*
X1436092Y108125D01*
X1435800Y108083D01*
X1435425Y107917D01*
X1435550Y109000D01*
X1436675D01*
G01X1438442Y106792D02*
X1438733Y106583D01*
X1439067Y106500D01*
X1439400Y106583D01*
X1439692Y106833D01*
X1439900Y107208D01*
X1439983Y107583D01*
Y108042D01*
X1439900Y108417D01*
X1439692Y108750D01*
X1439442Y108917D01*
X1439150Y109000D01*
X1438817Y108917D01*
X1438567Y108750D01*
X1438400Y108500D01*
X1438317Y108167D01*
X1438400Y107875D01*
X1438608Y107583D01*
X1438858Y107417D01*
X1439150Y107375D01*
X1439483Y107458D01*
X1439733Y107667D01*
X1439983Y108042D01*
G01X1378000Y138517D02*
X1375500D01*
Y139558D01*
X1375625Y139892D01*
X1375792Y140100D01*
X1376125Y140183D01*
X1376458Y140100D01*
X1376667Y139850D01*
X1376792Y139558D01*
Y138517D01*
G01Y139558D02*
X1378000Y140183D01*
G01Y142367D02*
X1377458Y142450D01*
X1377000Y142575D01*
X1376583Y142742D01*
X1376125Y142950D01*
X1375500Y143283D01*
Y141617D01*
G01X1378000Y145550D02*
X1377958Y145842D01*
X1377833Y146175D01*
X1377625Y146383D01*
X1377333Y146467D01*
X1377042Y146383D01*
X1376792Y146133D01*
X1376667Y145758D01*
Y145342D01*
X1376583Y145092D01*
X1376375Y144883D01*
X1376083Y144800D01*
X1375792Y144925D01*
X1375583Y145217D01*
X1375500Y145550D01*
X1375583Y145883D01*
X1375792Y146175D01*
X1376083Y146300D01*
X1376375Y146217D01*
X1376583Y146008D01*
X1376667Y145758D01*
Y145342D01*
X1376792Y144967D01*
X1377042Y144717D01*
X1377333Y144633D01*
X1377625Y144717D01*
X1377833Y144925D01*
X1377958Y145258D01*
X1378000Y145550D01*
G01Y148567D02*
X1377458Y148650D01*
X1377000Y148775D01*
X1376583Y148942D01*
X1376125Y149150D01*
X1375500Y149483D01*
Y147817D01*
G01X1424708Y157267D02*
X1424583Y157017D01*
X1424500Y156725D01*
Y156392D01*
X1424625Y156017D01*
X1424833Y155725D01*
X1425083Y155517D01*
X1425500Y155350D01*
X1425875Y155308D01*
X1426250Y155392D01*
X1426500Y155517D01*
X1426750Y155767D01*
X1426917Y156058D01*
X1427000Y156350D01*
Y156642D01*
X1426917Y156933D01*
X1426792Y157183D01*
X1426625Y157392D01*
G01X1427000Y159950D02*
X1424500D01*
X1426292Y158408D01*
Y160492D01*
G01X1426500Y161633D02*
X1426792Y161883D01*
X1426958Y162217D01*
X1427000Y162592D01*
X1426958Y162925D01*
X1426750Y163258D01*
X1426500Y163467D01*
X1426250Y163508D01*
X1425958Y163425D01*
X1425750Y163133D01*
X1425667Y162842D01*
Y162467D01*
G01Y162842D02*
X1425542Y163092D01*
X1425333Y163300D01*
X1425083Y163383D01*
X1424833Y163300D01*
X1424625Y163092D01*
X1424500Y162717D01*
X1424542Y162342D01*
X1424708Y161967D01*
G01X1427000Y166150D02*
X1424500D01*
X1426292Y164608D01*
Y166692D01*
G01X1428500Y136200D02*
Y141700D01*
G01X1436500Y136200D02*
X1428500D01*
G01Y153800D02*
X1436500D01*
G01X1428500Y148300D02*
Y153800D01*
G01X1424017Y118000D02*
Y120500D01*
X1425058D01*
X1425392Y120375D01*
X1425600Y120208D01*
X1425683Y119875D01*
X1425600Y119542D01*
X1425350Y119333D01*
X1425058Y119208D01*
X1424017D01*
G01X1425058D02*
X1425683Y118000D01*
G01X1427867D02*
X1427950Y118542D01*
X1428075Y119000D01*
X1428242Y119417D01*
X1428450Y119875D01*
X1428783Y120500D01*
X1427117D01*
G01X1431050Y118000D02*
X1431342Y118042D01*
X1431675Y118167D01*
X1431883Y118375D01*
X1431967Y118667D01*
X1431883Y118958D01*
X1431633Y119208D01*
X1431258Y119333D01*
X1430842D01*
X1430592Y119417D01*
X1430383Y119625D01*
X1430300Y119917D01*
X1430425Y120208D01*
X1430717Y120417D01*
X1431050Y120500D01*
X1431383Y120417D01*
X1431675Y120208D01*
X1431800Y119917D01*
X1431717Y119625D01*
X1431508Y119417D01*
X1431258Y119333D01*
X1430842D01*
X1430467Y119208D01*
X1430217Y118958D01*
X1430133Y118667D01*
X1430217Y118375D01*
X1430425Y118167D01*
X1430758Y118042D01*
X1431050Y118000D01*
G01X1433358Y120083D02*
X1433608Y120333D01*
X1433900Y120458D01*
X1434233Y120500D01*
X1434650Y120417D01*
X1434942Y120208D01*
X1435025Y119958D01*
X1434983Y119708D01*
X1434817Y119500D01*
X1433983Y119083D01*
X1433608Y118792D01*
X1433358Y118375D01*
X1433275Y118000D01*
X1435025D01*
G01X1437800Y130000D02*
Y122000D01*
X1420200D01*
Y130000D01*
X1437800D01*
G01X1434617Y165300D02*
Y167800D01*
X1435658D01*
X1435992Y167675D01*
X1436200Y167508D01*
X1436283Y167175D01*
X1436200Y166842D01*
X1435950Y166633D01*
X1435658Y166508D01*
X1434617D01*
G01X1435658D02*
X1436283Y165300D01*
G01X1438467D02*
X1438550Y165842D01*
X1438675Y166300D01*
X1438842Y166717D01*
X1439050Y167175D01*
X1439383Y167800D01*
X1437717D01*
G01X1441650Y165300D02*
X1441942Y165342D01*
X1442275Y165467D01*
X1442483Y165675D01*
X1442567Y165967D01*
X1442483Y166258D01*
X1442233Y166508D01*
X1441858Y166633D01*
X1441442D01*
X1441192Y166717D01*
X1440983Y166925D01*
X1440900Y167217D01*
X1441025Y167508D01*
X1441317Y167717D01*
X1441650Y167800D01*
X1441983Y167717D01*
X1442275Y167508D01*
X1442400Y167217D01*
X1442317Y166925D01*
X1442108Y166717D01*
X1441858Y166633D01*
X1441442D01*
X1441067Y166508D01*
X1440817Y166258D01*
X1440733Y165967D01*
X1440817Y165675D01*
X1441025Y165467D01*
X1441358Y165342D01*
X1441650Y165300D01*
G01X1445250D02*
Y167800D01*
X1443708Y166008D01*
X1445792D01*
G01X1445900Y163800D02*
Y155800D01*
X1428300D01*
Y163800D01*
X1445900D01*
G01X1428208Y190267D02*
X1428083Y190017D01*
X1428000Y189725D01*
Y189392D01*
X1428125Y189017D01*
X1428333Y188725D01*
X1428583Y188517D01*
X1429000Y188350D01*
X1429375Y188308D01*
X1429750Y188392D01*
X1430000Y188517D01*
X1430250Y188767D01*
X1430417Y189058D01*
X1430500Y189350D01*
Y189642D01*
X1430417Y189933D01*
X1430292Y190183D01*
X1430125Y190392D01*
G01X1430500Y192950D02*
X1428000D01*
X1429792Y191408D01*
Y193492D01*
G01X1430000Y194633D02*
X1430292Y194883D01*
X1430458Y195217D01*
X1430500Y195592D01*
X1430458Y195925D01*
X1430250Y196258D01*
X1430000Y196467D01*
X1429750Y196508D01*
X1429458Y196425D01*
X1429250Y196133D01*
X1429167Y195842D01*
Y195467D01*
G01Y195842D02*
X1429042Y196092D01*
X1428833Y196300D01*
X1428583Y196383D01*
X1428333Y196300D01*
X1428125Y196092D01*
X1428000Y195717D01*
X1428042Y195342D01*
X1428208Y194967D01*
G01X1430500Y198567D02*
X1429958Y198650D01*
X1429500Y198775D01*
X1429083Y198942D01*
X1428625Y199150D01*
X1428000Y199483D01*
Y197817D01*
G01X1395275Y208500D02*
Y211000D01*
G01X1397025D02*
Y208500D01*
G01Y209750D02*
X1395275D01*
G01X1398333Y208500D02*
Y211000D01*
X1399167D01*
X1399500Y210875D01*
X1399750Y210708D01*
X1399958Y210458D01*
X1400125Y210167D01*
X1400167Y209750D01*
X1400125Y209333D01*
X1399958Y209042D01*
X1399750Y208792D01*
X1399500Y208625D01*
X1399167Y208500D01*
X1398333D01*
G01X1401433D02*
Y211000D01*
X1402267D01*
X1402600Y210875D01*
X1402850Y210708D01*
X1403058Y210458D01*
X1403225Y210167D01*
X1403267Y209750D01*
X1403225Y209333D01*
X1403058Y209042D01*
X1402850Y208792D01*
X1402600Y208625D01*
X1402267Y208500D01*
X1401433D01*
G01X1404575Y208833D02*
X1404908Y208625D01*
X1405283Y208500D01*
X1405617D01*
X1405950Y208625D01*
X1406200Y208833D01*
X1406325Y209125D01*
X1406242Y209417D01*
X1406033Y209667D01*
X1405658Y209833D01*
X1405158Y209917D01*
X1404867Y210083D01*
X1404742Y210375D01*
X1404825Y210667D01*
X1405033Y210875D01*
X1405325Y211000D01*
X1405617D01*
X1405908Y210917D01*
X1406158Y210708D01*
G01X1407508Y208500D02*
X1408550Y211000D01*
X1409592Y208500D01*
G01X1409217Y209375D02*
X1407883D01*
G01X1410775Y208833D02*
X1411108Y208625D01*
X1411483Y208500D01*
X1411817D01*
X1412150Y208625D01*
X1412400Y208833D01*
X1412525Y209125D01*
X1412442Y209417D01*
X1412233Y209667D01*
X1411858Y209833D01*
X1411358Y209917D01*
X1411067Y210083D01*
X1410942Y210375D01*
X1411025Y210667D01*
X1411233Y210875D01*
X1411525Y211000D01*
X1411817D01*
X1412108Y210917D01*
X1412358Y210708D01*
G01X1413833Y209000D02*
X1414083Y208708D01*
X1414417Y208542D01*
X1414792Y208500D01*
X1415125Y208542D01*
X1415458Y208750D01*
X1415667Y209000D01*
X1415708Y209250D01*
X1415625Y209542D01*
X1415333Y209750D01*
X1415042Y209833D01*
X1414667D01*
G01X1415042D02*
X1415292Y209958D01*
X1415500Y210167D01*
X1415583Y210417D01*
X1415500Y210667D01*
X1415292Y210875D01*
X1414917Y211000D01*
X1414542Y210958D01*
X1414167Y210792D01*
G01X1417850Y208500D02*
Y211000D01*
X1417350Y210500D01*
G01Y208500D02*
X1418350D01*
G01X1359467Y269000D02*
Y266500D01*
X1361133D01*
G01X1364233D02*
X1362567D01*
Y269000D01*
X1364233D01*
G01X1363567Y267792D02*
X1362567D01*
G01X1365583Y266500D02*
Y269000D01*
X1366417D01*
X1366750Y268875D01*
X1367000Y268708D01*
X1367208Y268458D01*
X1367375Y268167D01*
X1367417Y267750D01*
X1367375Y267333D01*
X1367208Y267042D01*
X1367000Y266792D01*
X1366750Y266625D01*
X1366417Y266500D01*
X1365583D01*
G01X1368808Y268583D02*
X1369058Y268833D01*
X1369350Y268958D01*
X1369683Y269000D01*
X1370100Y268917D01*
X1370392Y268708D01*
X1370475Y268458D01*
X1370433Y268208D01*
X1370267Y268000D01*
X1369433Y267583D01*
X1369058Y267292D01*
X1368808Y266875D01*
X1368725Y266500D01*
X1370475D01*
G01X1372700Y269000D02*
X1372367Y268917D01*
X1372117Y268708D01*
X1371950Y268458D01*
X1371825Y268125D01*
X1371783Y267750D01*
X1371825Y267375D01*
X1371950Y267042D01*
X1372117Y266792D01*
X1372367Y266583D01*
X1372700Y266500D01*
X1373033Y266583D01*
X1373283Y266792D01*
X1373450Y267042D01*
X1373575Y267375D01*
X1373617Y267750D01*
X1373575Y268125D01*
X1373450Y268458D01*
X1373283Y268708D01*
X1373033Y268917D01*
X1372700Y269000D01*
G01X1360561Y251880D02*
Y263080D01*
X1369361D01*
Y251880D01*
X1360561D01*
G01X1389006Y560075D02*
X1394056D01*
Y658775D01*
X1418706D01*
Y474375D01*
X1394056D01*
Y533075D01*
X1389006D01*
Y560075D01*
G01X1348517Y406500D02*
Y409000D01*
X1349558D01*
X1349892Y408875D01*
X1350100Y408708D01*
X1350183Y408375D01*
X1350100Y408042D01*
X1349850Y407833D01*
X1349558Y407708D01*
X1348517D01*
G01X1349558D02*
X1350183Y406500D01*
G01X1352950D02*
Y409000D01*
X1351408Y407208D01*
X1353492D01*
G01X1355467Y406500D02*
X1355550Y407042D01*
X1355675Y407500D01*
X1355842Y407917D01*
X1356050Y408375D01*
X1356383Y409000D01*
X1354717D01*
G01X1358650D02*
X1358317Y408917D01*
X1358067Y408708D01*
X1357900Y408458D01*
X1357775Y408125D01*
X1357733Y407750D01*
X1357775Y407375D01*
X1357900Y407042D01*
X1358067Y406792D01*
X1358317Y406583D01*
X1358650Y406500D01*
X1358983Y406583D01*
X1359233Y406792D01*
X1359400Y407042D01*
X1359525Y407375D01*
X1359567Y407750D01*
X1359525Y408125D01*
X1359400Y408458D01*
X1359233Y408708D01*
X1358983Y408917D01*
X1358650Y409000D01*
G01X1358007Y401203D02*
Y405203D01*
X1350607D01*
G01X1363800Y399817D02*
X1361300D01*
Y400858D01*
X1361425Y401192D01*
X1361592Y401400D01*
X1361925Y401483D01*
X1362258Y401400D01*
X1362467Y401150D01*
X1362592Y400858D01*
Y399817D01*
G01Y400858D02*
X1363800Y401483D01*
G01Y404250D02*
X1361300D01*
X1363092Y402708D01*
Y404792D01*
G01X1363300Y405933D02*
X1363592Y406183D01*
X1363758Y406517D01*
X1363800Y406892D01*
X1363758Y407225D01*
X1363550Y407558D01*
X1363300Y407767D01*
X1363050Y407808D01*
X1362758Y407725D01*
X1362550Y407433D01*
X1362467Y407142D01*
Y406767D01*
G01Y407142D02*
X1362342Y407392D01*
X1362133Y407600D01*
X1361883Y407683D01*
X1361633Y407600D01*
X1361425Y407392D01*
X1361300Y407017D01*
X1361342Y406642D01*
X1361508Y406267D01*
G01X1363800Y410450D02*
X1361300D01*
X1363092Y408908D01*
Y410992D01*
G01X1367800Y399817D02*
X1365300D01*
Y400858D01*
X1365425Y401192D01*
X1365592Y401400D01*
X1365925Y401483D01*
X1366258Y401400D01*
X1366467Y401150D01*
X1366592Y400858D01*
Y399817D01*
G01Y400858D02*
X1367800Y401483D01*
G01Y404250D02*
X1365300D01*
X1367092Y402708D01*
Y404792D01*
G01X1367300Y405933D02*
X1367592Y406183D01*
X1367758Y406517D01*
X1367800Y406892D01*
X1367758Y407225D01*
X1367550Y407558D01*
X1367300Y407767D01*
X1367050Y407808D01*
X1366758Y407725D01*
X1366550Y407433D01*
X1366467Y407142D01*
Y406767D01*
G01Y407142D02*
X1366342Y407392D01*
X1366133Y407600D01*
X1365883Y407683D01*
X1365633Y407600D01*
X1365425Y407392D01*
X1365300Y407017D01*
X1365342Y406642D01*
X1365508Y406267D01*
G01X1367425Y409033D02*
X1367633Y409283D01*
X1367758Y409575D01*
X1367800Y409950D01*
X1367717Y410325D01*
X1367550Y410617D01*
X1367258Y410825D01*
X1366925Y410867D01*
X1366592Y410783D01*
X1366383Y410575D01*
X1366217Y410283D01*
X1366175Y409992D01*
X1366217Y409700D01*
X1366383Y409325D01*
X1365300Y409450D01*
Y410575D01*
G01X1347850Y381500D02*
X1347517Y381542D01*
X1347225Y381708D01*
X1346975Y381958D01*
X1346808Y382250D01*
X1346725Y382583D01*
Y382917D01*
X1346808Y383250D01*
X1346975Y383542D01*
X1347225Y383792D01*
X1347517Y383958D01*
X1347850Y384000D01*
X1348183Y383958D01*
X1348475Y383792D01*
X1348725Y383542D01*
X1348892Y383250D01*
X1348975Y382917D01*
Y382583D01*
X1348892Y382250D01*
X1348725Y381958D01*
X1348475Y381708D01*
X1348183Y381542D01*
X1347850Y381500D01*
G01X1348183Y382167D02*
X1348683Y381500D01*
G01X1350158Y383583D02*
X1350408Y383833D01*
X1350700Y383958D01*
X1351033Y384000D01*
X1351450Y383917D01*
X1351742Y383708D01*
X1351825Y383458D01*
X1351783Y383208D01*
X1351617Y383000D01*
X1350783Y382583D01*
X1350408Y382292D01*
X1350158Y381875D01*
X1350075Y381500D01*
X1351825D01*
G01X1353133Y382000D02*
X1353383Y381708D01*
X1353717Y381542D01*
X1354092Y381500D01*
X1354425Y381542D01*
X1354758Y381750D01*
X1354967Y382000D01*
X1355008Y382250D01*
X1354925Y382542D01*
X1354633Y382750D01*
X1354342Y382833D01*
X1353967D01*
G01X1354342D02*
X1354592Y382958D01*
X1354800Y383167D01*
X1354883Y383417D01*
X1354800Y383667D01*
X1354592Y383875D01*
X1354217Y384000D01*
X1353842Y383958D01*
X1353467Y383792D01*
G01X1357150Y381500D02*
X1357442Y381542D01*
X1357775Y381667D01*
X1357983Y381875D01*
X1358067Y382167D01*
X1357983Y382458D01*
X1357733Y382708D01*
X1357358Y382833D01*
X1356942D01*
X1356692Y382917D01*
X1356483Y383125D01*
X1356400Y383417D01*
X1356525Y383708D01*
X1356817Y383917D01*
X1357150Y384000D01*
X1357483Y383917D01*
X1357775Y383708D01*
X1357900Y383417D01*
X1357817Y383125D01*
X1357608Y382917D01*
X1357358Y382833D01*
X1356942D01*
X1356567Y382708D01*
X1356317Y382458D01*
X1356233Y382167D01*
X1356317Y381875D01*
X1356525Y381667D01*
X1356858Y381542D01*
X1357150Y381500D01*
G01X1358682Y385744D02*
Y399744D01*
G01X1345682Y385744D02*
X1358682D01*
G01X1345682Y399744D02*
Y385744D01*
G01X1358682Y399744D02*
X1345682D01*
G01X1344574Y386651D02*
Y399651D01*
G01X1377858Y517128D02*
X1377608Y517253D01*
X1377316Y517336D01*
X1376983D01*
X1376608Y517211D01*
X1376316Y517003D01*
X1376108Y516753D01*
X1375941Y516336D01*
X1375899Y515961D01*
X1375983Y515586D01*
X1376108Y515336D01*
X1376358Y515086D01*
X1376649Y514919D01*
X1376941Y514836D01*
X1377233D01*
X1377524Y514919D01*
X1377774Y515044D01*
X1377983Y515211D01*
G01X1379249Y516919D02*
X1379499Y517169D01*
X1379791Y517294D01*
X1380124Y517336D01*
X1380541Y517253D01*
X1380833Y517044D01*
X1380916Y516794D01*
X1380874Y516544D01*
X1380708Y516336D01*
X1379874Y515919D01*
X1379499Y515628D01*
X1379249Y515211D01*
X1379166Y514836D01*
X1380916D01*
G01X1383058D02*
X1383141Y515378D01*
X1383266Y515836D01*
X1383433Y516253D01*
X1383641Y516711D01*
X1383974Y517336D01*
X1382308D01*
G01X1385449Y515878D02*
X1385741Y516169D01*
X1385991Y516336D01*
X1386324Y516419D01*
X1386616Y516336D01*
X1386824Y516169D01*
X1386991Y515919D01*
X1387033Y515628D01*
X1386991Y515378D01*
X1386824Y515128D01*
X1386574Y514919D01*
X1386283Y514836D01*
X1385949Y514919D01*
X1385658Y515169D01*
X1385491Y515544D01*
X1385449Y515961D01*
X1385533Y516503D01*
X1385658Y516794D01*
X1385866Y517086D01*
X1386158Y517294D01*
X1386449Y517336D01*
X1386741Y517253D01*
X1386949Y517044D01*
G01X1377867Y521492D02*
X1377617Y521617D01*
X1377325Y521700D01*
X1376992D01*
X1376617Y521575D01*
X1376325Y521367D01*
X1376117Y521117D01*
X1375950Y520700D01*
X1375908Y520325D01*
X1375992Y519950D01*
X1376117Y519700D01*
X1376367Y519450D01*
X1376658Y519283D01*
X1376950Y519200D01*
X1377242D01*
X1377533Y519283D01*
X1377783Y519408D01*
X1377992Y519575D01*
G01X1379258Y521283D02*
X1379508Y521533D01*
X1379800Y521658D01*
X1380133Y521700D01*
X1380550Y521617D01*
X1380842Y521408D01*
X1380925Y521158D01*
X1380883Y520908D01*
X1380717Y520700D01*
X1379883Y520283D01*
X1379508Y519992D01*
X1379258Y519575D01*
X1379175Y519200D01*
X1380925D01*
G01X1383067D02*
X1383150Y519742D01*
X1383275Y520200D01*
X1383442Y520617D01*
X1383650Y521075D01*
X1383983Y521700D01*
X1382317D01*
G01X1385333Y519575D02*
X1385583Y519367D01*
X1385875Y519242D01*
X1386250Y519200D01*
X1386625Y519283D01*
X1386917Y519450D01*
X1387125Y519742D01*
X1387167Y520075D01*
X1387083Y520408D01*
X1386875Y520617D01*
X1386583Y520783D01*
X1386292Y520825D01*
X1386000Y520783D01*
X1385625Y520617D01*
X1385750Y521700D01*
X1386875D01*
G01X1420708Y534767D02*
X1420583Y534517D01*
X1420500Y534225D01*
Y533892D01*
X1420625Y533517D01*
X1420833Y533225D01*
X1421083Y533017D01*
X1421500Y532850D01*
X1421875Y532808D01*
X1422250Y532892D01*
X1422500Y533017D01*
X1422750Y533267D01*
X1422917Y533558D01*
X1423000Y533850D01*
Y534142D01*
X1422917Y534433D01*
X1422792Y534683D01*
X1422625Y534892D01*
G01X1420917Y536158D02*
X1420667Y536408D01*
X1420542Y536700D01*
X1420500Y537033D01*
X1420583Y537450D01*
X1420792Y537742D01*
X1421042Y537825D01*
X1421292Y537783D01*
X1421500Y537617D01*
X1421917Y536783D01*
X1422208Y536408D01*
X1422625Y536158D01*
X1423000Y536075D01*
Y537825D01*
G01Y540050D02*
X1422958Y540342D01*
X1422833Y540675D01*
X1422625Y540883D01*
X1422333Y540967D01*
X1422042Y540883D01*
X1421792Y540633D01*
X1421667Y540258D01*
Y539842D01*
X1421583Y539592D01*
X1421375Y539383D01*
X1421083Y539300D01*
X1420792Y539425D01*
X1420583Y539717D01*
X1420500Y540050D01*
X1420583Y540383D01*
X1420792Y540675D01*
X1421083Y540800D01*
X1421375Y540717D01*
X1421583Y540508D01*
X1421667Y540258D01*
Y539842D01*
X1421792Y539467D01*
X1422042Y539217D01*
X1422333Y539133D01*
X1422625Y539217D01*
X1422833Y539425D01*
X1422958Y539758D01*
X1423000Y540050D01*
G01X1422625Y542233D02*
X1422833Y542483D01*
X1422958Y542775D01*
X1423000Y543150D01*
X1422917Y543525D01*
X1422750Y543817D01*
X1422458Y544025D01*
X1422125Y544067D01*
X1421792Y543983D01*
X1421583Y543775D01*
X1421417Y543483D01*
X1421375Y543192D01*
X1421417Y542900D01*
X1421583Y542525D01*
X1420500Y542650D01*
Y543775D01*
G01X1423000Y520017D02*
X1420500D01*
Y521058D01*
X1420625Y521392D01*
X1420792Y521600D01*
X1421125Y521683D01*
X1421458Y521600D01*
X1421667Y521350D01*
X1421792Y521058D01*
Y520017D01*
G01Y521058D02*
X1423000Y521683D01*
G01X1422625Y523033D02*
X1422833Y523283D01*
X1422958Y523575D01*
X1423000Y523950D01*
X1422917Y524325D01*
X1422750Y524617D01*
X1422458Y524825D01*
X1422125Y524867D01*
X1421792Y524783D01*
X1421583Y524575D01*
X1421417Y524283D01*
X1421375Y523992D01*
X1421417Y523700D01*
X1421583Y523325D01*
X1420500Y523450D01*
Y524575D01*
G01X1423000Y527050D02*
X1420500D01*
X1421000Y526550D01*
G01X1423000D02*
Y527550D01*
G01Y530650D02*
X1420500D01*
X1422292Y529108D01*
Y531192D01*
G01X1425900Y531900D02*
Y527900D01*
X1433300D01*
G01X1428500Y496517D02*
X1426000D01*
Y497558D01*
X1426125Y497892D01*
X1426292Y498100D01*
X1426625Y498183D01*
X1426958Y498100D01*
X1427167Y497850D01*
X1427292Y497558D01*
Y496517D01*
G01Y497558D02*
X1428500Y498183D01*
G01X1428125Y499533D02*
X1428333Y499783D01*
X1428458Y500075D01*
X1428500Y500450D01*
X1428417Y500825D01*
X1428250Y501117D01*
X1427958Y501325D01*
X1427625Y501367D01*
X1427292Y501283D01*
X1427083Y501075D01*
X1426917Y500783D01*
X1426875Y500492D01*
X1426917Y500200D01*
X1427083Y499825D01*
X1426000Y499950D01*
Y501075D01*
G01X1428500Y503550D02*
X1426000D01*
X1426500Y503050D01*
G01X1428500D02*
Y504050D01*
G01X1428125Y505733D02*
X1428333Y505983D01*
X1428458Y506275D01*
X1428500Y506650D01*
X1428417Y507025D01*
X1428250Y507317D01*
X1427958Y507525D01*
X1427625Y507567D01*
X1427292Y507483D01*
X1427083Y507275D01*
X1426917Y506983D01*
X1426875Y506692D01*
X1426917Y506400D01*
X1427083Y506025D01*
X1426000Y506150D01*
Y507275D01*
G01X1434000Y502800D02*
X1438000D01*
Y510200D01*
G01X1424500Y496517D02*
X1422000D01*
Y497558D01*
X1422125Y497892D01*
X1422292Y498100D01*
X1422625Y498183D01*
X1422958Y498100D01*
X1423167Y497850D01*
X1423292Y497558D01*
Y496517D01*
G01Y497558D02*
X1424500Y498183D01*
G01X1424125Y499533D02*
X1424333Y499783D01*
X1424458Y500075D01*
X1424500Y500450D01*
X1424417Y500825D01*
X1424250Y501117D01*
X1423958Y501325D01*
X1423625Y501367D01*
X1423292Y501283D01*
X1423083Y501075D01*
X1422917Y500783D01*
X1422875Y500492D01*
X1422917Y500200D01*
X1423083Y499825D01*
X1422000Y499950D01*
Y501075D01*
G01X1424500Y503550D02*
X1422000D01*
X1422500Y503050D01*
G01X1424500D02*
Y504050D01*
G01X1424208Y505942D02*
X1424417Y506233D01*
X1424500Y506567D01*
X1424417Y506900D01*
X1424167Y507192D01*
X1423792Y507400D01*
X1423417Y507483D01*
X1422958D01*
X1422583Y507400D01*
X1422250Y507192D01*
X1422083Y506942D01*
X1422000Y506650D01*
X1422083Y506317D01*
X1422250Y506067D01*
X1422500Y505900D01*
X1422833Y505817D01*
X1423125Y505900D01*
X1423417Y506108D01*
X1423583Y506358D01*
X1423625Y506650D01*
X1423542Y506983D01*
X1423333Y507233D01*
X1422958Y507483D01*
G01X1433500Y510200D02*
X1429500D01*
Y502800D01*
G01X1430400Y559500D02*
X1430067Y559542D01*
X1429775Y559708D01*
X1429525Y559958D01*
X1429358Y560250D01*
X1429275Y560583D01*
Y560917D01*
X1429358Y561250D01*
X1429525Y561542D01*
X1429775Y561792D01*
X1430067Y561958D01*
X1430400Y562000D01*
X1430733Y561958D01*
X1431025Y561792D01*
X1431275Y561542D01*
X1431442Y561250D01*
X1431525Y560917D01*
Y560583D01*
X1431442Y560250D01*
X1431275Y559958D01*
X1431025Y559708D01*
X1430733Y559542D01*
X1430400Y559500D01*
G01X1430733Y560167D02*
X1431233Y559500D01*
G01X1433500D02*
X1433792Y559542D01*
X1434125Y559667D01*
X1434333Y559875D01*
X1434417Y560167D01*
X1434333Y560458D01*
X1434083Y560708D01*
X1433708Y560833D01*
X1433292D01*
X1433042Y560917D01*
X1432833Y561125D01*
X1432750Y561417D01*
X1432875Y561708D01*
X1433167Y561917D01*
X1433500Y562000D01*
X1433833Y561917D01*
X1434125Y561708D01*
X1434250Y561417D01*
X1434167Y561125D01*
X1433958Y560917D01*
X1433708Y560833D01*
X1433292D01*
X1432917Y560708D01*
X1432667Y560458D01*
X1432583Y560167D01*
X1432667Y559875D01*
X1432875Y559667D01*
X1433208Y559542D01*
X1433500Y559500D01*
G01X1436517D02*
X1436600Y560042D01*
X1436725Y560500D01*
X1436892Y560917D01*
X1437100Y561375D01*
X1437433Y562000D01*
X1435767D01*
G01X1423000Y510400D02*
X1422958Y510067D01*
X1422792Y509775D01*
X1422542Y509525D01*
X1422250Y509358D01*
X1421917Y509275D01*
X1421583D01*
X1421250Y509358D01*
X1420958Y509525D01*
X1420708Y509775D01*
X1420542Y510067D01*
X1420500Y510400D01*
X1420542Y510733D01*
X1420708Y511025D01*
X1420958Y511275D01*
X1421250Y511442D01*
X1421583Y511525D01*
X1421917D01*
X1422250Y511442D01*
X1422542Y511275D01*
X1422792Y511025D01*
X1422958Y510733D01*
X1423000Y510400D01*
G01X1422333Y510733D02*
X1423000Y511233D01*
G01Y513500D02*
X1422958Y513792D01*
X1422833Y514125D01*
X1422625Y514333D01*
X1422333Y514417D01*
X1422042Y514333D01*
X1421792Y514083D01*
X1421667Y513708D01*
Y513292D01*
X1421583Y513042D01*
X1421375Y512833D01*
X1421083Y512750D01*
X1420792Y512875D01*
X1420583Y513167D01*
X1420500Y513500D01*
X1420583Y513833D01*
X1420792Y514125D01*
X1421083Y514250D01*
X1421375Y514167D01*
X1421583Y513958D01*
X1421667Y513708D01*
Y513292D01*
X1421792Y512917D01*
X1422042Y512667D01*
X1422333Y512583D01*
X1422625Y512667D01*
X1422833Y512875D01*
X1422958Y513208D01*
X1423000Y513500D01*
G01X1422708Y515892D02*
X1422917Y516183D01*
X1423000Y516517D01*
X1422917Y516850D01*
X1422667Y517142D01*
X1422292Y517350D01*
X1421917Y517433D01*
X1421458D01*
X1421083Y517350D01*
X1420750Y517142D01*
X1420583Y516892D01*
X1420500Y516600D01*
X1420583Y516267D01*
X1420750Y516017D01*
X1421000Y515850D01*
X1421333Y515767D01*
X1421625Y515850D01*
X1421917Y516058D01*
X1422083Y516308D01*
X1422125Y516600D01*
X1422042Y516933D01*
X1421833Y517183D01*
X1421458Y517433D01*
G01X1424800Y522700D02*
Y511300D01*
G01X1438200Y522700D02*
X1424800D01*
G01Y511300D02*
X1438200D01*
G01X1425017Y570000D02*
Y572500D01*
X1426058D01*
X1426392Y572375D01*
X1426600Y572208D01*
X1426683Y571875D01*
X1426600Y571542D01*
X1426350Y571333D01*
X1426058Y571208D01*
X1425017D01*
G01X1426058D02*
X1426683Y570000D01*
G01X1428033Y570375D02*
X1428283Y570167D01*
X1428575Y570042D01*
X1428950Y570000D01*
X1429325Y570083D01*
X1429617Y570250D01*
X1429825Y570542D01*
X1429867Y570875D01*
X1429783Y571208D01*
X1429575Y571417D01*
X1429283Y571583D01*
X1428992Y571625D01*
X1428700Y571583D01*
X1428325Y571417D01*
X1428450Y572500D01*
X1429575D01*
G01X1432050D02*
X1431717Y572417D01*
X1431467Y572208D01*
X1431300Y571958D01*
X1431175Y571625D01*
X1431133Y571250D01*
X1431175Y570875D01*
X1431300Y570542D01*
X1431467Y570292D01*
X1431717Y570083D01*
X1432050Y570000D01*
X1432383Y570083D01*
X1432633Y570292D01*
X1432800Y570542D01*
X1432925Y570875D01*
X1432967Y571250D01*
X1432925Y571625D01*
X1432800Y571958D01*
X1432633Y572208D01*
X1432383Y572417D01*
X1432050Y572500D01*
G01X1434358Y571042D02*
X1434650Y571333D01*
X1434900Y571500D01*
X1435233Y571583D01*
X1435525Y571500D01*
X1435733Y571333D01*
X1435900Y571083D01*
X1435942Y570792D01*
X1435900Y570542D01*
X1435733Y570292D01*
X1435483Y570083D01*
X1435192Y570000D01*
X1434858Y570083D01*
X1434567Y570333D01*
X1434400Y570708D01*
X1434358Y571125D01*
X1434442Y571667D01*
X1434567Y571958D01*
X1434775Y572250D01*
X1435067Y572458D01*
X1435358Y572500D01*
X1435650Y572417D01*
X1435858Y572208D01*
G01X1393775Y662000D02*
Y664500D01*
G01X1395525D02*
Y662000D01*
G01Y663250D02*
X1393775D01*
G01X1396833Y662000D02*
Y664500D01*
X1397667D01*
X1398000Y664375D01*
X1398250Y664208D01*
X1398458Y663958D01*
X1398625Y663667D01*
X1398667Y663250D01*
X1398625Y662833D01*
X1398458Y662542D01*
X1398250Y662292D01*
X1398000Y662125D01*
X1397667Y662000D01*
X1396833D01*
G01X1399933D02*
Y664500D01*
X1400767D01*
X1401100Y664375D01*
X1401350Y664208D01*
X1401558Y663958D01*
X1401725Y663667D01*
X1401767Y663250D01*
X1401725Y662833D01*
X1401558Y662542D01*
X1401350Y662292D01*
X1401100Y662125D01*
X1400767Y662000D01*
X1399933D01*
G01X1403075Y662333D02*
X1403408Y662125D01*
X1403783Y662000D01*
X1404117D01*
X1404450Y662125D01*
X1404700Y662333D01*
X1404825Y662625D01*
X1404742Y662917D01*
X1404533Y663167D01*
X1404158Y663333D01*
X1403658Y663417D01*
X1403367Y663583D01*
X1403242Y663875D01*
X1403325Y664167D01*
X1403533Y664375D01*
X1403825Y664500D01*
X1404117D01*
X1404408Y664417D01*
X1404658Y664208D01*
G01X1406008Y662000D02*
X1407050Y664500D01*
X1408092Y662000D01*
G01X1407717Y662875D02*
X1406383D01*
G01X1409275Y662333D02*
X1409608Y662125D01*
X1409983Y662000D01*
X1410317D01*
X1410650Y662125D01*
X1410900Y662333D01*
X1411025Y662625D01*
X1410942Y662917D01*
X1410733Y663167D01*
X1410358Y663333D01*
X1409858Y663417D01*
X1409567Y663583D01*
X1409442Y663875D01*
X1409525Y664167D01*
X1409733Y664375D01*
X1410025Y664500D01*
X1410317D01*
X1410608Y664417D01*
X1410858Y664208D01*
G01X1413250Y662000D02*
Y664500D01*
X1412750Y664000D01*
G01Y662000D02*
X1413750D01*
G01X1415642Y662292D02*
X1415933Y662083D01*
X1416267Y662000D01*
X1416600Y662083D01*
X1416892Y662333D01*
X1417100Y662708D01*
X1417183Y663083D01*
Y663542D01*
X1417100Y663917D01*
X1416892Y664250D01*
X1416642Y664417D01*
X1416350Y664500D01*
X1416017Y664417D01*
X1415767Y664250D01*
X1415600Y664000D01*
X1415517Y663667D01*
X1415600Y663375D01*
X1415808Y663083D01*
X1416058Y662917D01*
X1416350Y662875D01*
X1416683Y662958D01*
X1416933Y663167D01*
X1417183Y663542D01*
G01X1388947Y584067D02*
X1388822Y583817D01*
X1388739Y583525D01*
Y583192D01*
X1388864Y582817D01*
X1389072Y582525D01*
X1389322Y582317D01*
X1389739Y582150D01*
X1390114Y582108D01*
X1390489Y582192D01*
X1390739Y582317D01*
X1390989Y582567D01*
X1391156Y582858D01*
X1391239Y583150D01*
Y583442D01*
X1391156Y583733D01*
X1391031Y583983D01*
X1390864Y584192D01*
G01X1389156Y585458D02*
X1388906Y585708D01*
X1388781Y586000D01*
X1388739Y586333D01*
X1388822Y586750D01*
X1389031Y587042D01*
X1389281Y587125D01*
X1389531Y587083D01*
X1389739Y586917D01*
X1390156Y586083D01*
X1390447Y585708D01*
X1390864Y585458D01*
X1391239Y585375D01*
Y587125D01*
G01Y589350D02*
X1391197Y589642D01*
X1391072Y589975D01*
X1390864Y590183D01*
X1390572Y590267D01*
X1390281Y590183D01*
X1390031Y589933D01*
X1389906Y589558D01*
Y589142D01*
X1389822Y588892D01*
X1389614Y588683D01*
X1389322Y588600D01*
X1389031Y588725D01*
X1388822Y589017D01*
X1388739Y589350D01*
X1388822Y589683D01*
X1389031Y589975D01*
X1389322Y590100D01*
X1389614Y590017D01*
X1389822Y589808D01*
X1389906Y589558D01*
Y589142D01*
X1390031Y588767D01*
X1390281Y588517D01*
X1390572Y588433D01*
X1390864Y588517D01*
X1391072Y588725D01*
X1391197Y589058D01*
X1391239Y589350D01*
G01Y592450D02*
X1388739D01*
X1389239Y591950D01*
G01X1391239D02*
Y592950D01*
G01X1387239Y582317D02*
X1384739D01*
Y583358D01*
X1384864Y583692D01*
X1385031Y583900D01*
X1385364Y583983D01*
X1385697Y583900D01*
X1385906Y583650D01*
X1386031Y583358D01*
Y582317D01*
G01Y583358D02*
X1387239Y583983D01*
G01X1386864Y585333D02*
X1387072Y585583D01*
X1387197Y585875D01*
X1387239Y586250D01*
X1387156Y586625D01*
X1386989Y586917D01*
X1386697Y587125D01*
X1386364Y587167D01*
X1386031Y587083D01*
X1385822Y586875D01*
X1385656Y586583D01*
X1385614Y586292D01*
X1385656Y586000D01*
X1385822Y585625D01*
X1384739Y585750D01*
Y586875D01*
G01Y589350D02*
X1384822Y589017D01*
X1385031Y588767D01*
X1385281Y588600D01*
X1385614Y588475D01*
X1385989Y588433D01*
X1386364Y588475D01*
X1386697Y588600D01*
X1386947Y588767D01*
X1387156Y589017D01*
X1387239Y589350D01*
X1387156Y589683D01*
X1386947Y589933D01*
X1386697Y590100D01*
X1386364Y590225D01*
X1385989Y590267D01*
X1385614Y590225D01*
X1385281Y590100D01*
X1385031Y589933D01*
X1384822Y589683D01*
X1384739Y589350D01*
G01X1387239Y592367D02*
X1386697Y592450D01*
X1386239Y592575D01*
X1385822Y592742D01*
X1385364Y592950D01*
X1384739Y593283D01*
Y591617D01*
G01X1384400Y573600D02*
X1388400D01*
Y581000D01*
G01X1421208Y610267D02*
X1421083Y610017D01*
X1421000Y609725D01*
Y609392D01*
X1421125Y609017D01*
X1421333Y608725D01*
X1421583Y608517D01*
X1422000Y608350D01*
X1422375Y608308D01*
X1422750Y608392D01*
X1423000Y608517D01*
X1423250Y608767D01*
X1423417Y609058D01*
X1423500Y609350D01*
Y609642D01*
X1423417Y609933D01*
X1423292Y610183D01*
X1423125Y610392D01*
G01X1421417Y611658D02*
X1421167Y611908D01*
X1421042Y612200D01*
X1421000Y612533D01*
X1421083Y612950D01*
X1421292Y613242D01*
X1421542Y613325D01*
X1421792Y613283D01*
X1422000Y613117D01*
X1422417Y612283D01*
X1422708Y611908D01*
X1423125Y611658D01*
X1423500Y611575D01*
Y613325D01*
G01Y615467D02*
X1422958Y615550D01*
X1422500Y615675D01*
X1422083Y615842D01*
X1421625Y616050D01*
X1421000Y616383D01*
Y614717D01*
G01X1423500Y618567D02*
X1422958Y618650D01*
X1422500Y618775D01*
X1422083Y618942D01*
X1421625Y619150D01*
X1421000Y619483D01*
Y617817D01*
G01X1422208Y643267D02*
X1422083Y643017D01*
X1422000Y642725D01*
Y642392D01*
X1422125Y642017D01*
X1422333Y641725D01*
X1422583Y641517D01*
X1423000Y641350D01*
X1423375Y641308D01*
X1423750Y641392D01*
X1424000Y641517D01*
X1424250Y641767D01*
X1424417Y642058D01*
X1424500Y642350D01*
Y642642D01*
X1424417Y642933D01*
X1424292Y643183D01*
X1424125Y643392D01*
G01X1422417Y644658D02*
X1422167Y644908D01*
X1422042Y645200D01*
X1422000Y645533D01*
X1422083Y645950D01*
X1422292Y646242D01*
X1422542Y646325D01*
X1422792Y646283D01*
X1423000Y646117D01*
X1423417Y645283D01*
X1423708Y644908D01*
X1424125Y644658D01*
X1424500Y644575D01*
Y646325D01*
G01Y648550D02*
X1424458Y648842D01*
X1424333Y649175D01*
X1424125Y649383D01*
X1423833Y649467D01*
X1423542Y649383D01*
X1423292Y649133D01*
X1423167Y648758D01*
Y648342D01*
X1423083Y648092D01*
X1422875Y647883D01*
X1422583Y647800D01*
X1422292Y647925D01*
X1422083Y648217D01*
X1422000Y648550D01*
X1422083Y648883D01*
X1422292Y649175D01*
X1422583Y649300D01*
X1422875Y649217D01*
X1423083Y649008D01*
X1423167Y648758D01*
Y648342D01*
X1423292Y647967D01*
X1423542Y647717D01*
X1423833Y647633D01*
X1424125Y647717D01*
X1424333Y647925D01*
X1424458Y648258D01*
X1424500Y648550D01*
G01Y652150D02*
X1422000D01*
X1423792Y650608D01*
Y652692D01*
G01X1373768Y616855D02*
Y614355D01*
G01X1372810Y616855D02*
X1374726D01*
G01X1376035Y614355D02*
Y616855D01*
X1377035D01*
X1377368Y616730D01*
X1377618Y616438D01*
X1377701Y616105D01*
X1377618Y615772D01*
X1377410Y615522D01*
X1377035Y615397D01*
X1376035D01*
G01X1379968Y614355D02*
Y616855D01*
X1379468Y616355D01*
G01Y614355D02*
X1380468D01*
G01X1383068D02*
Y616855D01*
X1382568Y616355D01*
G01Y614355D02*
X1383568D01*
G01X1385376Y615397D02*
X1385668Y615688D01*
X1385918Y615855D01*
X1386251Y615938D01*
X1386543Y615855D01*
X1386751Y615688D01*
X1386918Y615438D01*
X1386960Y615147D01*
X1386918Y614897D01*
X1386751Y614647D01*
X1386501Y614438D01*
X1386210Y614355D01*
X1385876Y614438D01*
X1385585Y614688D01*
X1385418Y615063D01*
X1385376Y615480D01*
X1385460Y616022D01*
X1385585Y616313D01*
X1385793Y616605D01*
X1386085Y616813D01*
X1386376Y616855D01*
X1386668Y616772D01*
X1386876Y616563D01*
G01X1378100Y582717D02*
X1375600D01*
Y583758D01*
X1375725Y584092D01*
X1375892Y584300D01*
X1376225Y584383D01*
X1376558Y584300D01*
X1376767Y584050D01*
X1376892Y583758D01*
Y582717D01*
G01Y583758D02*
X1378100Y584383D01*
G01X1377725Y585733D02*
X1377933Y585983D01*
X1378058Y586275D01*
X1378100Y586650D01*
X1378017Y587025D01*
X1377850Y587317D01*
X1377558Y587525D01*
X1377225Y587567D01*
X1376892Y587483D01*
X1376683Y587275D01*
X1376517Y586983D01*
X1376475Y586692D01*
X1376517Y586400D01*
X1376683Y586025D01*
X1375600Y586150D01*
Y587275D01*
G01X1378100Y589750D02*
X1375600D01*
X1376100Y589250D01*
G01X1378100D02*
Y590250D01*
G01Y592850D02*
X1375600D01*
X1376100Y592350D01*
G01X1378100D02*
Y593350D01*
G01X1425208Y608767D02*
X1425083Y608517D01*
X1425000Y608225D01*
Y607892D01*
X1425125Y607517D01*
X1425333Y607225D01*
X1425583Y607017D01*
X1426000Y606850D01*
X1426375Y606808D01*
X1426750Y606892D01*
X1427000Y607017D01*
X1427250Y607267D01*
X1427417Y607558D01*
X1427500Y607850D01*
Y608142D01*
X1427417Y608433D01*
X1427292Y608683D01*
X1427125Y608892D01*
G01X1425417Y610158D02*
X1425167Y610408D01*
X1425042Y610700D01*
X1425000Y611033D01*
X1425083Y611450D01*
X1425292Y611742D01*
X1425542Y611825D01*
X1425792Y611783D01*
X1426000Y611617D01*
X1426417Y610783D01*
X1426708Y610408D01*
X1427125Y610158D01*
X1427500Y610075D01*
Y611825D01*
G01Y613967D02*
X1426958Y614050D01*
X1426500Y614175D01*
X1426083Y614342D01*
X1425625Y614550D01*
X1425000Y614883D01*
Y613217D01*
G01X1427500Y617150D02*
X1427458Y617442D01*
X1427333Y617775D01*
X1427125Y617983D01*
X1426833Y618067D01*
X1426542Y617983D01*
X1426292Y617733D01*
X1426167Y617358D01*
Y616942D01*
X1426083Y616692D01*
X1425875Y616483D01*
X1425583Y616400D01*
X1425292Y616525D01*
X1425083Y616817D01*
X1425000Y617150D01*
X1425083Y617483D01*
X1425292Y617775D01*
X1425583Y617900D01*
X1425875Y617817D01*
X1426083Y617608D01*
X1426167Y617358D01*
Y616942D01*
X1426292Y616567D01*
X1426542Y616317D01*
X1426833Y616233D01*
X1427125Y616317D01*
X1427333Y616525D01*
X1427458Y616858D01*
X1427500Y617150D01*
G01X1428500Y589200D02*
Y594700D01*
G01X1436500Y589200D02*
X1428500D01*
G01Y606800D02*
X1436500D01*
G01X1428500Y601300D02*
Y606800D01*
G01X1437800Y583000D02*
Y575000D01*
X1420200D01*
Y583000D01*
X1437800D01*
G01X1435017Y618100D02*
Y620600D01*
X1436058D01*
X1436392Y620475D01*
X1436600Y620308D01*
X1436683Y619975D01*
X1436600Y619642D01*
X1436350Y619433D01*
X1436058Y619308D01*
X1435017D01*
G01X1436058D02*
X1436683Y618100D01*
G01X1438033Y618475D02*
X1438283Y618267D01*
X1438575Y618142D01*
X1438950Y618100D01*
X1439325Y618183D01*
X1439617Y618350D01*
X1439825Y618642D01*
X1439867Y618975D01*
X1439783Y619308D01*
X1439575Y619517D01*
X1439283Y619683D01*
X1438992Y619725D01*
X1438700Y619683D01*
X1438325Y619517D01*
X1438450Y620600D01*
X1439575D01*
G01X1442050D02*
X1441717Y620517D01*
X1441467Y620308D01*
X1441300Y620058D01*
X1441175Y619725D01*
X1441133Y619350D01*
X1441175Y618975D01*
X1441300Y618642D01*
X1441467Y618392D01*
X1441717Y618183D01*
X1442050Y618100D01*
X1442383Y618183D01*
X1442633Y618392D01*
X1442800Y618642D01*
X1442925Y618975D01*
X1442967Y619350D01*
X1442925Y619725D01*
X1442800Y620058D01*
X1442633Y620308D01*
X1442383Y620517D01*
X1442050Y620600D01*
G01X1445150Y618100D02*
X1445442Y618142D01*
X1445775Y618267D01*
X1445983Y618475D01*
X1446067Y618767D01*
X1445983Y619058D01*
X1445733Y619308D01*
X1445358Y619433D01*
X1444942D01*
X1444692Y619517D01*
X1444483Y619725D01*
X1444400Y620017D01*
X1444525Y620308D01*
X1444817Y620517D01*
X1445150Y620600D01*
X1445483Y620517D01*
X1445775Y620308D01*
X1445900Y620017D01*
X1445817Y619725D01*
X1445608Y619517D01*
X1445358Y619433D01*
X1444942D01*
X1444567Y619308D01*
X1444317Y619058D01*
X1444233Y618767D01*
X1444317Y618475D01*
X1444525Y618267D01*
X1444858Y618142D01*
X1445150Y618100D01*
G01X1446300Y616600D02*
Y608600D01*
X1428700D01*
Y616600D01*
X1446300D01*
G01X1428547Y643267D02*
X1428422Y643017D01*
X1428339Y642725D01*
Y642392D01*
X1428464Y642017D01*
X1428672Y641725D01*
X1428922Y641517D01*
X1429339Y641350D01*
X1429714Y641308D01*
X1430089Y641392D01*
X1430339Y641517D01*
X1430589Y641767D01*
X1430756Y642058D01*
X1430839Y642350D01*
Y642642D01*
X1430756Y642933D01*
X1430631Y643183D01*
X1430464Y643392D01*
G01X1428756Y644658D02*
X1428506Y644908D01*
X1428381Y645200D01*
X1428339Y645533D01*
X1428422Y645950D01*
X1428631Y646242D01*
X1428881Y646325D01*
X1429131Y646283D01*
X1429339Y646117D01*
X1429756Y645283D01*
X1430047Y644908D01*
X1430464Y644658D01*
X1430839Y644575D01*
Y646325D01*
G01Y648550D02*
X1430797Y648842D01*
X1430672Y649175D01*
X1430464Y649383D01*
X1430172Y649467D01*
X1429881Y649383D01*
X1429631Y649133D01*
X1429506Y648758D01*
Y648342D01*
X1429422Y648092D01*
X1429214Y647883D01*
X1428922Y647800D01*
X1428631Y647925D01*
X1428422Y648217D01*
X1428339Y648550D01*
X1428422Y648883D01*
X1428631Y649175D01*
X1428922Y649300D01*
X1429214Y649217D01*
X1429422Y649008D01*
X1429506Y648758D01*
Y648342D01*
X1429631Y647967D01*
X1429881Y647717D01*
X1430172Y647633D01*
X1430464Y647717D01*
X1430672Y647925D01*
X1430797Y648258D01*
X1430839Y648550D01*
G01X1428756Y650858D02*
X1428506Y651108D01*
X1428381Y651400D01*
X1428339Y651733D01*
X1428422Y652150D01*
X1428631Y652442D01*
X1428881Y652525D01*
X1429131Y652483D01*
X1429339Y652317D01*
X1429756Y651483D01*
X1430047Y651108D01*
X1430464Y650858D01*
X1430839Y650775D01*
Y652525D01*
G01X1359517Y721000D02*
Y718500D01*
X1361183D01*
G01X1364283D02*
X1362617D01*
Y721000D01*
X1364283D01*
G01X1363617Y719792D02*
X1362617D01*
G01X1365633Y718500D02*
Y721000D01*
X1366467D01*
X1366800Y720875D01*
X1367050Y720708D01*
X1367258Y720458D01*
X1367425Y720167D01*
X1367467Y719750D01*
X1367425Y719333D01*
X1367258Y719042D01*
X1367050Y718792D01*
X1366800Y718625D01*
X1366467Y718500D01*
X1365633D01*
G01X1369650D02*
X1369942Y718542D01*
X1370275Y718667D01*
X1370483Y718875D01*
X1370567Y719167D01*
X1370483Y719458D01*
X1370233Y719708D01*
X1369858Y719833D01*
X1369442D01*
X1369192Y719917D01*
X1368983Y720125D01*
X1368900Y720417D01*
X1369025Y720708D01*
X1369317Y720917D01*
X1369650Y721000D01*
X1369983Y720917D01*
X1370275Y720708D01*
X1370400Y720417D01*
X1370317Y720125D01*
X1370108Y719917D01*
X1369858Y719833D01*
X1369442D01*
X1369067Y719708D01*
X1368817Y719458D01*
X1368733Y719167D01*
X1368817Y718875D01*
X1369025Y718667D01*
X1369358Y718542D01*
X1369650Y718500D01*
G01X1360561Y704636D02*
Y715836D01*
X1369361D01*
Y704636D01*
X1360561D01*
G01X1358007Y853959D02*
Y857959D01*
X1350607D01*
G01X1364900Y854417D02*
X1362400D01*
Y855458D01*
X1362525Y855792D01*
X1362692Y856000D01*
X1363025Y856083D01*
X1363358Y856000D01*
X1363567Y855750D01*
X1363692Y855458D01*
Y854417D01*
G01Y855458D02*
X1364900Y856083D01*
G01X1364400Y857433D02*
X1364692Y857683D01*
X1364858Y858017D01*
X1364900Y858392D01*
X1364858Y858725D01*
X1364650Y859058D01*
X1364400Y859267D01*
X1364150Y859308D01*
X1363858Y859225D01*
X1363650Y858933D01*
X1363567Y858642D01*
Y858267D01*
G01Y858642D02*
X1363442Y858892D01*
X1363233Y859100D01*
X1362983Y859183D01*
X1362733Y859100D01*
X1362525Y858892D01*
X1362400Y858517D01*
X1362442Y858142D01*
X1362608Y857767D01*
G01X1364900Y861450D02*
X1362400D01*
X1362900Y860950D01*
G01X1364900D02*
Y861950D01*
G01X1363858Y863758D02*
X1363567Y864050D01*
X1363400Y864300D01*
X1363317Y864633D01*
X1363400Y864925D01*
X1363567Y865133D01*
X1363817Y865300D01*
X1364108Y865342D01*
X1364358Y865300D01*
X1364608Y865133D01*
X1364817Y864883D01*
X1364900Y864592D01*
X1364817Y864258D01*
X1364567Y863967D01*
X1364192Y863800D01*
X1363775Y863758D01*
X1363233Y863842D01*
X1362942Y863967D01*
X1362650Y864175D01*
X1362442Y864467D01*
X1362400Y864758D01*
X1362483Y865050D01*
X1362692Y865258D01*
G01X1368900Y854417D02*
X1366400D01*
Y855458D01*
X1366525Y855792D01*
X1366692Y856000D01*
X1367025Y856083D01*
X1367358Y856000D01*
X1367567Y855750D01*
X1367692Y855458D01*
Y854417D01*
G01Y855458D02*
X1368900Y856083D01*
G01X1368400Y857433D02*
X1368692Y857683D01*
X1368858Y858017D01*
X1368900Y858392D01*
X1368858Y858725D01*
X1368650Y859058D01*
X1368400Y859267D01*
X1368150Y859308D01*
X1367858Y859225D01*
X1367650Y858933D01*
X1367567Y858642D01*
Y858267D01*
G01Y858642D02*
X1367442Y858892D01*
X1367233Y859100D01*
X1366983Y859183D01*
X1366733Y859100D01*
X1366525Y858892D01*
X1366400Y858517D01*
X1366442Y858142D01*
X1366608Y857767D01*
G01X1368900Y861450D02*
X1366400D01*
X1366900Y860950D01*
G01X1368900D02*
Y861950D01*
G01Y864467D02*
X1368358Y864550D01*
X1367900Y864675D01*
X1367483Y864842D01*
X1367025Y865050D01*
X1366400Y865383D01*
Y863717D01*
G01X1350350Y834500D02*
X1350017Y834542D01*
X1349725Y834708D01*
X1349475Y834958D01*
X1349308Y835250D01*
X1349225Y835583D01*
Y835917D01*
X1349308Y836250D01*
X1349475Y836542D01*
X1349725Y836792D01*
X1350017Y836958D01*
X1350350Y837000D01*
X1350683Y836958D01*
X1350975Y836792D01*
X1351225Y836542D01*
X1351392Y836250D01*
X1351475Y835917D01*
Y835583D01*
X1351392Y835250D01*
X1351225Y834958D01*
X1350975Y834708D01*
X1350683Y834542D01*
X1350350Y834500D01*
G01X1350683Y835167D02*
X1351183Y834500D01*
G01X1352658Y836583D02*
X1352908Y836833D01*
X1353200Y836958D01*
X1353533Y837000D01*
X1353950Y836917D01*
X1354242Y836708D01*
X1354325Y836458D01*
X1354283Y836208D01*
X1354117Y836000D01*
X1353283Y835583D01*
X1352908Y835292D01*
X1352658Y834875D01*
X1352575Y834500D01*
X1354325D01*
G01X1355758Y836583D02*
X1356008Y836833D01*
X1356300Y836958D01*
X1356633Y837000D01*
X1357050Y836917D01*
X1357342Y836708D01*
X1357425Y836458D01*
X1357383Y836208D01*
X1357217Y836000D01*
X1356383Y835583D01*
X1356008Y835292D01*
X1355758Y834875D01*
X1355675Y834500D01*
X1357425D01*
G01X1358858Y835542D02*
X1359150Y835833D01*
X1359400Y836000D01*
X1359733Y836083D01*
X1360025Y836000D01*
X1360233Y835833D01*
X1360400Y835583D01*
X1360442Y835292D01*
X1360400Y835042D01*
X1360233Y834792D01*
X1359983Y834583D01*
X1359692Y834500D01*
X1359358Y834583D01*
X1359067Y834833D01*
X1358900Y835208D01*
X1358858Y835625D01*
X1358942Y836167D01*
X1359067Y836458D01*
X1359275Y836750D01*
X1359567Y836958D01*
X1359858Y837000D01*
X1360150Y836917D01*
X1360358Y836708D01*
G01X1358682Y838500D02*
Y852500D01*
G01X1345682Y838500D02*
X1358682D01*
G01X1345682Y852500D02*
Y838500D01*
G01X1358682Y852500D02*
X1345682D01*
G01X1344574Y839407D02*
Y852407D01*
G01X1389006Y1012831D02*
X1394056D01*
Y1111531D01*
X1418706D01*
Y927131D01*
X1394056D01*
Y985831D01*
X1389006D01*
Y1012831D01*
G01X1428500Y949517D02*
X1426000D01*
Y950558D01*
X1426125Y950892D01*
X1426292Y951100D01*
X1426625Y951183D01*
X1426958Y951100D01*
X1427167Y950850D01*
X1427292Y950558D01*
Y949517D01*
G01Y950558D02*
X1428500Y951183D01*
G01X1426417Y952658D02*
X1426167Y952908D01*
X1426042Y953200D01*
X1426000Y953533D01*
X1426083Y953950D01*
X1426292Y954242D01*
X1426542Y954325D01*
X1426792Y954283D01*
X1427000Y954117D01*
X1427417Y953283D01*
X1427708Y952908D01*
X1428125Y952658D01*
X1428500Y952575D01*
Y954325D01*
G01Y956467D02*
X1427958Y956550D01*
X1427500Y956675D01*
X1427083Y956842D01*
X1426625Y957050D01*
X1426000Y957383D01*
Y955717D01*
G01X1427458Y958858D02*
X1427167Y959150D01*
X1427000Y959400D01*
X1426917Y959733D01*
X1427000Y960025D01*
X1427167Y960233D01*
X1427417Y960400D01*
X1427708Y960442D01*
X1427958Y960400D01*
X1428208Y960233D01*
X1428417Y959983D01*
X1428500Y959692D01*
X1428417Y959358D01*
X1428167Y959067D01*
X1427792Y958900D01*
X1427375Y958858D01*
X1426833Y958942D01*
X1426542Y959067D01*
X1426250Y959275D01*
X1426042Y959567D01*
X1426000Y959858D01*
X1426083Y960150D01*
X1426292Y960358D01*
G01X1424500Y949517D02*
X1422000D01*
Y950558D01*
X1422125Y950892D01*
X1422292Y951100D01*
X1422625Y951183D01*
X1422958Y951100D01*
X1423167Y950850D01*
X1423292Y950558D01*
Y949517D01*
G01Y950558D02*
X1424500Y951183D01*
G01X1422417Y952658D02*
X1422167Y952908D01*
X1422042Y953200D01*
X1422000Y953533D01*
X1422083Y953950D01*
X1422292Y954242D01*
X1422542Y954325D01*
X1422792Y954283D01*
X1423000Y954117D01*
X1423417Y953283D01*
X1423708Y952908D01*
X1424125Y952658D01*
X1424500Y952575D01*
Y954325D01*
G01Y956467D02*
X1423958Y956550D01*
X1423500Y956675D01*
X1423083Y956842D01*
X1422625Y957050D01*
X1422000Y957383D01*
Y955717D01*
G01X1424208Y958942D02*
X1424417Y959233D01*
X1424500Y959567D01*
X1424417Y959900D01*
X1424167Y960192D01*
X1423792Y960400D01*
X1423417Y960483D01*
X1422958D01*
X1422583Y960400D01*
X1422250Y960192D01*
X1422083Y959942D01*
X1422000Y959650D01*
X1422083Y959317D01*
X1422250Y959067D01*
X1422500Y958900D01*
X1422833Y958817D01*
X1423125Y958900D01*
X1423417Y959108D01*
X1423583Y959358D01*
X1423625Y959650D01*
X1423542Y959983D01*
X1423333Y960233D01*
X1422958Y960483D01*
G01X1348017Y859500D02*
Y862000D01*
X1349058D01*
X1349392Y861875D01*
X1349600Y861708D01*
X1349683Y861375D01*
X1349600Y861042D01*
X1349350Y860833D01*
X1349058Y860708D01*
X1348017D01*
G01X1349058D02*
X1349683Y859500D01*
G01X1351158Y861583D02*
X1351408Y861833D01*
X1351700Y861958D01*
X1352033Y862000D01*
X1352450Y861917D01*
X1352742Y861708D01*
X1352825Y861458D01*
X1352783Y861208D01*
X1352617Y861000D01*
X1351783Y860583D01*
X1351408Y860292D01*
X1351158Y859875D01*
X1351075Y859500D01*
X1352825D01*
G01X1354133Y859875D02*
X1354383Y859667D01*
X1354675Y859542D01*
X1355050Y859500D01*
X1355425Y859583D01*
X1355717Y859750D01*
X1355925Y860042D01*
X1355967Y860375D01*
X1355883Y860708D01*
X1355675Y860917D01*
X1355383Y861083D01*
X1355092Y861125D01*
X1354800Y861083D01*
X1354425Y860917D01*
X1354550Y862000D01*
X1355675D01*
G01X1358150Y859500D02*
X1358442Y859542D01*
X1358775Y859667D01*
X1358983Y859875D01*
X1359067Y860167D01*
X1358983Y860458D01*
X1358733Y860708D01*
X1358358Y860833D01*
X1357942D01*
X1357692Y860917D01*
X1357483Y861125D01*
X1357400Y861417D01*
X1357525Y861708D01*
X1357817Y861917D01*
X1358150Y862000D01*
X1358483Y861917D01*
X1358775Y861708D01*
X1358900Y861417D01*
X1358817Y861125D01*
X1358608Y860917D01*
X1358358Y860833D01*
X1357942D01*
X1357567Y860708D01*
X1357317Y860458D01*
X1357233Y860167D01*
X1357317Y859875D01*
X1357525Y859667D01*
X1357858Y859542D01*
X1358150Y859500D01*
G01X1364767Y962792D02*
X1364517Y962917D01*
X1364225Y963000D01*
X1363892D01*
X1363517Y962875D01*
X1363225Y962667D01*
X1363017Y962417D01*
X1362850Y962000D01*
X1362808Y961625D01*
X1362892Y961250D01*
X1363017Y961000D01*
X1363267Y960750D01*
X1363558Y960583D01*
X1363850Y960500D01*
X1364142D01*
X1364433Y960583D01*
X1364683Y960708D01*
X1364892Y960875D01*
G01X1366950Y960500D02*
Y963000D01*
X1366450Y962500D01*
G01Y960500D02*
X1367450D01*
G01X1369258Y962583D02*
X1369508Y962833D01*
X1369800Y962958D01*
X1370133Y963000D01*
X1370550Y962917D01*
X1370842Y962708D01*
X1370925Y962458D01*
X1370883Y962208D01*
X1370717Y962000D01*
X1369883Y961583D01*
X1369508Y961292D01*
X1369258Y960875D01*
X1369175Y960500D01*
X1370925D01*
G01X1373150Y963000D02*
X1372817Y962917D01*
X1372567Y962708D01*
X1372400Y962458D01*
X1372275Y962125D01*
X1372233Y961750D01*
X1372275Y961375D01*
X1372400Y961042D01*
X1372567Y960792D01*
X1372817Y960583D01*
X1373150Y960500D01*
X1373483Y960583D01*
X1373733Y960792D01*
X1373900Y961042D01*
X1374025Y961375D01*
X1374067Y961750D01*
X1374025Y962125D01*
X1373900Y962458D01*
X1373733Y962708D01*
X1373483Y962917D01*
X1373150Y963000D01*
G01X1364767Y966792D02*
X1364517Y966917D01*
X1364225Y967000D01*
X1363892D01*
X1363517Y966875D01*
X1363225Y966667D01*
X1363017Y966417D01*
X1362850Y966000D01*
X1362808Y965625D01*
X1362892Y965250D01*
X1363017Y965000D01*
X1363267Y964750D01*
X1363558Y964583D01*
X1363850Y964500D01*
X1364142D01*
X1364433Y964583D01*
X1364683Y964708D01*
X1364892Y964875D01*
G01X1366950Y964500D02*
Y967000D01*
X1366450Y966500D01*
G01Y964500D02*
X1367450D01*
G01X1370050D02*
Y967000D01*
X1369550Y966500D01*
G01Y964500D02*
X1370550D01*
G01X1372442Y964792D02*
X1372733Y964583D01*
X1373067Y964500D01*
X1373400Y964583D01*
X1373692Y964833D01*
X1373900Y965208D01*
X1373983Y965583D01*
Y966042D01*
X1373900Y966417D01*
X1373692Y966750D01*
X1373442Y966917D01*
X1373150Y967000D01*
X1372817Y966917D01*
X1372567Y966750D01*
X1372400Y966500D01*
X1372317Y966167D01*
X1372400Y965875D01*
X1372608Y965583D01*
X1372858Y965417D01*
X1373150Y965375D01*
X1373483Y965458D01*
X1373733Y965667D01*
X1373983Y966042D01*
G01X1342267Y1019953D02*
X1342017Y1020078D01*
X1341725Y1020161D01*
X1341392D01*
X1341017Y1020036D01*
X1340725Y1019828D01*
X1340517Y1019578D01*
X1340350Y1019161D01*
X1340308Y1018786D01*
X1340392Y1018411D01*
X1340517Y1018161D01*
X1340767Y1017911D01*
X1341058Y1017744D01*
X1341350Y1017661D01*
X1341642D01*
X1341933Y1017744D01*
X1342183Y1017869D01*
X1342392Y1018036D01*
G01X1344450Y1017661D02*
Y1020161D01*
X1343950Y1019661D01*
G01Y1017661D02*
X1344950D01*
G01X1347550D02*
Y1020161D01*
X1347050Y1019661D01*
G01Y1017661D02*
X1348050D01*
G01X1350567D02*
X1350650Y1018203D01*
X1350775Y1018661D01*
X1350942Y1019078D01*
X1351150Y1019536D01*
X1351483Y1020161D01*
X1349817D01*
G01X1389547Y1037867D02*
X1389422Y1037617D01*
X1389339Y1037325D01*
Y1036992D01*
X1389464Y1036617D01*
X1389672Y1036325D01*
X1389922Y1036117D01*
X1390339Y1035950D01*
X1390714Y1035908D01*
X1391089Y1035992D01*
X1391339Y1036117D01*
X1391589Y1036367D01*
X1391756Y1036658D01*
X1391839Y1036950D01*
Y1037242D01*
X1391756Y1037533D01*
X1391631Y1037783D01*
X1391464Y1037992D01*
G01X1391839Y1040050D02*
X1389339D01*
X1389839Y1039550D01*
G01X1391839D02*
Y1040550D01*
G01X1389756Y1042358D02*
X1389506Y1042608D01*
X1389381Y1042900D01*
X1389339Y1043233D01*
X1389422Y1043650D01*
X1389631Y1043942D01*
X1389881Y1044025D01*
X1390131Y1043983D01*
X1390339Y1043817D01*
X1390756Y1042983D01*
X1391047Y1042608D01*
X1391464Y1042358D01*
X1391839Y1042275D01*
Y1044025D01*
G01X1391339Y1045333D02*
X1391631Y1045583D01*
X1391797Y1045917D01*
X1391839Y1046292D01*
X1391797Y1046625D01*
X1391589Y1046958D01*
X1391339Y1047167D01*
X1391089Y1047208D01*
X1390797Y1047125D01*
X1390589Y1046833D01*
X1390506Y1046542D01*
Y1046167D01*
G01Y1046542D02*
X1390381Y1046792D01*
X1390172Y1047000D01*
X1389922Y1047083D01*
X1389672Y1047000D01*
X1389464Y1046792D01*
X1389339Y1046417D01*
X1389381Y1046042D01*
X1389547Y1045667D01*
G01X1421071Y991216D02*
X1420946Y990966D01*
X1420863Y990674D01*
Y990341D01*
X1420988Y989966D01*
X1421196Y989674D01*
X1421446Y989466D01*
X1421863Y989299D01*
X1422238Y989257D01*
X1422613Y989341D01*
X1422863Y989466D01*
X1423113Y989716D01*
X1423280Y990007D01*
X1423363Y990299D01*
Y990591D01*
X1423280Y990882D01*
X1423155Y991132D01*
X1422988Y991341D01*
G01X1423363Y993399D02*
X1420863D01*
X1421363Y992899D01*
G01X1423363D02*
Y993899D01*
G01X1421280Y995707D02*
X1421030Y995957D01*
X1420905Y996249D01*
X1420863Y996582D01*
X1420946Y996999D01*
X1421155Y997291D01*
X1421405Y997374D01*
X1421655Y997332D01*
X1421863Y997166D01*
X1422280Y996332D01*
X1422571Y995957D01*
X1422988Y995707D01*
X1423363Y995624D01*
Y997374D01*
G01X1423071Y998891D02*
X1423280Y999182D01*
X1423363Y999516D01*
X1423280Y999849D01*
X1423030Y1000141D01*
X1422655Y1000349D01*
X1422280Y1000432D01*
X1421821D01*
X1421446Y1000349D01*
X1421113Y1000141D01*
X1420946Y999891D01*
X1420863Y999599D01*
X1420946Y999266D01*
X1421113Y999016D01*
X1421363Y998849D01*
X1421696Y998766D01*
X1421988Y998849D01*
X1422280Y999057D01*
X1422446Y999307D01*
X1422488Y999599D01*
X1422405Y999932D01*
X1422196Y1000182D01*
X1421821Y1000432D01*
G01X1340517Y1013661D02*
Y1016161D01*
X1341558D01*
X1341892Y1016036D01*
X1342100Y1015869D01*
X1342183Y1015536D01*
X1342100Y1015203D01*
X1341850Y1014994D01*
X1341558Y1014869D01*
X1340517D01*
G01X1341558D02*
X1342183Y1013661D01*
G01X1343658Y1015744D02*
X1343908Y1015994D01*
X1344200Y1016119D01*
X1344533Y1016161D01*
X1344950Y1016078D01*
X1345242Y1015869D01*
X1345325Y1015619D01*
X1345283Y1015369D01*
X1345117Y1015161D01*
X1344283Y1014744D01*
X1343908Y1014453D01*
X1343658Y1014036D01*
X1343575Y1013661D01*
X1345325D01*
G01X1346758Y1014703D02*
X1347050Y1014994D01*
X1347300Y1015161D01*
X1347633Y1015244D01*
X1347925Y1015161D01*
X1348133Y1014994D01*
X1348300Y1014744D01*
X1348342Y1014453D01*
X1348300Y1014203D01*
X1348133Y1013953D01*
X1347883Y1013744D01*
X1347592Y1013661D01*
X1347258Y1013744D01*
X1346967Y1013994D01*
X1346800Y1014369D01*
X1346758Y1014786D01*
X1346842Y1015328D01*
X1346967Y1015619D01*
X1347175Y1015911D01*
X1347467Y1016119D01*
X1347758Y1016161D01*
X1348050Y1016078D01*
X1348258Y1015869D01*
G01X1349733Y1014036D02*
X1349983Y1013828D01*
X1350275Y1013703D01*
X1350650Y1013661D01*
X1351025Y1013744D01*
X1351317Y1013911D01*
X1351525Y1014203D01*
X1351567Y1014536D01*
X1351483Y1014869D01*
X1351275Y1015078D01*
X1350983Y1015244D01*
X1350692Y1015286D01*
X1350400Y1015244D01*
X1350025Y1015078D01*
X1350150Y1016161D01*
X1351275D01*
G01X1340517Y984500D02*
Y987000D01*
X1341558D01*
X1341892Y986875D01*
X1342100Y986708D01*
X1342183Y986375D01*
X1342100Y986042D01*
X1341850Y985833D01*
X1341558Y985708D01*
X1340517D01*
G01X1341558D02*
X1342183Y984500D01*
G01X1343658Y986583D02*
X1343908Y986833D01*
X1344200Y986958D01*
X1344533Y987000D01*
X1344950Y986917D01*
X1345242Y986708D01*
X1345325Y986458D01*
X1345283Y986208D01*
X1345117Y986000D01*
X1344283Y985583D01*
X1343908Y985292D01*
X1343658Y984875D01*
X1343575Y984500D01*
X1345325D01*
G01X1346758Y985542D02*
X1347050Y985833D01*
X1347300Y986000D01*
X1347633Y986083D01*
X1347925Y986000D01*
X1348133Y985833D01*
X1348300Y985583D01*
X1348342Y985292D01*
X1348300Y985042D01*
X1348133Y984792D01*
X1347883Y984583D01*
X1347592Y984500D01*
X1347258Y984583D01*
X1346967Y984833D01*
X1346800Y985208D01*
X1346758Y985625D01*
X1346842Y986167D01*
X1346967Y986458D01*
X1347175Y986750D01*
X1347467Y986958D01*
X1347758Y987000D01*
X1348050Y986917D01*
X1348258Y986708D01*
G01X1349858Y985542D02*
X1350150Y985833D01*
X1350400Y986000D01*
X1350733Y986083D01*
X1351025Y986000D01*
X1351233Y985833D01*
X1351400Y985583D01*
X1351442Y985292D01*
X1351400Y985042D01*
X1351233Y984792D01*
X1350983Y984583D01*
X1350692Y984500D01*
X1350358Y984583D01*
X1350067Y984833D01*
X1349900Y985208D01*
X1349858Y985625D01*
X1349942Y986167D01*
X1350067Y986458D01*
X1350275Y986750D01*
X1350567Y986958D01*
X1350858Y987000D01*
X1351150Y986917D01*
X1351358Y986708D01*
G01X1387839Y1036117D02*
X1385339D01*
Y1037158D01*
X1385464Y1037492D01*
X1385631Y1037700D01*
X1385964Y1037783D01*
X1386297Y1037700D01*
X1386506Y1037450D01*
X1386631Y1037158D01*
Y1036117D01*
G01Y1037158D02*
X1387839Y1037783D01*
G01X1385756Y1039258D02*
X1385506Y1039508D01*
X1385381Y1039800D01*
X1385339Y1040133D01*
X1385422Y1040550D01*
X1385631Y1040842D01*
X1385881Y1040925D01*
X1386131Y1040883D01*
X1386339Y1040717D01*
X1386756Y1039883D01*
X1387047Y1039508D01*
X1387464Y1039258D01*
X1387839Y1039175D01*
Y1040925D01*
G01Y1043067D02*
X1387297Y1043150D01*
X1386839Y1043275D01*
X1386422Y1043442D01*
X1385964Y1043650D01*
X1385339Y1043983D01*
Y1042317D01*
G01X1387839Y1046250D02*
X1385339D01*
X1385839Y1045750D01*
G01X1387839D02*
Y1046750D01*
G01X1385000Y1026400D02*
X1389000D01*
Y1033800D01*
G01X1423000Y973017D02*
X1420500D01*
Y974058D01*
X1420625Y974392D01*
X1420792Y974600D01*
X1421125Y974683D01*
X1421458Y974600D01*
X1421667Y974350D01*
X1421792Y974058D01*
Y973017D01*
G01Y974058D02*
X1423000Y974683D01*
G01X1420917Y976158D02*
X1420667Y976408D01*
X1420542Y976700D01*
X1420500Y977033D01*
X1420583Y977450D01*
X1420792Y977742D01*
X1421042Y977825D01*
X1421292Y977783D01*
X1421500Y977617D01*
X1421917Y976783D01*
X1422208Y976408D01*
X1422625Y976158D01*
X1423000Y976075D01*
Y977825D01*
G01Y979967D02*
X1422458Y980050D01*
X1422000Y980175D01*
X1421583Y980342D01*
X1421125Y980550D01*
X1420500Y980883D01*
Y979217D01*
G01X1422625Y982233D02*
X1422833Y982483D01*
X1422958Y982775D01*
X1423000Y983150D01*
X1422917Y983525D01*
X1422750Y983817D01*
X1422458Y984025D01*
X1422125Y984067D01*
X1421792Y983983D01*
X1421583Y983775D01*
X1421417Y983483D01*
X1421375Y983192D01*
X1421417Y982900D01*
X1421583Y982525D01*
X1420500Y982650D01*
Y983775D01*
G01X1425900Y984400D02*
Y980400D01*
X1433300D01*
G01X1434000Y955300D02*
X1438000D01*
Y962700D01*
G01X1433500D02*
X1429500D01*
Y955300D01*
G01X1429900Y1011500D02*
X1429567Y1011542D01*
X1429275Y1011708D01*
X1429025Y1011958D01*
X1428858Y1012250D01*
X1428775Y1012583D01*
Y1012917D01*
X1428858Y1013250D01*
X1429025Y1013542D01*
X1429275Y1013792D01*
X1429567Y1013958D01*
X1429900Y1014000D01*
X1430233Y1013958D01*
X1430525Y1013792D01*
X1430775Y1013542D01*
X1430942Y1013250D01*
X1431025Y1012917D01*
Y1012583D01*
X1430942Y1012250D01*
X1430775Y1011958D01*
X1430525Y1011708D01*
X1430233Y1011542D01*
X1429900Y1011500D01*
G01X1430233Y1012167D02*
X1430733Y1011500D01*
G01X1432208Y1013583D02*
X1432458Y1013833D01*
X1432750Y1013958D01*
X1433083Y1014000D01*
X1433500Y1013917D01*
X1433792Y1013708D01*
X1433875Y1013458D01*
X1433833Y1013208D01*
X1433667Y1013000D01*
X1432833Y1012583D01*
X1432458Y1012292D01*
X1432208Y1011875D01*
X1432125Y1011500D01*
X1433875D01*
G01X1435308Y1012542D02*
X1435600Y1012833D01*
X1435850Y1013000D01*
X1436183Y1013083D01*
X1436475Y1013000D01*
X1436683Y1012833D01*
X1436850Y1012583D01*
X1436892Y1012292D01*
X1436850Y1012042D01*
X1436683Y1011792D01*
X1436433Y1011583D01*
X1436142Y1011500D01*
X1435808Y1011583D01*
X1435517Y1011833D01*
X1435350Y1012208D01*
X1435308Y1012625D01*
X1435392Y1013167D01*
X1435517Y1013458D01*
X1435725Y1013750D01*
X1436017Y1013958D01*
X1436308Y1014000D01*
X1436600Y1013917D01*
X1436808Y1013708D01*
G01X1378000Y1035517D02*
X1375500D01*
Y1036558D01*
X1375625Y1036892D01*
X1375792Y1037100D01*
X1376125Y1037183D01*
X1376458Y1037100D01*
X1376667Y1036850D01*
X1376792Y1036558D01*
Y1035517D01*
G01Y1036558D02*
X1378000Y1037183D01*
G01X1375917Y1038658D02*
X1375667Y1038908D01*
X1375542Y1039200D01*
X1375500Y1039533D01*
X1375583Y1039950D01*
X1375792Y1040242D01*
X1376042Y1040325D01*
X1376292Y1040283D01*
X1376500Y1040117D01*
X1376917Y1039283D01*
X1377208Y1038908D01*
X1377625Y1038658D01*
X1378000Y1038575D01*
Y1040325D01*
G01Y1042467D02*
X1377458Y1042550D01*
X1377000Y1042675D01*
X1376583Y1042842D01*
X1376125Y1043050D01*
X1375500Y1043383D01*
Y1041717D01*
G01X1377500Y1044733D02*
X1377792Y1044983D01*
X1377958Y1045317D01*
X1378000Y1045692D01*
X1377958Y1046025D01*
X1377750Y1046358D01*
X1377500Y1046567D01*
X1377250Y1046608D01*
X1376958Y1046525D01*
X1376750Y1046233D01*
X1376667Y1045942D01*
Y1045567D01*
G01Y1045942D02*
X1376542Y1046192D01*
X1376333Y1046400D01*
X1376083Y1046483D01*
X1375833Y1046400D01*
X1375625Y1046192D01*
X1375500Y1045817D01*
X1375542Y1045442D01*
X1375708Y1045067D01*
G01X1428500Y1041700D02*
Y1047200D01*
G01X1436500Y1041700D02*
X1428500D01*
G01X1423500Y963900D02*
X1423458Y963567D01*
X1423292Y963275D01*
X1423042Y963025D01*
X1422750Y962858D01*
X1422417Y962775D01*
X1422083D01*
X1421750Y962858D01*
X1421458Y963025D01*
X1421208Y963275D01*
X1421042Y963567D01*
X1421000Y963900D01*
X1421042Y964233D01*
X1421208Y964525D01*
X1421458Y964775D01*
X1421750Y964942D01*
X1422083Y965025D01*
X1422417D01*
X1422750Y964942D01*
X1423042Y964775D01*
X1423292Y964525D01*
X1423458Y964233D01*
X1423500Y963900D01*
G01X1422833Y964233D02*
X1423500Y964733D01*
G01X1421417Y966208D02*
X1421167Y966458D01*
X1421042Y966750D01*
X1421000Y967083D01*
X1421083Y967500D01*
X1421292Y967792D01*
X1421542Y967875D01*
X1421792Y967833D01*
X1422000Y967667D01*
X1422417Y966833D01*
X1422708Y966458D01*
X1423125Y966208D01*
X1423500Y966125D01*
Y967875D01*
G01Y970017D02*
X1422958Y970100D01*
X1422500Y970225D01*
X1422083Y970392D01*
X1421625Y970600D01*
X1421000Y970933D01*
Y969267D01*
G01X1424800Y975200D02*
Y963800D01*
G01X1438200Y975200D02*
X1424800D01*
G01Y963800D02*
X1438200D01*
G01X1423017Y1023000D02*
Y1025500D01*
X1424058D01*
X1424392Y1025375D01*
X1424600Y1025208D01*
X1424683Y1024875D01*
X1424600Y1024542D01*
X1424350Y1024333D01*
X1424058Y1024208D01*
X1423017D01*
G01X1424058D02*
X1424683Y1023000D01*
G01X1426158Y1025083D02*
X1426408Y1025333D01*
X1426700Y1025458D01*
X1427033Y1025500D01*
X1427450Y1025417D01*
X1427742Y1025208D01*
X1427825Y1024958D01*
X1427783Y1024708D01*
X1427617Y1024500D01*
X1426783Y1024083D01*
X1426408Y1023792D01*
X1426158Y1023375D01*
X1426075Y1023000D01*
X1427825D01*
G01X1429967D02*
X1430050Y1023542D01*
X1430175Y1024000D01*
X1430342Y1024417D01*
X1430550Y1024875D01*
X1430883Y1025500D01*
X1429217D01*
G01X1433150D02*
X1432817Y1025417D01*
X1432567Y1025208D01*
X1432400Y1024958D01*
X1432275Y1024625D01*
X1432233Y1024250D01*
X1432275Y1023875D01*
X1432400Y1023542D01*
X1432567Y1023292D01*
X1432817Y1023083D01*
X1433150Y1023000D01*
X1433483Y1023083D01*
X1433733Y1023292D01*
X1433900Y1023542D01*
X1434025Y1023875D01*
X1434067Y1024250D01*
X1434025Y1024625D01*
X1433900Y1024958D01*
X1433733Y1025208D01*
X1433483Y1025417D01*
X1433150Y1025500D01*
G01X1437800Y1035500D02*
Y1027500D01*
X1420200D01*
Y1035500D01*
X1437800D01*
G01X1394325Y1114500D02*
Y1117000D01*
G01X1396075D02*
Y1114500D01*
G01Y1115750D02*
X1394325D01*
G01X1397383Y1114500D02*
Y1117000D01*
X1398217D01*
X1398550Y1116875D01*
X1398800Y1116708D01*
X1399008Y1116458D01*
X1399175Y1116167D01*
X1399217Y1115750D01*
X1399175Y1115333D01*
X1399008Y1115042D01*
X1398800Y1114792D01*
X1398550Y1114625D01*
X1398217Y1114500D01*
X1397383D01*
G01X1400483D02*
Y1117000D01*
X1401317D01*
X1401650Y1116875D01*
X1401900Y1116708D01*
X1402108Y1116458D01*
X1402275Y1116167D01*
X1402317Y1115750D01*
X1402275Y1115333D01*
X1402108Y1115042D01*
X1401900Y1114792D01*
X1401650Y1114625D01*
X1401317Y1114500D01*
X1400483D01*
G01X1403625Y1114833D02*
X1403958Y1114625D01*
X1404333Y1114500D01*
X1404667D01*
X1405000Y1114625D01*
X1405250Y1114833D01*
X1405375Y1115125D01*
X1405292Y1115417D01*
X1405083Y1115667D01*
X1404708Y1115833D01*
X1404208Y1115917D01*
X1403917Y1116083D01*
X1403792Y1116375D01*
X1403875Y1116667D01*
X1404083Y1116875D01*
X1404375Y1117000D01*
X1404667D01*
X1404958Y1116917D01*
X1405208Y1116708D01*
G01X1406558Y1114500D02*
X1407600Y1117000D01*
X1408642Y1114500D01*
G01X1408267Y1115375D02*
X1406933D01*
G01X1409825Y1114833D02*
X1410158Y1114625D01*
X1410533Y1114500D01*
X1410867D01*
X1411200Y1114625D01*
X1411450Y1114833D01*
X1411575Y1115125D01*
X1411492Y1115417D01*
X1411283Y1115667D01*
X1410908Y1115833D01*
X1410408Y1115917D01*
X1410117Y1116083D01*
X1409992Y1116375D01*
X1410075Y1116667D01*
X1410283Y1116875D01*
X1410575Y1117000D01*
X1410867D01*
X1411158Y1116917D01*
X1411408Y1116708D01*
G01X1413717Y1114500D02*
X1413800Y1115042D01*
X1413925Y1115500D01*
X1414092Y1115917D01*
X1414300Y1116375D01*
X1414633Y1117000D01*
X1412967D01*
G01X1421208Y1062767D02*
X1421083Y1062517D01*
X1421000Y1062225D01*
Y1061892D01*
X1421125Y1061517D01*
X1421333Y1061225D01*
X1421583Y1061017D01*
X1422000Y1060850D01*
X1422375Y1060808D01*
X1422750Y1060892D01*
X1423000Y1061017D01*
X1423250Y1061267D01*
X1423417Y1061558D01*
X1423500Y1061850D01*
Y1062142D01*
X1423417Y1062433D01*
X1423292Y1062683D01*
X1423125Y1062892D01*
G01X1423500Y1064950D02*
X1421000D01*
X1421500Y1064450D01*
G01X1423500D02*
Y1065450D01*
G01X1421417Y1067258D02*
X1421167Y1067508D01*
X1421042Y1067800D01*
X1421000Y1068133D01*
X1421083Y1068550D01*
X1421292Y1068842D01*
X1421542Y1068925D01*
X1421792Y1068883D01*
X1422000Y1068717D01*
X1422417Y1067883D01*
X1422708Y1067508D01*
X1423125Y1067258D01*
X1423500Y1067175D01*
Y1068925D01*
G01Y1071150D02*
X1421000D01*
X1421500Y1070650D01*
G01X1423500D02*
Y1071650D01*
G01X1421708Y1095767D02*
X1421583Y1095517D01*
X1421500Y1095225D01*
Y1094892D01*
X1421625Y1094517D01*
X1421833Y1094225D01*
X1422083Y1094017D01*
X1422500Y1093850D01*
X1422875Y1093808D01*
X1423250Y1093892D01*
X1423500Y1094017D01*
X1423750Y1094267D01*
X1423917Y1094558D01*
X1424000Y1094850D01*
Y1095142D01*
X1423917Y1095433D01*
X1423792Y1095683D01*
X1423625Y1095892D01*
G01X1424000Y1097950D02*
X1421500D01*
X1422000Y1097450D01*
G01X1424000D02*
Y1098450D01*
G01X1421917Y1100258D02*
X1421667Y1100508D01*
X1421542Y1100800D01*
X1421500Y1101133D01*
X1421583Y1101550D01*
X1421792Y1101842D01*
X1422042Y1101925D01*
X1422292Y1101883D01*
X1422500Y1101717D01*
X1422917Y1100883D01*
X1423208Y1100508D01*
X1423625Y1100258D01*
X1424000Y1100175D01*
Y1101925D01*
G01Y1104150D02*
X1423958Y1104442D01*
X1423833Y1104775D01*
X1423625Y1104983D01*
X1423333Y1105067D01*
X1423042Y1104983D01*
X1422792Y1104733D01*
X1422667Y1104358D01*
Y1103942D01*
X1422583Y1103692D01*
X1422375Y1103483D01*
X1422083Y1103400D01*
X1421792Y1103525D01*
X1421583Y1103817D01*
X1421500Y1104150D01*
X1421583Y1104483D01*
X1421792Y1104775D01*
X1422083Y1104900D01*
X1422375Y1104817D01*
X1422583Y1104608D01*
X1422667Y1104358D01*
Y1103942D01*
X1422792Y1103567D01*
X1423042Y1103317D01*
X1423333Y1103233D01*
X1423625Y1103317D01*
X1423833Y1103525D01*
X1423958Y1103858D01*
X1424000Y1104150D01*
G01X1375350Y1068500D02*
Y1066000D01*
G01X1374392Y1068500D02*
X1376308D01*
G01X1377617Y1066000D02*
Y1068500D01*
X1378617D01*
X1378950Y1068375D01*
X1379200Y1068083D01*
X1379283Y1067750D01*
X1379200Y1067417D01*
X1378992Y1067167D01*
X1378617Y1067042D01*
X1377617D01*
G01X1380633Y1066375D02*
X1380883Y1066167D01*
X1381175Y1066042D01*
X1381550Y1066000D01*
X1381925Y1066083D01*
X1382217Y1066250D01*
X1382425Y1066542D01*
X1382467Y1066875D01*
X1382383Y1067208D01*
X1382175Y1067417D01*
X1381883Y1067583D01*
X1381592Y1067625D01*
X1381300Y1067583D01*
X1380925Y1067417D01*
X1381050Y1068500D01*
X1382175D01*
G01X1383858Y1067042D02*
X1384150Y1067333D01*
X1384400Y1067500D01*
X1384733Y1067583D01*
X1385025Y1067500D01*
X1385233Y1067333D01*
X1385400Y1067083D01*
X1385442Y1066792D01*
X1385400Y1066542D01*
X1385233Y1066292D01*
X1384983Y1066083D01*
X1384692Y1066000D01*
X1384358Y1066083D01*
X1384067Y1066333D01*
X1383900Y1066708D01*
X1383858Y1067125D01*
X1383942Y1067667D01*
X1384067Y1067958D01*
X1384275Y1068250D01*
X1384567Y1068458D01*
X1384858Y1068500D01*
X1385150Y1068417D01*
X1385358Y1068208D01*
G01X1425208Y1061767D02*
X1425083Y1061517D01*
X1425000Y1061225D01*
Y1060892D01*
X1425125Y1060517D01*
X1425333Y1060225D01*
X1425583Y1060017D01*
X1426000Y1059850D01*
X1426375Y1059808D01*
X1426750Y1059892D01*
X1427000Y1060017D01*
X1427250Y1060267D01*
X1427417Y1060558D01*
X1427500Y1060850D01*
Y1061142D01*
X1427417Y1061433D01*
X1427292Y1061683D01*
X1427125Y1061892D01*
G01X1427500Y1063950D02*
X1425000D01*
X1425500Y1063450D01*
G01X1427500D02*
Y1064450D01*
G01X1425417Y1066258D02*
X1425167Y1066508D01*
X1425042Y1066800D01*
X1425000Y1067133D01*
X1425083Y1067550D01*
X1425292Y1067842D01*
X1425542Y1067925D01*
X1425792Y1067883D01*
X1426000Y1067717D01*
X1426417Y1066883D01*
X1426708Y1066508D01*
X1427125Y1066258D01*
X1427500Y1066175D01*
Y1067925D01*
G01X1425417Y1069358D02*
X1425167Y1069608D01*
X1425042Y1069900D01*
X1425000Y1070233D01*
X1425083Y1070650D01*
X1425292Y1070942D01*
X1425542Y1071025D01*
X1425792Y1070983D01*
X1426000Y1070817D01*
X1426417Y1069983D01*
X1426708Y1069608D01*
X1427125Y1069358D01*
X1427500Y1069275D01*
Y1071025D01*
G01X1428500Y1059300D02*
X1436500D01*
G01X1428500Y1053800D02*
Y1059300D01*
G01X1446300Y1069300D02*
Y1061300D01*
X1428700D01*
Y1069300D01*
X1446300D01*
G01X1428547Y1095767D02*
X1428422Y1095517D01*
X1428339Y1095225D01*
Y1094892D01*
X1428464Y1094517D01*
X1428672Y1094225D01*
X1428922Y1094017D01*
X1429339Y1093850D01*
X1429714Y1093808D01*
X1430089Y1093892D01*
X1430339Y1094017D01*
X1430589Y1094267D01*
X1430756Y1094558D01*
X1430839Y1094850D01*
Y1095142D01*
X1430756Y1095433D01*
X1430631Y1095683D01*
X1430464Y1095892D01*
G01X1430839Y1097950D02*
X1428339D01*
X1428839Y1097450D01*
G01X1430839D02*
Y1098450D01*
G01X1428756Y1100258D02*
X1428506Y1100508D01*
X1428381Y1100800D01*
X1428339Y1101133D01*
X1428422Y1101550D01*
X1428631Y1101842D01*
X1428881Y1101925D01*
X1429131Y1101883D01*
X1429339Y1101717D01*
X1429756Y1100883D01*
X1430047Y1100508D01*
X1430464Y1100258D01*
X1430839Y1100175D01*
Y1101925D01*
G01X1429797Y1103358D02*
X1429506Y1103650D01*
X1429339Y1103900D01*
X1429256Y1104233D01*
X1429339Y1104525D01*
X1429506Y1104733D01*
X1429756Y1104900D01*
X1430047Y1104942D01*
X1430297Y1104900D01*
X1430547Y1104733D01*
X1430756Y1104483D01*
X1430839Y1104192D01*
X1430756Y1103858D01*
X1430506Y1103567D01*
X1430131Y1103400D01*
X1429714Y1103358D01*
X1429172Y1103442D01*
X1428881Y1103567D01*
X1428589Y1103775D01*
X1428381Y1104067D01*
X1428339Y1104358D01*
X1428422Y1104650D01*
X1428631Y1104858D01*
G01X1374600Y1347900D02*
Y1320100D01*
X1402400D01*
Y1347900D01*
X1374600D01*
G01Y1314900D02*
Y1287100D01*
X1402400D01*
Y1314900D01*
X1374600D01*
G01X1390041Y1430592D02*
X1389791Y1430717D01*
X1389499Y1430800D01*
X1389166D01*
X1388791Y1430675D01*
X1388499Y1430467D01*
X1388291Y1430217D01*
X1388124Y1429800D01*
X1388082Y1429425D01*
X1388166Y1429050D01*
X1388291Y1428800D01*
X1388541Y1428550D01*
X1388832Y1428383D01*
X1389124Y1428300D01*
X1389416D01*
X1389707Y1428383D01*
X1389957Y1428508D01*
X1390166Y1428675D01*
G01X1391307D02*
X1391557Y1428467D01*
X1391849Y1428342D01*
X1392224Y1428300D01*
X1392599Y1428383D01*
X1392891Y1428550D01*
X1393099Y1428842D01*
X1393141Y1429175D01*
X1393057Y1429508D01*
X1392849Y1429717D01*
X1392557Y1429883D01*
X1392266Y1429925D01*
X1391974Y1429883D01*
X1391599Y1429717D01*
X1391724Y1430800D01*
X1392849D01*
G01X1394407Y1428800D02*
X1394657Y1428508D01*
X1394991Y1428342D01*
X1395366Y1428300D01*
X1395699Y1428342D01*
X1396032Y1428550D01*
X1396241Y1428800D01*
X1396282Y1429050D01*
X1396199Y1429342D01*
X1395907Y1429550D01*
X1395616Y1429633D01*
X1395241D01*
G01X1395616D02*
X1395866Y1429758D01*
X1396074Y1429967D01*
X1396157Y1430217D01*
X1396074Y1430467D01*
X1395866Y1430675D01*
X1395491Y1430800D01*
X1395116Y1430758D01*
X1394741Y1430592D01*
G01X1398424Y1428300D02*
Y1430800D01*
X1397924Y1430300D01*
G01Y1428300D02*
X1398924D01*
G01X1388141Y1422453D02*
X1387891Y1422578D01*
X1387599Y1422661D01*
X1387266D01*
X1386891Y1422536D01*
X1386599Y1422328D01*
X1386391Y1422078D01*
X1386224Y1421661D01*
X1386182Y1421286D01*
X1386266Y1420911D01*
X1386391Y1420661D01*
X1386641Y1420411D01*
X1386932Y1420244D01*
X1387224Y1420161D01*
X1387516D01*
X1387807Y1420244D01*
X1388057Y1420369D01*
X1388266Y1420536D01*
G01X1389407D02*
X1389657Y1420328D01*
X1389949Y1420203D01*
X1390324Y1420161D01*
X1390699Y1420244D01*
X1390991Y1420411D01*
X1391199Y1420703D01*
X1391241Y1421036D01*
X1391157Y1421369D01*
X1390949Y1421578D01*
X1390657Y1421744D01*
X1390366Y1421786D01*
X1390074Y1421744D01*
X1389699Y1421578D01*
X1389824Y1422661D01*
X1390949D01*
G01X1392507Y1420661D02*
X1392757Y1420369D01*
X1393091Y1420203D01*
X1393466Y1420161D01*
X1393799Y1420203D01*
X1394132Y1420411D01*
X1394341Y1420661D01*
X1394382Y1420911D01*
X1394299Y1421203D01*
X1394007Y1421411D01*
X1393716Y1421494D01*
X1393341D01*
G01X1393716D02*
X1393966Y1421619D01*
X1394174Y1421828D01*
X1394257Y1422078D01*
X1394174Y1422328D01*
X1393966Y1422536D01*
X1393591Y1422661D01*
X1393216Y1422619D01*
X1392841Y1422453D01*
G01X1396524Y1422661D02*
X1396191Y1422578D01*
X1395941Y1422369D01*
X1395774Y1422119D01*
X1395649Y1421786D01*
X1395607Y1421411D01*
X1395649Y1421036D01*
X1395774Y1420703D01*
X1395941Y1420453D01*
X1396191Y1420244D01*
X1396524Y1420161D01*
X1396857Y1420244D01*
X1397107Y1420453D01*
X1397274Y1420703D01*
X1397399Y1421036D01*
X1397441Y1421411D01*
X1397399Y1421786D01*
X1397274Y1422119D01*
X1397107Y1422369D01*
X1396857Y1422578D01*
X1396524Y1422661D01*
G01X1369374Y1427200D02*
X1363174D01*
Y1414800D01*
X1369374D01*
G01X1375374D02*
X1381574D01*
Y1427200D01*
X1375374D01*
G01X1393432Y1463000D02*
Y1465500D01*
X1395016D01*
G01X1394432Y1464292D02*
X1393432D01*
G01X1396282Y1463000D02*
X1397324Y1465500D01*
X1398366Y1463000D01*
G01X1397991Y1463875D02*
X1396657D01*
G01X1399466Y1463000D02*
Y1465500D01*
X1401382Y1463000D01*
Y1465500D01*
G01X1402607Y1463500D02*
X1402857Y1463208D01*
X1403191Y1463042D01*
X1403566Y1463000D01*
X1403899Y1463042D01*
X1404232Y1463250D01*
X1404441Y1463500D01*
X1404482Y1463750D01*
X1404399Y1464042D01*
X1404107Y1464250D01*
X1403816Y1464333D01*
X1403441D01*
G01X1403816D02*
X1404066Y1464458D01*
X1404274Y1464667D01*
X1404357Y1464917D01*
X1404274Y1465167D01*
X1404066Y1465375D01*
X1403691Y1465500D01*
X1403316Y1465458D01*
X1402941Y1465292D01*
G01X1389896Y1434637D02*
X1389646Y1434762D01*
X1389354Y1434845D01*
X1389021D01*
X1388646Y1434720D01*
X1388354Y1434512D01*
X1388146Y1434262D01*
X1387979Y1433845D01*
X1387937Y1433470D01*
X1388021Y1433095D01*
X1388146Y1432845D01*
X1388396Y1432595D01*
X1388687Y1432428D01*
X1388979Y1432345D01*
X1389271D01*
X1389562Y1432428D01*
X1389812Y1432553D01*
X1390021Y1432720D01*
G01X1391162D02*
X1391412Y1432512D01*
X1391704Y1432387D01*
X1392079Y1432345D01*
X1392454Y1432428D01*
X1392746Y1432595D01*
X1392954Y1432887D01*
X1392996Y1433220D01*
X1392912Y1433553D01*
X1392704Y1433762D01*
X1392412Y1433928D01*
X1392121Y1433970D01*
X1391829Y1433928D01*
X1391454Y1433762D01*
X1391579Y1434845D01*
X1392704D01*
G01X1394262Y1432845D02*
X1394512Y1432553D01*
X1394846Y1432387D01*
X1395221Y1432345D01*
X1395554Y1432387D01*
X1395887Y1432595D01*
X1396096Y1432845D01*
X1396137Y1433095D01*
X1396054Y1433387D01*
X1395762Y1433595D01*
X1395471Y1433678D01*
X1395096D01*
G01X1395471D02*
X1395721Y1433803D01*
X1395929Y1434012D01*
X1396012Y1434262D01*
X1395929Y1434512D01*
X1395721Y1434720D01*
X1395346Y1434845D01*
X1394971Y1434803D01*
X1394596Y1434637D01*
G01X1397487Y1434428D02*
X1397737Y1434678D01*
X1398029Y1434803D01*
X1398362Y1434845D01*
X1398779Y1434762D01*
X1399071Y1434553D01*
X1399154Y1434303D01*
X1399112Y1434053D01*
X1398946Y1433845D01*
X1398112Y1433428D01*
X1397737Y1433137D01*
X1397487Y1432720D01*
X1397404Y1432345D01*
X1399154D01*
G01X1513218Y107319D02*
X1518268D01*
Y206019D01*
X1542918D01*
Y21619D01*
X1518268D01*
Y80319D01*
X1513218D01*
Y107319D01*
G01X1501770Y63572D02*
X1501520Y63697D01*
X1501228Y63780D01*
X1500895D01*
X1500520Y63655D01*
X1500228Y63447D01*
X1500020Y63197D01*
X1499853Y62780D01*
X1499811Y62405D01*
X1499895Y62030D01*
X1500020Y61780D01*
X1500270Y61530D01*
X1500561Y61363D01*
X1500853Y61280D01*
X1501145D01*
X1501436Y61363D01*
X1501686Y61488D01*
X1501895Y61655D01*
G01X1504453Y61280D02*
Y63780D01*
X1502911Y61988D01*
X1504995D01*
G01X1507553Y61280D02*
Y63780D01*
X1506011Y61988D01*
X1508095D01*
G01X1509236Y61655D02*
X1509486Y61447D01*
X1509778Y61322D01*
X1510153Y61280D01*
X1510528Y61363D01*
X1510820Y61530D01*
X1511028Y61822D01*
X1511070Y62155D01*
X1510986Y62488D01*
X1510778Y62697D01*
X1510486Y62863D01*
X1510195Y62905D01*
X1509903Y62863D01*
X1509528Y62697D01*
X1509653Y63780D01*
X1510778D01*
G01X1501567Y67692D02*
X1501317Y67817D01*
X1501025Y67900D01*
X1500692D01*
X1500317Y67775D01*
X1500025Y67567D01*
X1499817Y67317D01*
X1499650Y66900D01*
X1499608Y66525D01*
X1499692Y66150D01*
X1499817Y65900D01*
X1500067Y65650D01*
X1500358Y65483D01*
X1500650Y65400D01*
X1500942D01*
X1501233Y65483D01*
X1501483Y65608D01*
X1501692Y65775D01*
G01X1504250Y65400D02*
Y67900D01*
X1502708Y66108D01*
X1504792D01*
G01X1507350Y65400D02*
Y67900D01*
X1505808Y66108D01*
X1507892D01*
G01X1510450Y65400D02*
Y67900D01*
X1508908Y66108D01*
X1510992D01*
G01X1452000Y46017D02*
X1449500D01*
Y47058D01*
X1449625Y47392D01*
X1449792Y47600D01*
X1450125Y47683D01*
X1450458Y47600D01*
X1450667Y47350D01*
X1450792Y47058D01*
Y46017D01*
G01Y47058D02*
X1452000Y47683D01*
G01Y49867D02*
X1451458Y49950D01*
X1451000Y50075D01*
X1450583Y50242D01*
X1450125Y50450D01*
X1449500Y50783D01*
Y49117D01*
G01X1451708Y52342D02*
X1451917Y52633D01*
X1452000Y52967D01*
X1451917Y53300D01*
X1451667Y53592D01*
X1451292Y53800D01*
X1450917Y53883D01*
X1450458D01*
X1450083Y53800D01*
X1449750Y53592D01*
X1449583Y53342D01*
X1449500Y53050D01*
X1449583Y52717D01*
X1449750Y52467D01*
X1450000Y52300D01*
X1450333Y52217D01*
X1450625Y52300D01*
X1450917Y52508D01*
X1451083Y52758D01*
X1451125Y53050D01*
X1451042Y53383D01*
X1450833Y53633D01*
X1450458Y53883D01*
G01X1451500Y55233D02*
X1451792Y55483D01*
X1451958Y55817D01*
X1452000Y56192D01*
X1451958Y56525D01*
X1451750Y56858D01*
X1451500Y57067D01*
X1451250Y57108D01*
X1450958Y57025D01*
X1450750Y56733D01*
X1450667Y56442D01*
Y56067D01*
G01Y56442D02*
X1450542Y56692D01*
X1450333Y56900D01*
X1450083Y56983D01*
X1449833Y56900D01*
X1449625Y56692D01*
X1449500Y56317D01*
X1449542Y55942D01*
X1449708Y55567D01*
G01X1444000Y49800D02*
X1448000D01*
Y57200D01*
G01X1461339Y57517D02*
X1458839D01*
Y58558D01*
X1458964Y58892D01*
X1459131Y59100D01*
X1459464Y59183D01*
X1459797Y59100D01*
X1460006Y58850D01*
X1460131Y58558D01*
Y57517D01*
G01Y58558D02*
X1461339Y59183D01*
G01Y61367D02*
X1460797Y61450D01*
X1460339Y61575D01*
X1459922Y61742D01*
X1459464Y61950D01*
X1458839Y62283D01*
Y60617D01*
G01X1461047Y63842D02*
X1461256Y64133D01*
X1461339Y64467D01*
X1461256Y64800D01*
X1461006Y65092D01*
X1460631Y65300D01*
X1460256Y65383D01*
X1459797D01*
X1459422Y65300D01*
X1459089Y65092D01*
X1458922Y64842D01*
X1458839Y64550D01*
X1458922Y64217D01*
X1459089Y63967D01*
X1459339Y63800D01*
X1459672Y63717D01*
X1459964Y63800D01*
X1460256Y64008D01*
X1460422Y64258D01*
X1460464Y64550D01*
X1460381Y64883D01*
X1460172Y65133D01*
X1459797Y65383D01*
G01X1460297Y66858D02*
X1460006Y67150D01*
X1459839Y67400D01*
X1459756Y67733D01*
X1459839Y68025D01*
X1460006Y68233D01*
X1460256Y68400D01*
X1460547Y68442D01*
X1460797Y68400D01*
X1461047Y68233D01*
X1461256Y67983D01*
X1461339Y67692D01*
X1461256Y67358D01*
X1461006Y67067D01*
X1460631Y66900D01*
X1460214Y66858D01*
X1459672Y66942D01*
X1459381Y67067D01*
X1459089Y67275D01*
X1458881Y67567D01*
X1458839Y67858D01*
X1458922Y68150D01*
X1459131Y68358D01*
G01X1448500Y62300D02*
X1452500D01*
Y69700D01*
G01X1463517Y79500D02*
Y82000D01*
X1464558D01*
X1464892Y81875D01*
X1465100Y81708D01*
X1465183Y81375D01*
X1465100Y81042D01*
X1464850Y80833D01*
X1464558Y80708D01*
X1463517D01*
G01X1464558D02*
X1465183Y79500D01*
G01X1467367D02*
X1467450Y80042D01*
X1467575Y80500D01*
X1467742Y80917D01*
X1467950Y81375D01*
X1468283Y82000D01*
X1466617D01*
G01X1469842Y79792D02*
X1470133Y79583D01*
X1470467Y79500D01*
X1470800Y79583D01*
X1471092Y79833D01*
X1471300Y80208D01*
X1471383Y80583D01*
Y81042D01*
X1471300Y81417D01*
X1471092Y81750D01*
X1470842Y81917D01*
X1470550Y82000D01*
X1470217Y81917D01*
X1469967Y81750D01*
X1469800Y81500D01*
X1469717Y81167D01*
X1469800Y80875D01*
X1470008Y80583D01*
X1470258Y80417D01*
X1470550Y80375D01*
X1470883Y80458D01*
X1471133Y80667D01*
X1471383Y81042D01*
G01X1472942Y79792D02*
X1473233Y79583D01*
X1473567Y79500D01*
X1473900Y79583D01*
X1474192Y79833D01*
X1474400Y80208D01*
X1474483Y80583D01*
Y81042D01*
X1474400Y81417D01*
X1474192Y81750D01*
X1473942Y81917D01*
X1473650Y82000D01*
X1473317Y81917D01*
X1473067Y81750D01*
X1472900Y81500D01*
X1472817Y81167D01*
X1472900Y80875D01*
X1473108Y80583D01*
X1473358Y80417D01*
X1473650Y80375D01*
X1473983Y80458D01*
X1474233Y80667D01*
X1474483Y81042D01*
G01X1451300Y82500D02*
Y78500D01*
X1458700D01*
G01X1456839Y57517D02*
X1454339D01*
Y58558D01*
X1454464Y58892D01*
X1454631Y59100D01*
X1454964Y59183D01*
X1455297Y59100D01*
X1455506Y58850D01*
X1455631Y58558D01*
Y57517D01*
G01Y58558D02*
X1456839Y59183D01*
G01Y61450D02*
X1456797Y61742D01*
X1456672Y62075D01*
X1456464Y62283D01*
X1456172Y62367D01*
X1455881Y62283D01*
X1455631Y62033D01*
X1455506Y61658D01*
Y61242D01*
X1455422Y60992D01*
X1455214Y60783D01*
X1454922Y60700D01*
X1454631Y60825D01*
X1454422Y61117D01*
X1454339Y61450D01*
X1454422Y61783D01*
X1454631Y62075D01*
X1454922Y62200D01*
X1455214Y62117D01*
X1455422Y61908D01*
X1455506Y61658D01*
Y61242D01*
X1455631Y60867D01*
X1455881Y60617D01*
X1456172Y60533D01*
X1456464Y60617D01*
X1456672Y60825D01*
X1456797Y61158D01*
X1456839Y61450D01*
G01X1454339Y64550D02*
X1454422Y64217D01*
X1454631Y63967D01*
X1454881Y63800D01*
X1455214Y63675D01*
X1455589Y63633D01*
X1455964Y63675D01*
X1456297Y63800D01*
X1456547Y63967D01*
X1456756Y64217D01*
X1456839Y64550D01*
X1456756Y64883D01*
X1456547Y65133D01*
X1456297Y65300D01*
X1455964Y65425D01*
X1455589Y65467D01*
X1455214Y65425D01*
X1454881Y65300D01*
X1454631Y65133D01*
X1454422Y64883D01*
X1454339Y64550D01*
G01Y67650D02*
X1454422Y67317D01*
X1454631Y67067D01*
X1454881Y66900D01*
X1455214Y66775D01*
X1455589Y66733D01*
X1455964Y66775D01*
X1456297Y66900D01*
X1456547Y67067D01*
X1456756Y67317D01*
X1456839Y67650D01*
X1456756Y67983D01*
X1456547Y68233D01*
X1456297Y68400D01*
X1455964Y68525D01*
X1455589Y68567D01*
X1455214Y68525D01*
X1454881Y68400D01*
X1454631Y68233D01*
X1454422Y67983D01*
X1454339Y67650D01*
G01X1444000Y62300D02*
X1448000D01*
Y69700D01*
G01X1436900Y104800D02*
Y85600D01*
X1448100D01*
Y104800D01*
X1436900D01*
Y104400D01*
G01X1462983Y73000D02*
Y75500D01*
X1463817D01*
X1464150Y75375D01*
X1464400Y75208D01*
X1464608Y74958D01*
X1464775Y74667D01*
X1464817Y74250D01*
X1464775Y73833D01*
X1464608Y73542D01*
X1464400Y73292D01*
X1464150Y73125D01*
X1463817Y73000D01*
X1462983D01*
G01X1466083Y73500D02*
X1466333Y73208D01*
X1466667Y73042D01*
X1467042Y73000D01*
X1467375Y73042D01*
X1467708Y73250D01*
X1467917Y73500D01*
X1467958Y73750D01*
X1467875Y74042D01*
X1467583Y74250D01*
X1467292Y74333D01*
X1466917D01*
G01X1467292D02*
X1467542Y74458D01*
X1467750Y74667D01*
X1467833Y74917D01*
X1467750Y75167D01*
X1467542Y75375D01*
X1467167Y75500D01*
X1466792Y75458D01*
X1466417Y75292D01*
G01X1470100Y73000D02*
Y75500D01*
X1469600Y75000D01*
G01Y73000D02*
X1470600D01*
G01X1460500Y70500D02*
X1444400D01*
G01X1460500Y77500D02*
Y70500D01*
G01X1444400Y77500D02*
X1460500D01*
G01X1444400Y70500D02*
Y77500D01*
G01X1438200Y58300D02*
Y69700D01*
G01X1464267Y114453D02*
X1464017Y114578D01*
X1463725Y114661D01*
X1463392D01*
X1463017Y114536D01*
X1462725Y114328D01*
X1462517Y114078D01*
X1462350Y113661D01*
X1462308Y113286D01*
X1462392Y112911D01*
X1462517Y112661D01*
X1462767Y112411D01*
X1463058Y112244D01*
X1463350Y112161D01*
X1463642D01*
X1463933Y112244D01*
X1464183Y112369D01*
X1464392Y112536D01*
G01X1466950Y112161D02*
Y114661D01*
X1465408Y112869D01*
X1467492D01*
G01X1470050Y112161D02*
Y114661D01*
X1468508Y112869D01*
X1470592D01*
G01X1471858Y114244D02*
X1472108Y114494D01*
X1472400Y114619D01*
X1472733Y114661D01*
X1473150Y114578D01*
X1473442Y114369D01*
X1473525Y114119D01*
X1473483Y113869D01*
X1473317Y113661D01*
X1472483Y113244D01*
X1472108Y112953D01*
X1471858Y112536D01*
X1471775Y112161D01*
X1473525D01*
G01X1513947Y131867D02*
X1513822Y131617D01*
X1513739Y131325D01*
Y130992D01*
X1513864Y130617D01*
X1514072Y130325D01*
X1514322Y130117D01*
X1514739Y129950D01*
X1515114Y129908D01*
X1515489Y129992D01*
X1515739Y130117D01*
X1515989Y130367D01*
X1516156Y130658D01*
X1516239Y130950D01*
Y131242D01*
X1516156Y131533D01*
X1516031Y131783D01*
X1515864Y131992D01*
G01X1516239Y134550D02*
X1513739D01*
X1515531Y133008D01*
Y135092D01*
G01X1515864Y136233D02*
X1516072Y136483D01*
X1516197Y136775D01*
X1516239Y137150D01*
X1516156Y137525D01*
X1515989Y137817D01*
X1515697Y138025D01*
X1515364Y138067D01*
X1515031Y137983D01*
X1514822Y137775D01*
X1514656Y137483D01*
X1514614Y137192D01*
X1514656Y136900D01*
X1514822Y136525D01*
X1513739Y136650D01*
Y137775D01*
G01X1515739Y139333D02*
X1516031Y139583D01*
X1516197Y139917D01*
X1516239Y140292D01*
X1516197Y140625D01*
X1515989Y140958D01*
X1515739Y141167D01*
X1515489Y141208D01*
X1515197Y141125D01*
X1514989Y140833D01*
X1514906Y140542D01*
Y140167D01*
G01Y140542D02*
X1514781Y140792D01*
X1514572Y141000D01*
X1514322Y141083D01*
X1514072Y141000D01*
X1513864Y140792D01*
X1513739Y140417D01*
X1513781Y140042D01*
X1513947Y139667D01*
G01X1462517Y108161D02*
Y110661D01*
X1463558D01*
X1463892Y110536D01*
X1464100Y110369D01*
X1464183Y110036D01*
X1464100Y109703D01*
X1463850Y109494D01*
X1463558Y109369D01*
X1462517D01*
G01X1463558D02*
X1464183Y108161D01*
G01X1466367D02*
X1466450Y108703D01*
X1466575Y109161D01*
X1466742Y109578D01*
X1466950Y110036D01*
X1467283Y110661D01*
X1465617D01*
G01X1468842Y108453D02*
X1469133Y108244D01*
X1469467Y108161D01*
X1469800Y108244D01*
X1470092Y108494D01*
X1470300Y108869D01*
X1470383Y109244D01*
Y109703D01*
X1470300Y110078D01*
X1470092Y110411D01*
X1469842Y110578D01*
X1469550Y110661D01*
X1469217Y110578D01*
X1468967Y110411D01*
X1468800Y110161D01*
X1468717Y109828D01*
X1468800Y109536D01*
X1469008Y109244D01*
X1469258Y109078D01*
X1469550Y109036D01*
X1469883Y109119D01*
X1470133Y109328D01*
X1470383Y109703D01*
G01X1472567Y108161D02*
X1472650Y108703D01*
X1472775Y109161D01*
X1472942Y109578D01*
X1473150Y110036D01*
X1473483Y110661D01*
X1471817D01*
G01X1461200Y107500D02*
Y111500D01*
X1453800D01*
G01X1512239Y130117D02*
X1509739D01*
Y131158D01*
X1509864Y131492D01*
X1510031Y131700D01*
X1510364Y131783D01*
X1510697Y131700D01*
X1510906Y131450D01*
X1511031Y131158D01*
Y130117D01*
G01Y131158D02*
X1512239Y131783D01*
G01Y134050D02*
X1512197Y134342D01*
X1512072Y134675D01*
X1511864Y134883D01*
X1511572Y134967D01*
X1511281Y134883D01*
X1511031Y134633D01*
X1510906Y134258D01*
Y133842D01*
X1510822Y133592D01*
X1510614Y133383D01*
X1510322Y133300D01*
X1510031Y133425D01*
X1509822Y133717D01*
X1509739Y134050D01*
X1509822Y134383D01*
X1510031Y134675D01*
X1510322Y134800D01*
X1510614Y134717D01*
X1510822Y134508D01*
X1510906Y134258D01*
Y133842D01*
X1511031Y133467D01*
X1511281Y133217D01*
X1511572Y133133D01*
X1511864Y133217D01*
X1512072Y133425D01*
X1512197Y133758D01*
X1512239Y134050D01*
G01X1509739Y137150D02*
X1509822Y136817D01*
X1510031Y136567D01*
X1510281Y136400D01*
X1510614Y136275D01*
X1510989Y136233D01*
X1511364Y136275D01*
X1511697Y136400D01*
X1511947Y136567D01*
X1512156Y136817D01*
X1512239Y137150D01*
X1512156Y137483D01*
X1511947Y137733D01*
X1511697Y137900D01*
X1511364Y138025D01*
X1510989Y138067D01*
X1510614Y138025D01*
X1510281Y137900D01*
X1510031Y137733D01*
X1509822Y137483D01*
X1509739Y137150D01*
G01X1511197Y139458D02*
X1510906Y139750D01*
X1510739Y140000D01*
X1510656Y140333D01*
X1510739Y140625D01*
X1510906Y140833D01*
X1511156Y141000D01*
X1511447Y141042D01*
X1511697Y141000D01*
X1511947Y140833D01*
X1512156Y140583D01*
X1512239Y140292D01*
X1512156Y139958D01*
X1511906Y139667D01*
X1511531Y139500D01*
X1511114Y139458D01*
X1510572Y139542D01*
X1510281Y139667D01*
X1509989Y139875D01*
X1509781Y140167D01*
X1509739Y140458D01*
X1509822Y140750D01*
X1510031Y140958D01*
G01X1509400Y120900D02*
X1513400D01*
Y128300D01*
G01X1498300Y162500D02*
Y160000D01*
G01X1497342Y162500D02*
X1499258D01*
G01X1500567Y160000D02*
Y162500D01*
X1501567D01*
X1501900Y162375D01*
X1502150Y162083D01*
X1502233Y161750D01*
X1502150Y161417D01*
X1501942Y161167D01*
X1501567Y161042D01*
X1500567D01*
G01X1504500Y160000D02*
Y162500D01*
X1504000Y162000D01*
G01Y160000D02*
X1505000D01*
G01X1507600D02*
X1507892Y160042D01*
X1508225Y160167D01*
X1508433Y160375D01*
X1508517Y160667D01*
X1508433Y160958D01*
X1508183Y161208D01*
X1507808Y161333D01*
X1507392D01*
X1507142Y161417D01*
X1506933Y161625D01*
X1506850Y161917D01*
X1506975Y162208D01*
X1507267Y162417D01*
X1507600Y162500D01*
X1507933Y162417D01*
X1508225Y162208D01*
X1508350Y161917D01*
X1508267Y161625D01*
X1508058Y161417D01*
X1507808Y161333D01*
X1507392D01*
X1507017Y161208D01*
X1506767Y160958D01*
X1506683Y160667D01*
X1506767Y160375D01*
X1506975Y160167D01*
X1507308Y160042D01*
X1507600Y160000D01*
G01X1510700D02*
Y162500D01*
X1510200Y162000D01*
G01Y160000D02*
X1511200D01*
G01X1444500Y104700D02*
X1442700Y102600D01*
X1440500Y104700D01*
G01X1450350Y145500D02*
X1450017Y145542D01*
X1449725Y145708D01*
X1449475Y145958D01*
X1449308Y146250D01*
X1449225Y146583D01*
Y146917D01*
X1449308Y147250D01*
X1449475Y147542D01*
X1449725Y147792D01*
X1450017Y147958D01*
X1450350Y148000D01*
X1450683Y147958D01*
X1450975Y147792D01*
X1451225Y147542D01*
X1451392Y147250D01*
X1451475Y146917D01*
Y146583D01*
X1451392Y146250D01*
X1451225Y145958D01*
X1450975Y145708D01*
X1450683Y145542D01*
X1450350Y145500D01*
G01X1450683Y146167D02*
X1451183Y145500D01*
G01X1453450D02*
Y148000D01*
X1452950Y147500D01*
G01Y145500D02*
X1453950D01*
G01X1455758Y146542D02*
X1456050Y146833D01*
X1456300Y147000D01*
X1456633Y147083D01*
X1456925Y147000D01*
X1457133Y146833D01*
X1457300Y146583D01*
X1457342Y146292D01*
X1457300Y146042D01*
X1457133Y145792D01*
X1456883Y145583D01*
X1456592Y145500D01*
X1456258Y145583D01*
X1455967Y145833D01*
X1455800Y146208D01*
X1455758Y146625D01*
X1455842Y147167D01*
X1455967Y147458D01*
X1456175Y147750D01*
X1456467Y147958D01*
X1456758Y148000D01*
X1457050Y147917D01*
X1457258Y147708D01*
G01X1458858Y147583D02*
X1459108Y147833D01*
X1459400Y147958D01*
X1459733Y148000D01*
X1460150Y147917D01*
X1460442Y147708D01*
X1460525Y147458D01*
X1460483Y147208D01*
X1460317Y147000D01*
X1459483Y146583D01*
X1459108Y146292D01*
X1458858Y145875D01*
X1458775Y145500D01*
X1460525D01*
G01X1439300Y132000D02*
X1441400Y130200D01*
X1439300Y128000D01*
G01X1439200Y124400D02*
X1458400D01*
Y135600D01*
X1439200D01*
Y124400D01*
X1439600D01*
G01X1502000Y138517D02*
X1499500D01*
Y139558D01*
X1499625Y139892D01*
X1499792Y140100D01*
X1500125Y140183D01*
X1500458Y140100D01*
X1500667Y139850D01*
X1500792Y139558D01*
Y138517D01*
G01Y139558D02*
X1502000Y140183D01*
G01Y142450D02*
X1501958Y142742D01*
X1501833Y143075D01*
X1501625Y143283D01*
X1501333Y143367D01*
X1501042Y143283D01*
X1500792Y143033D01*
X1500667Y142658D01*
Y142242D01*
X1500583Y141992D01*
X1500375Y141783D01*
X1500083Y141700D01*
X1499792Y141825D01*
X1499583Y142117D01*
X1499500Y142450D01*
X1499583Y142783D01*
X1499792Y143075D01*
X1500083Y143200D01*
X1500375Y143117D01*
X1500583Y142908D01*
X1500667Y142658D01*
Y142242D01*
X1500792Y141867D01*
X1501042Y141617D01*
X1501333Y141533D01*
X1501625Y141617D01*
X1501833Y141825D01*
X1501958Y142158D01*
X1502000Y142450D01*
G01Y145550D02*
X1499500D01*
X1500000Y145050D01*
G01X1502000D02*
Y146050D01*
G01X1499500Y148650D02*
X1499583Y148317D01*
X1499792Y148067D01*
X1500042Y147900D01*
X1500375Y147775D01*
X1500750Y147733D01*
X1501125Y147775D01*
X1501458Y147900D01*
X1501708Y148067D01*
X1501917Y148317D01*
X1502000Y148650D01*
X1501917Y148983D01*
X1501708Y149233D01*
X1501458Y149400D01*
X1501125Y149525D01*
X1500750Y149567D01*
X1500375Y149525D01*
X1500042Y149400D01*
X1499792Y149233D01*
X1499583Y148983D01*
X1499500Y148650D01*
G01X1436500Y141700D02*
Y136200D01*
G01Y153800D02*
Y148300D01*
G01X1436208Y190267D02*
X1436083Y190017D01*
X1436000Y189725D01*
Y189392D01*
X1436125Y189017D01*
X1436333Y188725D01*
X1436583Y188517D01*
X1437000Y188350D01*
X1437375Y188308D01*
X1437750Y188392D01*
X1438000Y188517D01*
X1438250Y188767D01*
X1438417Y189058D01*
X1438500Y189350D01*
Y189642D01*
X1438417Y189933D01*
X1438292Y190183D01*
X1438125Y190392D01*
G01X1438500Y192950D02*
X1436000D01*
X1437792Y191408D01*
Y193492D01*
G01X1438000Y194633D02*
X1438292Y194883D01*
X1438458Y195217D01*
X1438500Y195592D01*
X1438458Y195925D01*
X1438250Y196258D01*
X1438000Y196467D01*
X1437750Y196508D01*
X1437458Y196425D01*
X1437250Y196133D01*
X1437167Y195842D01*
Y195467D01*
G01Y195842D02*
X1437042Y196092D01*
X1436833Y196300D01*
X1436583Y196383D01*
X1436333Y196300D01*
X1436125Y196092D01*
X1436000Y195717D01*
X1436042Y195342D01*
X1436208Y194967D01*
G01X1438500Y198650D02*
X1438458Y198942D01*
X1438333Y199275D01*
X1438125Y199483D01*
X1437833Y199567D01*
X1437542Y199483D01*
X1437292Y199233D01*
X1437167Y198858D01*
Y198442D01*
X1437083Y198192D01*
X1436875Y197983D01*
X1436583Y197900D01*
X1436292Y198025D01*
X1436083Y198317D01*
X1436000Y198650D01*
X1436083Y198983D01*
X1436292Y199275D01*
X1436583Y199400D01*
X1436875Y199317D01*
X1437083Y199108D01*
X1437167Y198858D01*
Y198442D01*
X1437292Y198067D01*
X1437542Y197817D01*
X1437833Y197733D01*
X1438125Y197817D01*
X1438333Y198025D01*
X1438458Y198358D01*
X1438500Y198650D01*
G01X1518775Y209000D02*
Y211500D01*
G01X1520525D02*
Y209000D01*
G01Y210250D02*
X1518775D01*
G01X1521833Y209000D02*
Y211500D01*
X1522667D01*
X1523000Y211375D01*
X1523250Y211208D01*
X1523458Y210958D01*
X1523625Y210667D01*
X1523667Y210250D01*
X1523625Y209833D01*
X1523458Y209542D01*
X1523250Y209292D01*
X1523000Y209125D01*
X1522667Y209000D01*
X1521833D01*
G01X1524933D02*
Y211500D01*
X1525767D01*
X1526100Y211375D01*
X1526350Y211208D01*
X1526558Y210958D01*
X1526725Y210667D01*
X1526767Y210250D01*
X1526725Y209833D01*
X1526558Y209542D01*
X1526350Y209292D01*
X1526100Y209125D01*
X1525767Y209000D01*
X1524933D01*
G01X1528075Y209333D02*
X1528408Y209125D01*
X1528783Y209000D01*
X1529117D01*
X1529450Y209125D01*
X1529700Y209333D01*
X1529825Y209625D01*
X1529742Y209917D01*
X1529533Y210167D01*
X1529158Y210333D01*
X1528658Y210417D01*
X1528367Y210583D01*
X1528242Y210875D01*
X1528325Y211167D01*
X1528533Y211375D01*
X1528825Y211500D01*
X1529117D01*
X1529408Y211417D01*
X1529658Y211208D01*
G01X1531008Y209000D02*
X1532050Y211500D01*
X1533092Y209000D01*
G01X1532717Y209875D02*
X1531383D01*
G01X1534275Y209333D02*
X1534608Y209125D01*
X1534983Y209000D01*
X1535317D01*
X1535650Y209125D01*
X1535900Y209333D01*
X1536025Y209625D01*
X1535942Y209917D01*
X1535733Y210167D01*
X1535358Y210333D01*
X1534858Y210417D01*
X1534567Y210583D01*
X1534442Y210875D01*
X1534525Y211167D01*
X1534733Y211375D01*
X1535025Y211500D01*
X1535317D01*
X1535608Y211417D01*
X1535858Y211208D01*
G01X1537333Y209500D02*
X1537583Y209208D01*
X1537917Y209042D01*
X1538292Y209000D01*
X1538625Y209042D01*
X1538958Y209250D01*
X1539167Y209500D01*
X1539208Y209750D01*
X1539125Y210042D01*
X1538833Y210250D01*
X1538542Y210333D01*
X1538167D01*
G01X1538542D02*
X1538792Y210458D01*
X1539000Y210667D01*
X1539083Y210917D01*
X1539000Y211167D01*
X1538792Y211375D01*
X1538417Y211500D01*
X1538042Y211458D01*
X1537667Y211292D01*
G01X1540558Y211083D02*
X1540808Y211333D01*
X1541100Y211458D01*
X1541433Y211500D01*
X1541850Y211417D01*
X1542142Y211208D01*
X1542225Y210958D01*
X1542183Y210708D01*
X1542017Y210500D01*
X1541183Y210083D01*
X1540808Y209792D01*
X1540558Y209375D01*
X1540475Y209000D01*
X1542225D01*
G01X1481967Y269500D02*
Y267000D01*
X1483633D01*
G01X1486733D02*
X1485067D01*
Y269500D01*
X1486733D01*
G01X1486067Y268292D02*
X1485067D01*
G01X1488083Y267000D02*
Y269500D01*
X1488917D01*
X1489250Y269375D01*
X1489500Y269208D01*
X1489708Y268958D01*
X1489875Y268667D01*
X1489917Y268250D01*
X1489875Y267833D01*
X1489708Y267542D01*
X1489500Y267292D01*
X1489250Y267125D01*
X1488917Y267000D01*
X1488083D01*
G01X1491308Y269083D02*
X1491558Y269333D01*
X1491850Y269458D01*
X1492183Y269500D01*
X1492600Y269417D01*
X1492892Y269208D01*
X1492975Y268958D01*
X1492933Y268708D01*
X1492767Y268500D01*
X1491933Y268083D01*
X1491558Y267792D01*
X1491308Y267375D01*
X1491225Y267000D01*
X1492975D01*
G01X1495200D02*
Y269500D01*
X1494700Y269000D01*
G01Y267000D02*
X1495700D01*
G01X1484773Y251880D02*
Y263080D01*
X1493573D01*
Y251880D01*
X1484773D01*
G01X1513218Y560075D02*
X1518268D01*
Y658775D01*
X1542918D01*
Y474375D01*
X1518268D01*
Y533075D01*
X1513218D01*
Y560075D01*
G01X1447517Y382000D02*
Y384500D01*
X1448558D01*
X1448892Y384375D01*
X1449100Y384208D01*
X1449183Y383875D01*
X1449100Y383542D01*
X1448850Y383333D01*
X1448558Y383208D01*
X1447517D01*
G01X1448558D02*
X1449183Y382000D01*
G01X1451950D02*
Y384500D01*
X1450408Y382708D01*
X1452492D01*
G01X1454467Y382000D02*
X1454550Y382542D01*
X1454675Y383000D01*
X1454842Y383417D01*
X1455050Y383875D01*
X1455383Y384500D01*
X1453717D01*
G01X1456942Y382292D02*
X1457233Y382083D01*
X1457567Y382000D01*
X1457900Y382083D01*
X1458192Y382333D01*
X1458400Y382708D01*
X1458483Y383083D01*
Y383542D01*
X1458400Y383917D01*
X1458192Y384250D01*
X1457942Y384417D01*
X1457650Y384500D01*
X1457317Y384417D01*
X1457067Y384250D01*
X1456900Y384000D01*
X1456817Y383667D01*
X1456900Y383375D01*
X1457108Y383083D01*
X1457358Y382917D01*
X1457650Y382875D01*
X1457983Y382958D01*
X1458233Y383167D01*
X1458483Y383542D01*
G01X1467486Y381426D02*
Y385426D01*
X1460086D01*
G01X1473517Y406000D02*
Y408500D01*
X1474558D01*
X1474892Y408375D01*
X1475100Y408208D01*
X1475183Y407875D01*
X1475100Y407542D01*
X1474850Y407333D01*
X1474558Y407208D01*
X1473517D01*
G01X1474558D02*
X1475183Y406000D01*
G01X1477950D02*
Y408500D01*
X1476408Y406708D01*
X1478492D01*
G01X1480467Y406000D02*
X1480550Y406542D01*
X1480675Y407000D01*
X1480842Y407417D01*
X1481050Y407875D01*
X1481383Y408500D01*
X1479717D01*
G01X1484150Y406000D02*
Y408500D01*
X1482608Y406708D01*
X1484692D01*
G01X1482219Y401203D02*
Y405203D01*
X1474819D01*
G01X1488400Y399517D02*
X1485900D01*
Y400558D01*
X1486025Y400892D01*
X1486192Y401100D01*
X1486525Y401183D01*
X1486858Y401100D01*
X1487067Y400850D01*
X1487192Y400558D01*
Y399517D01*
G01Y400558D02*
X1488400Y401183D01*
G01Y403950D02*
X1485900D01*
X1487692Y402408D01*
Y404492D01*
G01X1487900Y405633D02*
X1488192Y405883D01*
X1488358Y406217D01*
X1488400Y406592D01*
X1488358Y406925D01*
X1488150Y407258D01*
X1487900Y407467D01*
X1487650Y407508D01*
X1487358Y407425D01*
X1487150Y407133D01*
X1487067Y406842D01*
Y406467D01*
G01Y406842D02*
X1486942Y407092D01*
X1486733Y407300D01*
X1486483Y407383D01*
X1486233Y407300D01*
X1486025Y407092D01*
X1485900Y406717D01*
X1485942Y406342D01*
X1486108Y405967D01*
G01X1487358Y408858D02*
X1487067Y409150D01*
X1486900Y409400D01*
X1486817Y409733D01*
X1486900Y410025D01*
X1487067Y410233D01*
X1487317Y410400D01*
X1487608Y410442D01*
X1487858Y410400D01*
X1488108Y410233D01*
X1488317Y409983D01*
X1488400Y409692D01*
X1488317Y409358D01*
X1488067Y409067D01*
X1487692Y408900D01*
X1487275Y408858D01*
X1486733Y408942D01*
X1486442Y409067D01*
X1486150Y409275D01*
X1485942Y409567D01*
X1485900Y409858D01*
X1485983Y410150D01*
X1486192Y410358D01*
G01X1495100Y399817D02*
X1492600D01*
Y400858D01*
X1492725Y401192D01*
X1492892Y401400D01*
X1493225Y401483D01*
X1493558Y401400D01*
X1493767Y401150D01*
X1493892Y400858D01*
Y399817D01*
G01Y400858D02*
X1495100Y401483D01*
G01Y404250D02*
X1492600D01*
X1494392Y402708D01*
Y404792D01*
G01X1495100Y407350D02*
X1492600D01*
X1494392Y405808D01*
Y407892D01*
G01X1494600Y409033D02*
X1494892Y409283D01*
X1495058Y409617D01*
X1495100Y409992D01*
X1495058Y410325D01*
X1494850Y410658D01*
X1494600Y410867D01*
X1494350Y410908D01*
X1494058Y410825D01*
X1493850Y410533D01*
X1493767Y410242D01*
Y409867D01*
G01Y410242D02*
X1493642Y410492D01*
X1493433Y410700D01*
X1493183Y410783D01*
X1492933Y410700D01*
X1492725Y410492D01*
X1492600Y410117D01*
X1492642Y409742D01*
X1492808Y409367D01*
G01X1472850Y382000D02*
X1472517Y382042D01*
X1472225Y382208D01*
X1471975Y382458D01*
X1471808Y382750D01*
X1471725Y383083D01*
Y383417D01*
X1471808Y383750D01*
X1471975Y384042D01*
X1472225Y384292D01*
X1472517Y384458D01*
X1472850Y384500D01*
X1473183Y384458D01*
X1473475Y384292D01*
X1473725Y384042D01*
X1473892Y383750D01*
X1473975Y383417D01*
Y383083D01*
X1473892Y382750D01*
X1473725Y382458D01*
X1473475Y382208D01*
X1473183Y382042D01*
X1472850Y382000D01*
G01X1473183Y382667D02*
X1473683Y382000D01*
G01X1475158Y384083D02*
X1475408Y384333D01*
X1475700Y384458D01*
X1476033Y384500D01*
X1476450Y384417D01*
X1476742Y384208D01*
X1476825Y383958D01*
X1476783Y383708D01*
X1476617Y383500D01*
X1475783Y383083D01*
X1475408Y382792D01*
X1475158Y382375D01*
X1475075Y382000D01*
X1476825D01*
G01X1478133Y382500D02*
X1478383Y382208D01*
X1478717Y382042D01*
X1479092Y382000D01*
X1479425Y382042D01*
X1479758Y382250D01*
X1479967Y382500D01*
X1480008Y382750D01*
X1479925Y383042D01*
X1479633Y383250D01*
X1479342Y383333D01*
X1478967D01*
G01X1479342D02*
X1479592Y383458D01*
X1479800Y383667D01*
X1479883Y383917D01*
X1479800Y384167D01*
X1479592Y384375D01*
X1479217Y384500D01*
X1478842Y384458D01*
X1478467Y384292D01*
G01X1481442Y382292D02*
X1481733Y382083D01*
X1482067Y382000D01*
X1482400Y382083D01*
X1482692Y382333D01*
X1482900Y382708D01*
X1482983Y383083D01*
Y383542D01*
X1482900Y383917D01*
X1482692Y384250D01*
X1482442Y384417D01*
X1482150Y384500D01*
X1481817Y384417D01*
X1481567Y384250D01*
X1481400Y384000D01*
X1481317Y383667D01*
X1481400Y383375D01*
X1481608Y383083D01*
X1481858Y382917D01*
X1482150Y382875D01*
X1482483Y382958D01*
X1482733Y383167D01*
X1482983Y383542D01*
G01X1482894Y385744D02*
Y399744D01*
G01X1469894Y385744D02*
X1482894D01*
G01X1469894Y399744D02*
Y385744D01*
G01X1482894Y399744D02*
X1469894D01*
G01X1453850Y401500D02*
X1453517Y401542D01*
X1453225Y401708D01*
X1452975Y401958D01*
X1452808Y402250D01*
X1452725Y402583D01*
Y402917D01*
X1452808Y403250D01*
X1452975Y403542D01*
X1453225Y403792D01*
X1453517Y403958D01*
X1453850Y404000D01*
X1454183Y403958D01*
X1454475Y403792D01*
X1454725Y403542D01*
X1454892Y403250D01*
X1454975Y402917D01*
Y402583D01*
X1454892Y402250D01*
X1454725Y401958D01*
X1454475Y401708D01*
X1454183Y401542D01*
X1453850Y401500D01*
G01X1454183Y402167D02*
X1454683Y401500D01*
G01X1456158Y403583D02*
X1456408Y403833D01*
X1456700Y403958D01*
X1457033Y404000D01*
X1457450Y403917D01*
X1457742Y403708D01*
X1457825Y403458D01*
X1457783Y403208D01*
X1457617Y403000D01*
X1456783Y402583D01*
X1456408Y402292D01*
X1456158Y401875D01*
X1456075Y401500D01*
X1457825D01*
G01X1459258Y402542D02*
X1459550Y402833D01*
X1459800Y403000D01*
X1460133Y403083D01*
X1460425Y403000D01*
X1460633Y402833D01*
X1460800Y402583D01*
X1460842Y402292D01*
X1460800Y402042D01*
X1460633Y401792D01*
X1460383Y401583D01*
X1460092Y401500D01*
X1459758Y401583D01*
X1459467Y401833D01*
X1459300Y402208D01*
X1459258Y402625D01*
X1459342Y403167D01*
X1459467Y403458D01*
X1459675Y403750D01*
X1459967Y403958D01*
X1460258Y404000D01*
X1460550Y403917D01*
X1460758Y403708D01*
G01X1463150Y401500D02*
Y404000D01*
X1462650Y403500D01*
G01Y401500D02*
X1463650D01*
G01X1454786Y386651D02*
X1468786D01*
G01X1454786Y399651D02*
Y386651D01*
G01X1468786Y399651D02*
X1454786D01*
G01X1468786Y386651D02*
Y399651D01*
G01X1501970Y516428D02*
X1501720Y516553D01*
X1501428Y516636D01*
X1501095D01*
X1500720Y516511D01*
X1500428Y516303D01*
X1500220Y516053D01*
X1500053Y515636D01*
X1500011Y515261D01*
X1500095Y514886D01*
X1500220Y514636D01*
X1500470Y514386D01*
X1500761Y514219D01*
X1501053Y514136D01*
X1501345D01*
X1501636Y514219D01*
X1501886Y514344D01*
X1502095Y514511D01*
G01X1503361Y516219D02*
X1503611Y516469D01*
X1503903Y516594D01*
X1504236Y516636D01*
X1504653Y516553D01*
X1504945Y516344D01*
X1505028Y516094D01*
X1504986Y515844D01*
X1504820Y515636D01*
X1503986Y515219D01*
X1503611Y514928D01*
X1503361Y514511D01*
X1503278Y514136D01*
X1505028D01*
G01X1507253D02*
X1507545Y514178D01*
X1507878Y514303D01*
X1508086Y514511D01*
X1508170Y514803D01*
X1508086Y515094D01*
X1507836Y515344D01*
X1507461Y515469D01*
X1507045D01*
X1506795Y515553D01*
X1506586Y515761D01*
X1506503Y516053D01*
X1506628Y516344D01*
X1506920Y516553D01*
X1507253Y516636D01*
X1507586Y516553D01*
X1507878Y516344D01*
X1508003Y516053D01*
X1507920Y515761D01*
X1507711Y515553D01*
X1507461Y515469D01*
X1507045D01*
X1506670Y515344D01*
X1506420Y515094D01*
X1506336Y514803D01*
X1506420Y514511D01*
X1506628Y514303D01*
X1506961Y514178D01*
X1507253Y514136D01*
G01X1509645Y514428D02*
X1509936Y514219D01*
X1510270Y514136D01*
X1510603Y514219D01*
X1510895Y514469D01*
X1511103Y514844D01*
X1511186Y515219D01*
Y515678D01*
X1511103Y516053D01*
X1510895Y516386D01*
X1510645Y516553D01*
X1510353Y516636D01*
X1510020Y516553D01*
X1509770Y516386D01*
X1509603Y516136D01*
X1509520Y515803D01*
X1509603Y515511D01*
X1509811Y515219D01*
X1510061Y515053D01*
X1510353Y515011D01*
X1510686Y515094D01*
X1510936Y515303D01*
X1511186Y515678D01*
G01X1501767Y520292D02*
X1501517Y520417D01*
X1501225Y520500D01*
X1500892D01*
X1500517Y520375D01*
X1500225Y520167D01*
X1500017Y519917D01*
X1499850Y519500D01*
X1499808Y519125D01*
X1499892Y518750D01*
X1500017Y518500D01*
X1500267Y518250D01*
X1500558Y518083D01*
X1500850Y518000D01*
X1501142D01*
X1501433Y518083D01*
X1501683Y518208D01*
X1501892Y518375D01*
G01X1503158Y520083D02*
X1503408Y520333D01*
X1503700Y520458D01*
X1504033Y520500D01*
X1504450Y520417D01*
X1504742Y520208D01*
X1504825Y519958D01*
X1504783Y519708D01*
X1504617Y519500D01*
X1503783Y519083D01*
X1503408Y518792D01*
X1503158Y518375D01*
X1503075Y518000D01*
X1504825D01*
G01X1507050D02*
X1507342Y518042D01*
X1507675Y518167D01*
X1507883Y518375D01*
X1507967Y518667D01*
X1507883Y518958D01*
X1507633Y519208D01*
X1507258Y519333D01*
X1506842D01*
X1506592Y519417D01*
X1506383Y519625D01*
X1506300Y519917D01*
X1506425Y520208D01*
X1506717Y520417D01*
X1507050Y520500D01*
X1507383Y520417D01*
X1507675Y520208D01*
X1507800Y519917D01*
X1507717Y519625D01*
X1507508Y519417D01*
X1507258Y519333D01*
X1506842D01*
X1506467Y519208D01*
X1506217Y518958D01*
X1506133Y518667D01*
X1506217Y518375D01*
X1506425Y518167D01*
X1506758Y518042D01*
X1507050Y518000D01*
G01X1510150D02*
X1510442Y518042D01*
X1510775Y518167D01*
X1510983Y518375D01*
X1511067Y518667D01*
X1510983Y518958D01*
X1510733Y519208D01*
X1510358Y519333D01*
X1509942D01*
X1509692Y519417D01*
X1509483Y519625D01*
X1509400Y519917D01*
X1509525Y520208D01*
X1509817Y520417D01*
X1510150Y520500D01*
X1510483Y520417D01*
X1510775Y520208D01*
X1510900Y519917D01*
X1510817Y519625D01*
X1510608Y519417D01*
X1510358Y519333D01*
X1509942D01*
X1509567Y519208D01*
X1509317Y518958D01*
X1509233Y518667D01*
X1509317Y518375D01*
X1509525Y518167D01*
X1509858Y518042D01*
X1510150Y518000D01*
G01X1465767Y567292D02*
X1465517Y567417D01*
X1465225Y567500D01*
X1464892D01*
X1464517Y567375D01*
X1464225Y567167D01*
X1464017Y566917D01*
X1463850Y566500D01*
X1463808Y566125D01*
X1463892Y565750D01*
X1464017Y565500D01*
X1464267Y565250D01*
X1464558Y565083D01*
X1464850Y565000D01*
X1465142D01*
X1465433Y565083D01*
X1465683Y565208D01*
X1465892Y565375D01*
G01X1467158Y567083D02*
X1467408Y567333D01*
X1467700Y567458D01*
X1468033Y567500D01*
X1468450Y567417D01*
X1468742Y567208D01*
X1468825Y566958D01*
X1468783Y566708D01*
X1468617Y566500D01*
X1467783Y566083D01*
X1467408Y565792D01*
X1467158Y565375D01*
X1467075Y565000D01*
X1468825D01*
G01X1471050D02*
X1471342Y565042D01*
X1471675Y565167D01*
X1471883Y565375D01*
X1471967Y565667D01*
X1471883Y565958D01*
X1471633Y566208D01*
X1471258Y566333D01*
X1470842D01*
X1470592Y566417D01*
X1470383Y566625D01*
X1470300Y566917D01*
X1470425Y567208D01*
X1470717Y567417D01*
X1471050Y567500D01*
X1471383Y567417D01*
X1471675Y567208D01*
X1471800Y566917D01*
X1471717Y566625D01*
X1471508Y566417D01*
X1471258Y566333D01*
X1470842D01*
X1470467Y566208D01*
X1470217Y565958D01*
X1470133Y565667D01*
X1470217Y565375D01*
X1470425Y565167D01*
X1470758Y565042D01*
X1471050Y565000D01*
G01X1473358Y566042D02*
X1473650Y566333D01*
X1473900Y566500D01*
X1474233Y566583D01*
X1474525Y566500D01*
X1474733Y566333D01*
X1474900Y566083D01*
X1474942Y565792D01*
X1474900Y565542D01*
X1474733Y565292D01*
X1474483Y565083D01*
X1474192Y565000D01*
X1473858Y565083D01*
X1473567Y565333D01*
X1473400Y565708D01*
X1473358Y566125D01*
X1473442Y566667D01*
X1473567Y566958D01*
X1473775Y567250D01*
X1474067Y567458D01*
X1474358Y567500D01*
X1474650Y567417D01*
X1474858Y567208D01*
G01X1454000Y498017D02*
X1451500D01*
Y499058D01*
X1451625Y499392D01*
X1451792Y499600D01*
X1452125Y499683D01*
X1452458Y499600D01*
X1452667Y499350D01*
X1452792Y499058D01*
Y498017D01*
G01Y499058D02*
X1454000Y499683D01*
G01X1453625Y501033D02*
X1453833Y501283D01*
X1453958Y501575D01*
X1454000Y501950D01*
X1453917Y502325D01*
X1453750Y502617D01*
X1453458Y502825D01*
X1453125Y502867D01*
X1452792Y502783D01*
X1452583Y502575D01*
X1452417Y502283D01*
X1452375Y501992D01*
X1452417Y501700D01*
X1452583Y501325D01*
X1451500Y501450D01*
Y502575D01*
G01X1454000Y505050D02*
X1451500D01*
X1452000Y504550D01*
G01X1454000D02*
Y505550D01*
G01Y508067D02*
X1453458Y508150D01*
X1453000Y508275D01*
X1452583Y508442D01*
X1452125Y508650D01*
X1451500Y508983D01*
Y507317D01*
G01X1444000Y502800D02*
X1448000D01*
Y510200D01*
G01X1460839Y510517D02*
X1458339D01*
Y511558D01*
X1458464Y511892D01*
X1458631Y512100D01*
X1458964Y512183D01*
X1459297Y512100D01*
X1459506Y511850D01*
X1459631Y511558D01*
Y510517D01*
G01Y511558D02*
X1460839Y512183D01*
G01X1460464Y513533D02*
X1460672Y513783D01*
X1460797Y514075D01*
X1460839Y514450D01*
X1460756Y514825D01*
X1460589Y515117D01*
X1460297Y515325D01*
X1459964Y515367D01*
X1459631Y515283D01*
X1459422Y515075D01*
X1459256Y514783D01*
X1459214Y514492D01*
X1459256Y514200D01*
X1459422Y513825D01*
X1458339Y513950D01*
Y515075D01*
G01X1458756Y516758D02*
X1458506Y517008D01*
X1458381Y517300D01*
X1458339Y517633D01*
X1458422Y518050D01*
X1458631Y518342D01*
X1458881Y518425D01*
X1459131Y518383D01*
X1459339Y518217D01*
X1459756Y517383D01*
X1460047Y517008D01*
X1460464Y516758D01*
X1460839Y516675D01*
Y518425D01*
G01Y520650D02*
X1458339D01*
X1458839Y520150D01*
G01X1460839D02*
Y521150D01*
G01X1448500Y515300D02*
X1452500D01*
Y522700D01*
G01X1464017Y560661D02*
Y563161D01*
X1465058D01*
X1465392Y563036D01*
X1465600Y562869D01*
X1465683Y562536D01*
X1465600Y562203D01*
X1465350Y561994D01*
X1465058Y561869D01*
X1464017D01*
G01X1465058D02*
X1465683Y560661D01*
G01X1467033Y561036D02*
X1467283Y560828D01*
X1467575Y560703D01*
X1467950Y560661D01*
X1468325Y560744D01*
X1468617Y560911D01*
X1468825Y561203D01*
X1468867Y561536D01*
X1468783Y561869D01*
X1468575Y562078D01*
X1468283Y562244D01*
X1467992Y562286D01*
X1467700Y562244D01*
X1467325Y562078D01*
X1467450Y563161D01*
X1468575D01*
G01X1470258Y562744D02*
X1470508Y562994D01*
X1470800Y563119D01*
X1471133Y563161D01*
X1471550Y563078D01*
X1471842Y562869D01*
X1471925Y562619D01*
X1471883Y562369D01*
X1471717Y562161D01*
X1470883Y561744D01*
X1470508Y561453D01*
X1470258Y561036D01*
X1470175Y560661D01*
X1471925D01*
G01X1473358Y562744D02*
X1473608Y562994D01*
X1473900Y563119D01*
X1474233Y563161D01*
X1474650Y563078D01*
X1474942Y562869D01*
X1475025Y562619D01*
X1474983Y562369D01*
X1474817Y562161D01*
X1473983Y561744D01*
X1473608Y561453D01*
X1473358Y561036D01*
X1473275Y560661D01*
X1475025D01*
G01X1461200Y560500D02*
Y564500D01*
X1453800D01*
G01X1464017Y532000D02*
Y534500D01*
X1465058D01*
X1465392Y534375D01*
X1465600Y534208D01*
X1465683Y533875D01*
X1465600Y533542D01*
X1465350Y533333D01*
X1465058Y533208D01*
X1464017D01*
G01X1465058D02*
X1465683Y532000D01*
G01X1467033Y532375D02*
X1467283Y532167D01*
X1467575Y532042D01*
X1467950Y532000D01*
X1468325Y532083D01*
X1468617Y532250D01*
X1468825Y532542D01*
X1468867Y532875D01*
X1468783Y533208D01*
X1468575Y533417D01*
X1468283Y533583D01*
X1467992Y533625D01*
X1467700Y533583D01*
X1467325Y533417D01*
X1467450Y534500D01*
X1468575D01*
G01X1470258Y534083D02*
X1470508Y534333D01*
X1470800Y534458D01*
X1471133Y534500D01*
X1471550Y534417D01*
X1471842Y534208D01*
X1471925Y533958D01*
X1471883Y533708D01*
X1471717Y533500D01*
X1470883Y533083D01*
X1470508Y532792D01*
X1470258Y532375D01*
X1470175Y532000D01*
X1471925D01*
G01X1473233Y532500D02*
X1473483Y532208D01*
X1473817Y532042D01*
X1474192Y532000D01*
X1474525Y532042D01*
X1474858Y532250D01*
X1475067Y532500D01*
X1475108Y532750D01*
X1475025Y533042D01*
X1474733Y533250D01*
X1474442Y533333D01*
X1474067D01*
G01X1474442D02*
X1474692Y533458D01*
X1474900Y533667D01*
X1474983Y533917D01*
X1474900Y534167D01*
X1474692Y534375D01*
X1474317Y534500D01*
X1473942Y534458D01*
X1473567Y534292D01*
G01X1451300Y535500D02*
Y531500D01*
X1458700D01*
G01X1456339Y510517D02*
X1453839D01*
Y511558D01*
X1453964Y511892D01*
X1454131Y512100D01*
X1454464Y512183D01*
X1454797Y512100D01*
X1455006Y511850D01*
X1455131Y511558D01*
Y510517D01*
G01Y511558D02*
X1456339Y512183D01*
G01X1455964Y513533D02*
X1456172Y513783D01*
X1456297Y514075D01*
X1456339Y514450D01*
X1456256Y514825D01*
X1456089Y515117D01*
X1455797Y515325D01*
X1455464Y515367D01*
X1455131Y515283D01*
X1454922Y515075D01*
X1454756Y514783D01*
X1454714Y514492D01*
X1454756Y514200D01*
X1454922Y513825D01*
X1453839Y513950D01*
Y515075D01*
G01X1454256Y516758D02*
X1454006Y517008D01*
X1453881Y517300D01*
X1453839Y517633D01*
X1453922Y518050D01*
X1454131Y518342D01*
X1454381Y518425D01*
X1454631Y518383D01*
X1454839Y518217D01*
X1455256Y517383D01*
X1455547Y517008D01*
X1455964Y516758D01*
X1456339Y516675D01*
Y518425D01*
G01Y521150D02*
X1453839D01*
X1455631Y519608D01*
Y521692D01*
G01X1444000Y515300D02*
X1448000D01*
Y522700D01*
G01X1444500Y557700D02*
X1442700Y555600D01*
X1440500Y557700D01*
G01X1436900Y557800D02*
Y538600D01*
X1448100D01*
Y557800D01*
X1436900D01*
Y557400D01*
G01X1462483Y526000D02*
Y528500D01*
X1463317D01*
X1463650Y528375D01*
X1463900Y528208D01*
X1464108Y527958D01*
X1464275Y527667D01*
X1464317Y527250D01*
X1464275Y526833D01*
X1464108Y526542D01*
X1463900Y526292D01*
X1463650Y526125D01*
X1463317Y526000D01*
X1462483D01*
G01X1466500D02*
Y528500D01*
X1466000Y528000D01*
G01Y526000D02*
X1467000D01*
G01X1468892Y526292D02*
X1469183Y526083D01*
X1469517Y526000D01*
X1469850Y526083D01*
X1470142Y526333D01*
X1470350Y526708D01*
X1470433Y527083D01*
Y527542D01*
X1470350Y527917D01*
X1470142Y528250D01*
X1469892Y528417D01*
X1469600Y528500D01*
X1469267Y528417D01*
X1469017Y528250D01*
X1468850Y528000D01*
X1468767Y527667D01*
X1468850Y527375D01*
X1469058Y527083D01*
X1469308Y526917D01*
X1469600Y526875D01*
X1469933Y526958D01*
X1470183Y527167D01*
X1470433Y527542D01*
G01X1460500Y523500D02*
X1444400D01*
G01X1460500Y530500D02*
Y523500D01*
G01X1444400Y530500D02*
X1460500D01*
G01X1444400Y523500D02*
Y530500D01*
G01X1438200Y511300D02*
Y522700D01*
G01X1519275Y662000D02*
Y664500D01*
G01X1521025D02*
Y662000D01*
G01Y663250D02*
X1519275D01*
G01X1522333Y662000D02*
Y664500D01*
X1523167D01*
X1523500Y664375D01*
X1523750Y664208D01*
X1523958Y663958D01*
X1524125Y663667D01*
X1524167Y663250D01*
X1524125Y662833D01*
X1523958Y662542D01*
X1523750Y662292D01*
X1523500Y662125D01*
X1523167Y662000D01*
X1522333D01*
G01X1525433D02*
Y664500D01*
X1526267D01*
X1526600Y664375D01*
X1526850Y664208D01*
X1527058Y663958D01*
X1527225Y663667D01*
X1527267Y663250D01*
X1527225Y662833D01*
X1527058Y662542D01*
X1526850Y662292D01*
X1526600Y662125D01*
X1526267Y662000D01*
X1525433D01*
G01X1528575Y662333D02*
X1528908Y662125D01*
X1529283Y662000D01*
X1529617D01*
X1529950Y662125D01*
X1530200Y662333D01*
X1530325Y662625D01*
X1530242Y662917D01*
X1530033Y663167D01*
X1529658Y663333D01*
X1529158Y663417D01*
X1528867Y663583D01*
X1528742Y663875D01*
X1528825Y664167D01*
X1529033Y664375D01*
X1529325Y664500D01*
X1529617D01*
X1529908Y664417D01*
X1530158Y664208D01*
G01X1531508Y662000D02*
X1532550Y664500D01*
X1533592Y662000D01*
G01X1533217Y662875D02*
X1531883D01*
G01X1534775Y662333D02*
X1535108Y662125D01*
X1535483Y662000D01*
X1535817D01*
X1536150Y662125D01*
X1536400Y662333D01*
X1536525Y662625D01*
X1536442Y662917D01*
X1536233Y663167D01*
X1535858Y663333D01*
X1535358Y663417D01*
X1535067Y663583D01*
X1534942Y663875D01*
X1535025Y664167D01*
X1535233Y664375D01*
X1535525Y664500D01*
X1535817D01*
X1536108Y664417D01*
X1536358Y664208D01*
G01X1537958Y664083D02*
X1538208Y664333D01*
X1538500Y664458D01*
X1538833Y664500D01*
X1539250Y664417D01*
X1539542Y664208D01*
X1539625Y663958D01*
X1539583Y663708D01*
X1539417Y663500D01*
X1538583Y663083D01*
X1538208Y662792D01*
X1537958Y662375D01*
X1537875Y662000D01*
X1539625D01*
G01X1541850Y664500D02*
X1541517Y664417D01*
X1541267Y664208D01*
X1541100Y663958D01*
X1540975Y663625D01*
X1540933Y663250D01*
X1540975Y662875D01*
X1541100Y662542D01*
X1541267Y662292D01*
X1541517Y662083D01*
X1541850Y662000D01*
X1542183Y662083D01*
X1542433Y662292D01*
X1542600Y662542D01*
X1542725Y662875D01*
X1542767Y663250D01*
X1542725Y663625D01*
X1542600Y663958D01*
X1542433Y664208D01*
X1542183Y664417D01*
X1541850Y664500D01*
G01X1513747Y584567D02*
X1513622Y584317D01*
X1513539Y584025D01*
Y583692D01*
X1513664Y583317D01*
X1513872Y583025D01*
X1514122Y582817D01*
X1514539Y582650D01*
X1514914Y582608D01*
X1515289Y582692D01*
X1515539Y582817D01*
X1515789Y583067D01*
X1515956Y583358D01*
X1516039Y583650D01*
Y583942D01*
X1515956Y584233D01*
X1515831Y584483D01*
X1515664Y584692D01*
G01X1513956Y585958D02*
X1513706Y586208D01*
X1513581Y586500D01*
X1513539Y586833D01*
X1513622Y587250D01*
X1513831Y587542D01*
X1514081Y587625D01*
X1514331Y587583D01*
X1514539Y587417D01*
X1514956Y586583D01*
X1515247Y586208D01*
X1515664Y585958D01*
X1516039Y585875D01*
Y587625D01*
G01X1515747Y589142D02*
X1515956Y589433D01*
X1516039Y589767D01*
X1515956Y590100D01*
X1515706Y590392D01*
X1515331Y590600D01*
X1514956Y590683D01*
X1514497D01*
X1514122Y590600D01*
X1513789Y590392D01*
X1513622Y590142D01*
X1513539Y589850D01*
X1513622Y589517D01*
X1513789Y589267D01*
X1514039Y589100D01*
X1514372Y589017D01*
X1514664Y589100D01*
X1514956Y589308D01*
X1515122Y589558D01*
X1515164Y589850D01*
X1515081Y590183D01*
X1514872Y590433D01*
X1514497Y590683D01*
G01X1516039Y592867D02*
X1515497Y592950D01*
X1515039Y593075D01*
X1514622Y593242D01*
X1514164Y593450D01*
X1513539Y593783D01*
Y592117D01*
G01X1512039Y582817D02*
X1509539D01*
Y583858D01*
X1509664Y584192D01*
X1509831Y584400D01*
X1510164Y584483D01*
X1510497Y584400D01*
X1510706Y584150D01*
X1510831Y583858D01*
Y582817D01*
G01Y583858D02*
X1512039Y584483D01*
G01X1511664Y585833D02*
X1511872Y586083D01*
X1511997Y586375D01*
X1512039Y586750D01*
X1511956Y587125D01*
X1511789Y587417D01*
X1511497Y587625D01*
X1511164Y587667D01*
X1510831Y587583D01*
X1510622Y587375D01*
X1510456Y587083D01*
X1510414Y586792D01*
X1510456Y586500D01*
X1510622Y586125D01*
X1509539Y586250D01*
Y587375D01*
G01X1511539Y588933D02*
X1511831Y589183D01*
X1511997Y589517D01*
X1512039Y589892D01*
X1511997Y590225D01*
X1511789Y590558D01*
X1511539Y590767D01*
X1511289Y590808D01*
X1510997Y590725D01*
X1510789Y590433D01*
X1510706Y590142D01*
Y589767D01*
G01Y590142D02*
X1510581Y590392D01*
X1510372Y590600D01*
X1510122Y590683D01*
X1509872Y590600D01*
X1509664Y590392D01*
X1509539Y590017D01*
X1509581Y589642D01*
X1509747Y589267D01*
G01X1509539Y592950D02*
X1509622Y592617D01*
X1509831Y592367D01*
X1510081Y592200D01*
X1510414Y592075D01*
X1510789Y592033D01*
X1511164Y592075D01*
X1511497Y592200D01*
X1511747Y592367D01*
X1511956Y592617D01*
X1512039Y592950D01*
X1511956Y593283D01*
X1511747Y593533D01*
X1511497Y593700D01*
X1511164Y593825D01*
X1510789Y593867D01*
X1510414Y593825D01*
X1510081Y593700D01*
X1509831Y593533D01*
X1509622Y593283D01*
X1509539Y592950D01*
G01X1509200Y573600D02*
X1513200D01*
Y581000D01*
G01X1495800Y616500D02*
Y614000D01*
G01X1494842Y616500D02*
X1496758D01*
G01X1498067Y614000D02*
Y616500D01*
X1499067D01*
X1499400Y616375D01*
X1499650Y616083D01*
X1499733Y615750D01*
X1499650Y615417D01*
X1499442Y615167D01*
X1499067Y615042D01*
X1498067D01*
G01X1502000Y614000D02*
Y616500D01*
X1501500Y616000D01*
G01Y614000D02*
X1502500D01*
G01X1504308Y616083D02*
X1504558Y616333D01*
X1504850Y616458D01*
X1505183Y616500D01*
X1505600Y616417D01*
X1505892Y616208D01*
X1505975Y615958D01*
X1505933Y615708D01*
X1505767Y615500D01*
X1504933Y615083D01*
X1504558Y614792D01*
X1504308Y614375D01*
X1504225Y614000D01*
X1505975D01*
G01X1508200D02*
Y616500D01*
X1507700Y616000D01*
G01Y614000D02*
X1508700D01*
G01X1452400Y598500D02*
X1452067Y598542D01*
X1451775Y598708D01*
X1451525Y598958D01*
X1451358Y599250D01*
X1451275Y599583D01*
Y599917D01*
X1451358Y600250D01*
X1451525Y600542D01*
X1451775Y600792D01*
X1452067Y600958D01*
X1452400Y601000D01*
X1452733Y600958D01*
X1453025Y600792D01*
X1453275Y600542D01*
X1453442Y600250D01*
X1453525Y599917D01*
Y599583D01*
X1453442Y599250D01*
X1453275Y598958D01*
X1453025Y598708D01*
X1452733Y598542D01*
X1452400Y598500D01*
G01X1452733Y599167D02*
X1453233Y598500D01*
G01X1454792Y598792D02*
X1455083Y598583D01*
X1455417Y598500D01*
X1455750Y598583D01*
X1456042Y598833D01*
X1456250Y599208D01*
X1456333Y599583D01*
Y600042D01*
X1456250Y600417D01*
X1456042Y600750D01*
X1455792Y600917D01*
X1455500Y601000D01*
X1455167Y600917D01*
X1454917Y600750D01*
X1454750Y600500D01*
X1454667Y600167D01*
X1454750Y599875D01*
X1454958Y599583D01*
X1455208Y599417D01*
X1455500Y599375D01*
X1455833Y599458D01*
X1456083Y599667D01*
X1456333Y600042D01*
G01X1458600Y601000D02*
X1458267Y600917D01*
X1458017Y600708D01*
X1457850Y600458D01*
X1457725Y600125D01*
X1457683Y599750D01*
X1457725Y599375D01*
X1457850Y599042D01*
X1458017Y598792D01*
X1458267Y598583D01*
X1458600Y598500D01*
X1458933Y598583D01*
X1459183Y598792D01*
X1459350Y599042D01*
X1459475Y599375D01*
X1459517Y599750D01*
X1459475Y600125D01*
X1459350Y600458D01*
X1459183Y600708D01*
X1458933Y600917D01*
X1458600Y601000D01*
G01X1439300Y585000D02*
X1441400Y583200D01*
X1439300Y581000D01*
G01X1439200Y577400D02*
X1458400D01*
Y588600D01*
X1439200D01*
Y577400D01*
X1439600D01*
G01X1501300Y582817D02*
X1498800D01*
Y583858D01*
X1498925Y584192D01*
X1499092Y584400D01*
X1499425Y584483D01*
X1499758Y584400D01*
X1499967Y584150D01*
X1500092Y583858D01*
Y582817D01*
G01Y583858D02*
X1501300Y584483D01*
G01X1500925Y585833D02*
X1501133Y586083D01*
X1501258Y586375D01*
X1501300Y586750D01*
X1501217Y587125D01*
X1501050Y587417D01*
X1500758Y587625D01*
X1500425Y587667D01*
X1500092Y587583D01*
X1499883Y587375D01*
X1499717Y587083D01*
X1499675Y586792D01*
X1499717Y586500D01*
X1499883Y586125D01*
X1498800Y586250D01*
Y587375D01*
G01X1500800Y588933D02*
X1501092Y589183D01*
X1501258Y589517D01*
X1501300Y589892D01*
X1501258Y590225D01*
X1501050Y590558D01*
X1500800Y590767D01*
X1500550Y590808D01*
X1500258Y590725D01*
X1500050Y590433D01*
X1499967Y590142D01*
Y589767D01*
G01Y590142D02*
X1499842Y590392D01*
X1499633Y590600D01*
X1499383Y590683D01*
X1499133Y590600D01*
X1498925Y590392D01*
X1498800Y590017D01*
X1498842Y589642D01*
X1499008Y589267D01*
G01X1501300Y593450D02*
X1498800D01*
X1500592Y591908D01*
Y593992D01*
G01X1436500Y594700D02*
Y589200D01*
G01Y606800D02*
Y601300D01*
G01X1436547Y643267D02*
X1436422Y643017D01*
X1436339Y642725D01*
Y642392D01*
X1436464Y642017D01*
X1436672Y641725D01*
X1436922Y641517D01*
X1437339Y641350D01*
X1437714Y641308D01*
X1438089Y641392D01*
X1438339Y641517D01*
X1438589Y641767D01*
X1438756Y642058D01*
X1438839Y642350D01*
Y642642D01*
X1438756Y642933D01*
X1438631Y643183D01*
X1438464Y643392D01*
G01X1436756Y644658D02*
X1436506Y644908D01*
X1436381Y645200D01*
X1436339Y645533D01*
X1436422Y645950D01*
X1436631Y646242D01*
X1436881Y646325D01*
X1437131Y646283D01*
X1437339Y646117D01*
X1437756Y645283D01*
X1438047Y644908D01*
X1438464Y644658D01*
X1438839Y644575D01*
Y646325D01*
G01Y648550D02*
X1438797Y648842D01*
X1438672Y649175D01*
X1438464Y649383D01*
X1438172Y649467D01*
X1437881Y649383D01*
X1437631Y649133D01*
X1437506Y648758D01*
Y648342D01*
X1437422Y648092D01*
X1437214Y647883D01*
X1436922Y647800D01*
X1436631Y647925D01*
X1436422Y648217D01*
X1436339Y648550D01*
X1436422Y648883D01*
X1436631Y649175D01*
X1436922Y649300D01*
X1437214Y649217D01*
X1437422Y649008D01*
X1437506Y648758D01*
Y648342D01*
X1437631Y647967D01*
X1437881Y647717D01*
X1438172Y647633D01*
X1438464Y647717D01*
X1438672Y647925D01*
X1438797Y648258D01*
X1438839Y648550D01*
G01X1438339Y650733D02*
X1438631Y650983D01*
X1438797Y651317D01*
X1438839Y651692D01*
X1438797Y652025D01*
X1438589Y652358D01*
X1438339Y652567D01*
X1438089Y652608D01*
X1437797Y652525D01*
X1437589Y652233D01*
X1437506Y651942D01*
Y651567D01*
G01Y651942D02*
X1437381Y652192D01*
X1437172Y652400D01*
X1436922Y652483D01*
X1436672Y652400D01*
X1436464Y652192D01*
X1436339Y651817D01*
X1436381Y651442D01*
X1436547Y651067D01*
G01X1483517Y720500D02*
Y718000D01*
X1485183D01*
G01X1488283D02*
X1486617D01*
Y720500D01*
X1488283D01*
G01X1487617Y719292D02*
X1486617D01*
G01X1489633Y718000D02*
Y720500D01*
X1490467D01*
X1490800Y720375D01*
X1491050Y720208D01*
X1491258Y719958D01*
X1491425Y719667D01*
X1491467Y719250D01*
X1491425Y718833D01*
X1491258Y718542D01*
X1491050Y718292D01*
X1490800Y718125D01*
X1490467Y718000D01*
X1489633D01*
G01X1492942Y718292D02*
X1493233Y718083D01*
X1493567Y718000D01*
X1493900Y718083D01*
X1494192Y718333D01*
X1494400Y718708D01*
X1494483Y719083D01*
Y719542D01*
X1494400Y719917D01*
X1494192Y720250D01*
X1493942Y720417D01*
X1493650Y720500D01*
X1493317Y720417D01*
X1493067Y720250D01*
X1492900Y720000D01*
X1492817Y719667D01*
X1492900Y719375D01*
X1493108Y719083D01*
X1493358Y718917D01*
X1493650Y718875D01*
X1493983Y718958D01*
X1494233Y719167D01*
X1494483Y719542D01*
G01X1484773Y704636D02*
Y715836D01*
X1493573D01*
Y704636D01*
X1484773D01*
G01X1447517Y834500D02*
Y837000D01*
X1448558D01*
X1448892Y836875D01*
X1449100Y836708D01*
X1449183Y836375D01*
X1449100Y836042D01*
X1448850Y835833D01*
X1448558Y835708D01*
X1447517D01*
G01X1448558D02*
X1449183Y834500D01*
G01X1450658Y836583D02*
X1450908Y836833D01*
X1451200Y836958D01*
X1451533Y837000D01*
X1451950Y836917D01*
X1452242Y836708D01*
X1452325Y836458D01*
X1452283Y836208D01*
X1452117Y836000D01*
X1451283Y835583D01*
X1450908Y835292D01*
X1450658Y834875D01*
X1450575Y834500D01*
X1452325D01*
G01X1454467D02*
X1454550Y835042D01*
X1454675Y835500D01*
X1454842Y835917D01*
X1455050Y836375D01*
X1455383Y837000D01*
X1453717D01*
G01X1457567Y834500D02*
X1457650Y835042D01*
X1457775Y835500D01*
X1457942Y835917D01*
X1458150Y836375D01*
X1458483Y837000D01*
X1456817D01*
G01X1467486Y834182D02*
Y838182D01*
X1460086D01*
G01X1482219Y853959D02*
Y857959D01*
X1474819D01*
G01X1488100Y853117D02*
X1485600D01*
Y854158D01*
X1485725Y854492D01*
X1485892Y854700D01*
X1486225Y854783D01*
X1486558Y854700D01*
X1486767Y854450D01*
X1486892Y854158D01*
Y853117D01*
G01Y854158D02*
X1488100Y854783D01*
G01X1487600Y856133D02*
X1487892Y856383D01*
X1488058Y856717D01*
X1488100Y857092D01*
X1488058Y857425D01*
X1487850Y857758D01*
X1487600Y857967D01*
X1487350Y858008D01*
X1487058Y857925D01*
X1486850Y857633D01*
X1486767Y857342D01*
Y856967D01*
G01Y857342D02*
X1486642Y857592D01*
X1486433Y857800D01*
X1486183Y857883D01*
X1485933Y857800D01*
X1485725Y857592D01*
X1485600Y857217D01*
X1485642Y856842D01*
X1485808Y856467D01*
G01X1487600Y859233D02*
X1487892Y859483D01*
X1488058Y859817D01*
X1488100Y860192D01*
X1488058Y860525D01*
X1487850Y860858D01*
X1487600Y861067D01*
X1487350Y861108D01*
X1487058Y861025D01*
X1486850Y860733D01*
X1486767Y860442D01*
Y860067D01*
G01Y860442D02*
X1486642Y860692D01*
X1486433Y860900D01*
X1486183Y860983D01*
X1485933Y860900D01*
X1485725Y860692D01*
X1485600Y860317D01*
X1485642Y859942D01*
X1485808Y859567D01*
G01X1486017Y862458D02*
X1485767Y862708D01*
X1485642Y863000D01*
X1485600Y863333D01*
X1485683Y863750D01*
X1485892Y864042D01*
X1486142Y864125D01*
X1486392Y864083D01*
X1486600Y863917D01*
X1487017Y863083D01*
X1487308Y862708D01*
X1487725Y862458D01*
X1488100Y862375D01*
Y864125D01*
G01X1492100Y853117D02*
X1489600D01*
Y854158D01*
X1489725Y854492D01*
X1489892Y854700D01*
X1490225Y854783D01*
X1490558Y854700D01*
X1490767Y854450D01*
X1490892Y854158D01*
Y853117D01*
G01Y854158D02*
X1492100Y854783D01*
G01X1491600Y856133D02*
X1491892Y856383D01*
X1492058Y856717D01*
X1492100Y857092D01*
X1492058Y857425D01*
X1491850Y857758D01*
X1491600Y857967D01*
X1491350Y858008D01*
X1491058Y857925D01*
X1490850Y857633D01*
X1490767Y857342D01*
Y856967D01*
G01Y857342D02*
X1490642Y857592D01*
X1490433Y857800D01*
X1490183Y857883D01*
X1489933Y857800D01*
X1489725Y857592D01*
X1489600Y857217D01*
X1489642Y856842D01*
X1489808Y856467D01*
G01X1491600Y859233D02*
X1491892Y859483D01*
X1492058Y859817D01*
X1492100Y860192D01*
X1492058Y860525D01*
X1491850Y860858D01*
X1491600Y861067D01*
X1491350Y861108D01*
X1491058Y861025D01*
X1490850Y860733D01*
X1490767Y860442D01*
Y860067D01*
G01Y860442D02*
X1490642Y860692D01*
X1490433Y860900D01*
X1490183Y860983D01*
X1489933Y860900D01*
X1489725Y860692D01*
X1489600Y860317D01*
X1489642Y859942D01*
X1489808Y859567D01*
G01X1491600Y862333D02*
X1491892Y862583D01*
X1492058Y862917D01*
X1492100Y863292D01*
X1492058Y863625D01*
X1491850Y863958D01*
X1491600Y864167D01*
X1491350Y864208D01*
X1491058Y864125D01*
X1490850Y863833D01*
X1490767Y863542D01*
Y863167D01*
G01Y863542D02*
X1490642Y863792D01*
X1490433Y864000D01*
X1490183Y864083D01*
X1489933Y864000D01*
X1489725Y863792D01*
X1489600Y863417D01*
X1489642Y863042D01*
X1489808Y862667D01*
G01X1473850Y834000D02*
X1473517Y834042D01*
X1473225Y834208D01*
X1472975Y834458D01*
X1472808Y834750D01*
X1472725Y835083D01*
Y835417D01*
X1472808Y835750D01*
X1472975Y836042D01*
X1473225Y836292D01*
X1473517Y836458D01*
X1473850Y836500D01*
X1474183Y836458D01*
X1474475Y836292D01*
X1474725Y836042D01*
X1474892Y835750D01*
X1474975Y835417D01*
Y835083D01*
X1474892Y834750D01*
X1474725Y834458D01*
X1474475Y834208D01*
X1474183Y834042D01*
X1473850Y834000D01*
G01X1474183Y834667D02*
X1474683Y834000D01*
G01X1476158Y836083D02*
X1476408Y836333D01*
X1476700Y836458D01*
X1477033Y836500D01*
X1477450Y836417D01*
X1477742Y836208D01*
X1477825Y835958D01*
X1477783Y835708D01*
X1477617Y835500D01*
X1476783Y835083D01*
X1476408Y834792D01*
X1476158Y834375D01*
X1476075Y834000D01*
X1477825D01*
G01X1479258Y836083D02*
X1479508Y836333D01*
X1479800Y836458D01*
X1480133Y836500D01*
X1480550Y836417D01*
X1480842Y836208D01*
X1480925Y835958D01*
X1480883Y835708D01*
X1480717Y835500D01*
X1479883Y835083D01*
X1479508Y834792D01*
X1479258Y834375D01*
X1479175Y834000D01*
X1480925D01*
G01X1483067D02*
X1483150Y834542D01*
X1483275Y835000D01*
X1483442Y835417D01*
X1483650Y835875D01*
X1483983Y836500D01*
X1482317D01*
G01X1482894Y838500D02*
Y852500D01*
G01X1469894Y838500D02*
X1482894D01*
G01X1469894Y852500D02*
Y838500D01*
G01X1482894Y852500D02*
X1469894D01*
G01X1458150Y855600D02*
X1457817Y855642D01*
X1457525Y855808D01*
X1457275Y856058D01*
X1457108Y856350D01*
X1457025Y856683D01*
Y857017D01*
X1457108Y857350D01*
X1457275Y857642D01*
X1457525Y857892D01*
X1457817Y858058D01*
X1458150Y858100D01*
X1458483Y858058D01*
X1458775Y857892D01*
X1459025Y857642D01*
X1459192Y857350D01*
X1459275Y857017D01*
Y856683D01*
X1459192Y856350D01*
X1459025Y856058D01*
X1458775Y855808D01*
X1458483Y855642D01*
X1458150Y855600D01*
G01X1458483Y856267D02*
X1458983Y855600D01*
G01X1460458Y857683D02*
X1460708Y857933D01*
X1461000Y858058D01*
X1461333Y858100D01*
X1461750Y858017D01*
X1462042Y857808D01*
X1462125Y857558D01*
X1462083Y857308D01*
X1461917Y857100D01*
X1461083Y856683D01*
X1460708Y856392D01*
X1460458Y855975D01*
X1460375Y855600D01*
X1462125D01*
G01X1463433Y855975D02*
X1463683Y855767D01*
X1463975Y855642D01*
X1464350Y855600D01*
X1464725Y855683D01*
X1465017Y855850D01*
X1465225Y856142D01*
X1465267Y856475D01*
X1465183Y856808D01*
X1464975Y857017D01*
X1464683Y857183D01*
X1464392Y857225D01*
X1464100Y857183D01*
X1463725Y857017D01*
X1463850Y858100D01*
X1464975D01*
G01X1467450Y855600D02*
Y858100D01*
X1466950Y857600D01*
G01Y855600D02*
X1467950D01*
G01X1454786Y839407D02*
X1468786D01*
G01X1454786Y852407D02*
Y839407D01*
G01X1468786Y852407D02*
X1454786D01*
G01X1468786Y839407D02*
Y852407D01*
G01X1513218Y1012831D02*
X1518268D01*
Y1111531D01*
X1542918D01*
Y927131D01*
X1518268D01*
Y985831D01*
X1513218D01*
Y1012831D01*
G01X1454000Y952017D02*
X1451500D01*
Y953058D01*
X1451625Y953392D01*
X1451792Y953600D01*
X1452125Y953683D01*
X1452458Y953600D01*
X1452667Y953350D01*
X1452792Y953058D01*
Y952017D01*
G01Y953058D02*
X1454000Y953683D01*
G01X1451917Y955158D02*
X1451667Y955408D01*
X1451542Y955700D01*
X1451500Y956033D01*
X1451583Y956450D01*
X1451792Y956742D01*
X1452042Y956825D01*
X1452292Y956783D01*
X1452500Y956617D01*
X1452917Y955783D01*
X1453208Y955408D01*
X1453625Y955158D01*
X1454000Y955075D01*
Y956825D01*
G01Y958967D02*
X1453458Y959050D01*
X1453000Y959175D01*
X1452583Y959342D01*
X1452125Y959550D01*
X1451500Y959883D01*
Y958217D01*
G01X1454000Y962150D02*
X1453958Y962442D01*
X1453833Y962775D01*
X1453625Y962983D01*
X1453333Y963067D01*
X1453042Y962983D01*
X1452792Y962733D01*
X1452667Y962358D01*
Y961942D01*
X1452583Y961692D01*
X1452375Y961483D01*
X1452083Y961400D01*
X1451792Y961525D01*
X1451583Y961817D01*
X1451500Y962150D01*
X1451583Y962483D01*
X1451792Y962775D01*
X1452083Y962900D01*
X1452375Y962817D01*
X1452583Y962608D01*
X1452667Y962358D01*
Y961942D01*
X1452792Y961567D01*
X1453042Y961317D01*
X1453333Y961233D01*
X1453625Y961317D01*
X1453833Y961525D01*
X1453958Y961858D01*
X1454000Y962150D01*
G01X1472017Y859000D02*
Y861500D01*
X1473058D01*
X1473392Y861375D01*
X1473600Y861208D01*
X1473683Y860875D01*
X1473600Y860542D01*
X1473350Y860333D01*
X1473058Y860208D01*
X1472017D01*
G01X1473058D02*
X1473683Y859000D01*
G01X1475158Y861083D02*
X1475408Y861333D01*
X1475700Y861458D01*
X1476033Y861500D01*
X1476450Y861417D01*
X1476742Y861208D01*
X1476825Y860958D01*
X1476783Y860708D01*
X1476617Y860500D01*
X1475783Y860083D01*
X1475408Y859792D01*
X1475158Y859375D01*
X1475075Y859000D01*
X1476825D01*
G01X1478967D02*
X1479050Y859542D01*
X1479175Y860000D01*
X1479342Y860417D01*
X1479550Y860875D01*
X1479883Y861500D01*
X1478217D01*
G01X1482650Y859000D02*
Y861500D01*
X1481108Y859708D01*
X1483192D01*
G01X1493067Y965192D02*
X1492817Y965317D01*
X1492525Y965400D01*
X1492192D01*
X1491817Y965275D01*
X1491525Y965067D01*
X1491317Y964817D01*
X1491150Y964400D01*
X1491108Y964025D01*
X1491192Y963650D01*
X1491317Y963400D01*
X1491567Y963150D01*
X1491858Y962983D01*
X1492150Y962900D01*
X1492442D01*
X1492733Y962983D01*
X1492983Y963108D01*
X1493192Y963275D01*
G01X1495250Y962900D02*
Y965400D01*
X1494750Y964900D01*
G01Y962900D02*
X1495750D01*
G01X1497433Y963400D02*
X1497683Y963108D01*
X1498017Y962942D01*
X1498392Y962900D01*
X1498725Y962942D01*
X1499058Y963150D01*
X1499267Y963400D01*
X1499308Y963650D01*
X1499225Y963942D01*
X1498933Y964150D01*
X1498642Y964233D01*
X1498267D01*
G01X1498642D02*
X1498892Y964358D01*
X1499100Y964567D01*
X1499183Y964817D01*
X1499100Y965067D01*
X1498892Y965275D01*
X1498517Y965400D01*
X1498142Y965358D01*
X1497767Y965192D01*
G01X1500533Y963400D02*
X1500783Y963108D01*
X1501117Y962942D01*
X1501492Y962900D01*
X1501825Y962942D01*
X1502158Y963150D01*
X1502367Y963400D01*
X1502408Y963650D01*
X1502325Y963942D01*
X1502033Y964150D01*
X1501742Y964233D01*
X1501367D01*
G01X1501742D02*
X1501992Y964358D01*
X1502200Y964567D01*
X1502283Y964817D01*
X1502200Y965067D01*
X1501992Y965275D01*
X1501617Y965400D01*
X1501242Y965358D01*
X1500867Y965192D01*
G01X1493067Y969192D02*
X1492817Y969317D01*
X1492525Y969400D01*
X1492192D01*
X1491817Y969275D01*
X1491525Y969067D01*
X1491317Y968817D01*
X1491150Y968400D01*
X1491108Y968025D01*
X1491192Y967650D01*
X1491317Y967400D01*
X1491567Y967150D01*
X1491858Y966983D01*
X1492150Y966900D01*
X1492442D01*
X1492733Y966983D01*
X1492983Y967108D01*
X1493192Y967275D01*
G01X1495250Y966900D02*
Y969400D01*
X1494750Y968900D01*
G01Y966900D02*
X1495750D01*
G01X1497433Y967400D02*
X1497683Y967108D01*
X1498017Y966942D01*
X1498392Y966900D01*
X1498725Y966942D01*
X1499058Y967150D01*
X1499267Y967400D01*
X1499308Y967650D01*
X1499225Y967942D01*
X1498933Y968150D01*
X1498642Y968233D01*
X1498267D01*
G01X1498642D02*
X1498892Y968358D01*
X1499100Y968567D01*
X1499183Y968817D01*
X1499100Y969067D01*
X1498892Y969275D01*
X1498517Y969400D01*
X1498142Y969358D01*
X1497767Y969192D01*
G01X1500658Y968983D02*
X1500908Y969233D01*
X1501200Y969358D01*
X1501533Y969400D01*
X1501950Y969317D01*
X1502242Y969108D01*
X1502325Y968858D01*
X1502283Y968608D01*
X1502117Y968400D01*
X1501283Y967983D01*
X1500908Y967692D01*
X1500658Y967275D01*
X1500575Y966900D01*
X1502325D01*
G01X1464767Y1019953D02*
X1464517Y1020078D01*
X1464225Y1020161D01*
X1463892D01*
X1463517Y1020036D01*
X1463225Y1019828D01*
X1463017Y1019578D01*
X1462850Y1019161D01*
X1462808Y1018786D01*
X1462892Y1018411D01*
X1463017Y1018161D01*
X1463267Y1017911D01*
X1463558Y1017744D01*
X1463850Y1017661D01*
X1464142D01*
X1464433Y1017744D01*
X1464683Y1017869D01*
X1464892Y1018036D01*
G01X1466950Y1017661D02*
Y1020161D01*
X1466450Y1019661D01*
G01Y1017661D02*
X1467450D01*
G01X1469133Y1018161D02*
X1469383Y1017869D01*
X1469717Y1017703D01*
X1470092Y1017661D01*
X1470425Y1017703D01*
X1470758Y1017911D01*
X1470967Y1018161D01*
X1471008Y1018411D01*
X1470925Y1018703D01*
X1470633Y1018911D01*
X1470342Y1018994D01*
X1469967D01*
G01X1470342D02*
X1470592Y1019119D01*
X1470800Y1019328D01*
X1470883Y1019578D01*
X1470800Y1019828D01*
X1470592Y1020036D01*
X1470217Y1020161D01*
X1469842Y1020119D01*
X1469467Y1019953D01*
G01X1473150Y1020161D02*
X1472817Y1020078D01*
X1472567Y1019869D01*
X1472400Y1019619D01*
X1472275Y1019286D01*
X1472233Y1018911D01*
X1472275Y1018536D01*
X1472400Y1018203D01*
X1472567Y1017953D01*
X1472817Y1017744D01*
X1473150Y1017661D01*
X1473483Y1017744D01*
X1473733Y1017953D01*
X1473900Y1018203D01*
X1474025Y1018536D01*
X1474067Y1018911D01*
X1474025Y1019286D01*
X1473900Y1019619D01*
X1473733Y1019869D01*
X1473483Y1020078D01*
X1473150Y1020161D01*
G01X1514208Y1036767D02*
X1514083Y1036517D01*
X1514000Y1036225D01*
Y1035892D01*
X1514125Y1035517D01*
X1514333Y1035225D01*
X1514583Y1035017D01*
X1515000Y1034850D01*
X1515375Y1034808D01*
X1515750Y1034892D01*
X1516000Y1035017D01*
X1516250Y1035267D01*
X1516417Y1035558D01*
X1516500Y1035850D01*
Y1036142D01*
X1516417Y1036433D01*
X1516292Y1036683D01*
X1516125Y1036892D01*
G01X1516500Y1038950D02*
X1514000D01*
X1514500Y1038450D01*
G01X1516500D02*
Y1039450D01*
G01Y1042550D02*
X1514000D01*
X1515792Y1041008D01*
Y1043092D01*
G01X1516500Y1045150D02*
X1514000D01*
X1514500Y1044650D01*
G01X1516500D02*
Y1045650D01*
G01X1444000Y955300D02*
X1448000D01*
Y962700D01*
G01X1462000Y963517D02*
X1459500D01*
Y964558D01*
X1459625Y964892D01*
X1459792Y965100D01*
X1460125Y965183D01*
X1460458Y965100D01*
X1460667Y964850D01*
X1460792Y964558D01*
Y963517D01*
G01Y964558D02*
X1462000Y965183D01*
G01X1459917Y966658D02*
X1459667Y966908D01*
X1459542Y967200D01*
X1459500Y967533D01*
X1459583Y967950D01*
X1459792Y968242D01*
X1460042Y968325D01*
X1460292Y968283D01*
X1460500Y968117D01*
X1460917Y967283D01*
X1461208Y966908D01*
X1461625Y966658D01*
X1462000Y966575D01*
Y968325D01*
G01Y970550D02*
X1461958Y970842D01*
X1461833Y971175D01*
X1461625Y971383D01*
X1461333Y971467D01*
X1461042Y971383D01*
X1460792Y971133D01*
X1460667Y970758D01*
Y970342D01*
X1460583Y970092D01*
X1460375Y969883D01*
X1460083Y969800D01*
X1459792Y969925D01*
X1459583Y970217D01*
X1459500Y970550D01*
X1459583Y970883D01*
X1459792Y971175D01*
X1460083Y971300D01*
X1460375Y971217D01*
X1460583Y971008D01*
X1460667Y970758D01*
Y970342D01*
X1460792Y969967D01*
X1461042Y969717D01*
X1461333Y969633D01*
X1461625Y969717D01*
X1461833Y969925D01*
X1461958Y970258D01*
X1462000Y970550D01*
G01X1459500Y973650D02*
X1459583Y973317D01*
X1459792Y973067D01*
X1460042Y972900D01*
X1460375Y972775D01*
X1460750Y972733D01*
X1461125Y972775D01*
X1461458Y972900D01*
X1461708Y973067D01*
X1461917Y973317D01*
X1462000Y973650D01*
X1461917Y973983D01*
X1461708Y974233D01*
X1461458Y974400D01*
X1461125Y974525D01*
X1460750Y974567D01*
X1460375Y974525D01*
X1460042Y974400D01*
X1459792Y974233D01*
X1459583Y973983D01*
X1459500Y973650D01*
G01X1448500Y967800D02*
X1452500D01*
Y975200D01*
G01X1463017Y1013661D02*
Y1016161D01*
X1464058D01*
X1464392Y1016036D01*
X1464600Y1015869D01*
X1464683Y1015536D01*
X1464600Y1015203D01*
X1464350Y1014994D01*
X1464058Y1014869D01*
X1463017D01*
G01X1464058D02*
X1464683Y1013661D01*
G01X1466158Y1015744D02*
X1466408Y1015994D01*
X1466700Y1016119D01*
X1467033Y1016161D01*
X1467450Y1016078D01*
X1467742Y1015869D01*
X1467825Y1015619D01*
X1467783Y1015369D01*
X1467617Y1015161D01*
X1466783Y1014744D01*
X1466408Y1014453D01*
X1466158Y1014036D01*
X1466075Y1013661D01*
X1467825D01*
G01X1470050D02*
X1470342Y1013703D01*
X1470675Y1013828D01*
X1470883Y1014036D01*
X1470967Y1014328D01*
X1470883Y1014619D01*
X1470633Y1014869D01*
X1470258Y1014994D01*
X1469842D01*
X1469592Y1015078D01*
X1469383Y1015286D01*
X1469300Y1015578D01*
X1469425Y1015869D01*
X1469717Y1016078D01*
X1470050Y1016161D01*
X1470383Y1016078D01*
X1470675Y1015869D01*
X1470800Y1015578D01*
X1470717Y1015286D01*
X1470508Y1015078D01*
X1470258Y1014994D01*
X1469842D01*
X1469467Y1014869D01*
X1469217Y1014619D01*
X1469133Y1014328D01*
X1469217Y1014036D01*
X1469425Y1013828D01*
X1469758Y1013703D01*
X1470050Y1013661D01*
G01X1473150D02*
Y1016161D01*
X1472650Y1015661D01*
G01Y1013661D02*
X1473650D01*
G01X1461200Y1013000D02*
Y1017000D01*
X1453800D01*
G01X1464517Y985000D02*
Y987500D01*
X1465558D01*
X1465892Y987375D01*
X1466100Y987208D01*
X1466183Y986875D01*
X1466100Y986542D01*
X1465850Y986333D01*
X1465558Y986208D01*
X1464517D01*
G01X1465558D02*
X1466183Y985000D01*
G01X1467658Y987083D02*
X1467908Y987333D01*
X1468200Y987458D01*
X1468533Y987500D01*
X1468950Y987417D01*
X1469242Y987208D01*
X1469325Y986958D01*
X1469283Y986708D01*
X1469117Y986500D01*
X1468283Y986083D01*
X1467908Y985792D01*
X1467658Y985375D01*
X1467575Y985000D01*
X1469325D01*
G01X1471550D02*
X1471842Y985042D01*
X1472175Y985167D01*
X1472383Y985375D01*
X1472467Y985667D01*
X1472383Y985958D01*
X1472133Y986208D01*
X1471758Y986333D01*
X1471342D01*
X1471092Y986417D01*
X1470883Y986625D01*
X1470800Y986917D01*
X1470925Y987208D01*
X1471217Y987417D01*
X1471550Y987500D01*
X1471883Y987417D01*
X1472175Y987208D01*
X1472300Y986917D01*
X1472217Y986625D01*
X1472008Y986417D01*
X1471758Y986333D01*
X1471342D01*
X1470967Y986208D01*
X1470717Y985958D01*
X1470633Y985667D01*
X1470717Y985375D01*
X1470925Y985167D01*
X1471258Y985042D01*
X1471550Y985000D01*
G01X1473858Y987083D02*
X1474108Y987333D01*
X1474400Y987458D01*
X1474733Y987500D01*
X1475150Y987417D01*
X1475442Y987208D01*
X1475525Y986958D01*
X1475483Y986708D01*
X1475317Y986500D01*
X1474483Y986083D01*
X1474108Y985792D01*
X1473858Y985375D01*
X1473775Y985000D01*
X1475525D01*
G01X1451300Y988000D02*
Y984000D01*
X1458700D01*
G01X1458000Y963517D02*
X1455500D01*
Y964558D01*
X1455625Y964892D01*
X1455792Y965100D01*
X1456125Y965183D01*
X1456458Y965100D01*
X1456667Y964850D01*
X1456792Y964558D01*
Y963517D01*
G01Y964558D02*
X1458000Y965183D01*
G01X1455917Y966658D02*
X1455667Y966908D01*
X1455542Y967200D01*
X1455500Y967533D01*
X1455583Y967950D01*
X1455792Y968242D01*
X1456042Y968325D01*
X1456292Y968283D01*
X1456500Y968117D01*
X1456917Y967283D01*
X1457208Y966908D01*
X1457625Y966658D01*
X1458000Y966575D01*
Y968325D01*
G01Y970550D02*
X1457958Y970842D01*
X1457833Y971175D01*
X1457625Y971383D01*
X1457333Y971467D01*
X1457042Y971383D01*
X1456792Y971133D01*
X1456667Y970758D01*
Y970342D01*
X1456583Y970092D01*
X1456375Y969883D01*
X1456083Y969800D01*
X1455792Y969925D01*
X1455583Y970217D01*
X1455500Y970550D01*
X1455583Y970883D01*
X1455792Y971175D01*
X1456083Y971300D01*
X1456375Y971217D01*
X1456583Y971008D01*
X1456667Y970758D01*
Y970342D01*
X1456792Y969967D01*
X1457042Y969717D01*
X1457333Y969633D01*
X1457625Y969717D01*
X1457833Y969925D01*
X1457958Y970258D01*
X1458000Y970550D01*
G01X1457500Y972733D02*
X1457792Y972983D01*
X1457958Y973317D01*
X1458000Y973692D01*
X1457958Y974025D01*
X1457750Y974358D01*
X1457500Y974567D01*
X1457250Y974608D01*
X1456958Y974525D01*
X1456750Y974233D01*
X1456667Y973942D01*
Y973567D01*
G01Y973942D02*
X1456542Y974192D01*
X1456333Y974400D01*
X1456083Y974483D01*
X1455833Y974400D01*
X1455625Y974192D01*
X1455500Y973817D01*
X1455542Y973442D01*
X1455708Y973067D01*
G01X1444000Y967800D02*
X1448000D01*
Y975200D01*
G01X1512500Y1035017D02*
X1510000D01*
Y1036058D01*
X1510125Y1036392D01*
X1510292Y1036600D01*
X1510625Y1036683D01*
X1510958Y1036600D01*
X1511167Y1036350D01*
X1511292Y1036058D01*
Y1035017D01*
G01Y1036058D02*
X1512500Y1036683D01*
G01X1510417Y1038158D02*
X1510167Y1038408D01*
X1510042Y1038700D01*
X1510000Y1039033D01*
X1510083Y1039450D01*
X1510292Y1039742D01*
X1510542Y1039825D01*
X1510792Y1039783D01*
X1511000Y1039617D01*
X1511417Y1038783D01*
X1511708Y1038408D01*
X1512125Y1038158D01*
X1512500Y1038075D01*
Y1039825D01*
G01Y1042050D02*
X1512458Y1042342D01*
X1512333Y1042675D01*
X1512125Y1042883D01*
X1511833Y1042967D01*
X1511542Y1042883D01*
X1511292Y1042633D01*
X1511167Y1042258D01*
Y1041842D01*
X1511083Y1041592D01*
X1510875Y1041383D01*
X1510583Y1041300D01*
X1510292Y1041425D01*
X1510083Y1041717D01*
X1510000Y1042050D01*
X1510083Y1042383D01*
X1510292Y1042675D01*
X1510583Y1042800D01*
X1510875Y1042717D01*
X1511083Y1042508D01*
X1511167Y1042258D01*
Y1041842D01*
X1511292Y1041467D01*
X1511542Y1041217D01*
X1511833Y1041133D01*
X1512125Y1041217D01*
X1512333Y1041425D01*
X1512458Y1041758D01*
X1512500Y1042050D01*
G01Y1045067D02*
X1511958Y1045150D01*
X1511500Y1045275D01*
X1511083Y1045442D01*
X1510625Y1045650D01*
X1510000Y1045983D01*
Y1044317D01*
G01X1509400Y1026400D02*
X1513400D01*
Y1033800D01*
G01X1444500Y1010200D02*
X1442700Y1008100D01*
X1440500Y1010200D01*
G01X1436900Y1010300D02*
Y991100D01*
X1448100D01*
Y1010300D01*
X1436900D01*
Y1009900D01*
G01X1439300Y1037500D02*
X1441400Y1035700D01*
X1439300Y1033500D01*
G01X1439200Y1029900D02*
X1458400D01*
Y1041100D01*
X1439200D01*
Y1029900D01*
X1439600D01*
G01X1502000Y1035017D02*
X1499500D01*
Y1036058D01*
X1499625Y1036392D01*
X1499792Y1036600D01*
X1500125Y1036683D01*
X1500458Y1036600D01*
X1500667Y1036350D01*
X1500792Y1036058D01*
Y1035017D01*
G01Y1036058D02*
X1502000Y1036683D01*
G01X1499917Y1038158D02*
X1499667Y1038408D01*
X1499542Y1038700D01*
X1499500Y1039033D01*
X1499583Y1039450D01*
X1499792Y1039742D01*
X1500042Y1039825D01*
X1500292Y1039783D01*
X1500500Y1039617D01*
X1500917Y1038783D01*
X1501208Y1038408D01*
X1501625Y1038158D01*
X1502000Y1038075D01*
Y1039825D01*
G01Y1042050D02*
X1501958Y1042342D01*
X1501833Y1042675D01*
X1501625Y1042883D01*
X1501333Y1042967D01*
X1501042Y1042883D01*
X1500792Y1042633D01*
X1500667Y1042258D01*
Y1041842D01*
X1500583Y1041592D01*
X1500375Y1041383D01*
X1500083Y1041300D01*
X1499792Y1041425D01*
X1499583Y1041717D01*
X1499500Y1042050D01*
X1499583Y1042383D01*
X1499792Y1042675D01*
X1500083Y1042800D01*
X1500375Y1042717D01*
X1500583Y1042508D01*
X1500667Y1042258D01*
Y1041842D01*
X1500792Y1041467D01*
X1501042Y1041217D01*
X1501333Y1041133D01*
X1501625Y1041217D01*
X1501833Y1041425D01*
X1501958Y1041758D01*
X1502000Y1042050D01*
G01X1501708Y1044442D02*
X1501917Y1044733D01*
X1502000Y1045067D01*
X1501917Y1045400D01*
X1501667Y1045692D01*
X1501292Y1045900D01*
X1500917Y1045983D01*
X1500458D01*
X1500083Y1045900D01*
X1499750Y1045692D01*
X1499583Y1045442D01*
X1499500Y1045150D01*
X1499583Y1044817D01*
X1499750Y1044567D01*
X1500000Y1044400D01*
X1500333Y1044317D01*
X1500625Y1044400D01*
X1500917Y1044608D01*
X1501083Y1044858D01*
X1501125Y1045150D01*
X1501042Y1045483D01*
X1500833Y1045733D01*
X1500458Y1045983D01*
G01X1436500Y1047200D02*
Y1041700D01*
G01X1463033Y978500D02*
Y981000D01*
X1463867D01*
X1464200Y980875D01*
X1464450Y980708D01*
X1464658Y980458D01*
X1464825Y980167D01*
X1464867Y979750D01*
X1464825Y979333D01*
X1464658Y979042D01*
X1464450Y978792D01*
X1464200Y978625D01*
X1463867Y978500D01*
X1463033D01*
G01X1466967D02*
X1467050Y979042D01*
X1467175Y979500D01*
X1467342Y979917D01*
X1467550Y980375D01*
X1467883Y981000D01*
X1466217D01*
G01X1460500Y976000D02*
X1444400D01*
G01X1460500Y983000D02*
Y976000D01*
G01X1444400Y983000D02*
X1460500D01*
G01X1444400Y976000D02*
Y983000D01*
G01X1438200Y963800D02*
Y975200D01*
G01X1519325Y1114000D02*
Y1116500D01*
G01X1521075D02*
Y1114000D01*
G01Y1115250D02*
X1519325D01*
G01X1522383Y1114000D02*
Y1116500D01*
X1523217D01*
X1523550Y1116375D01*
X1523800Y1116208D01*
X1524008Y1115958D01*
X1524175Y1115667D01*
X1524217Y1115250D01*
X1524175Y1114833D01*
X1524008Y1114542D01*
X1523800Y1114292D01*
X1523550Y1114125D01*
X1523217Y1114000D01*
X1522383D01*
G01X1525483D02*
Y1116500D01*
X1526317D01*
X1526650Y1116375D01*
X1526900Y1116208D01*
X1527108Y1115958D01*
X1527275Y1115667D01*
X1527317Y1115250D01*
X1527275Y1114833D01*
X1527108Y1114542D01*
X1526900Y1114292D01*
X1526650Y1114125D01*
X1526317Y1114000D01*
X1525483D01*
G01X1528625Y1114333D02*
X1528958Y1114125D01*
X1529333Y1114000D01*
X1529667D01*
X1530000Y1114125D01*
X1530250Y1114333D01*
X1530375Y1114625D01*
X1530292Y1114917D01*
X1530083Y1115167D01*
X1529708Y1115333D01*
X1529208Y1115417D01*
X1528917Y1115583D01*
X1528792Y1115875D01*
X1528875Y1116167D01*
X1529083Y1116375D01*
X1529375Y1116500D01*
X1529667D01*
X1529958Y1116417D01*
X1530208Y1116208D01*
G01X1531558Y1114000D02*
X1532600Y1116500D01*
X1533642Y1114000D01*
G01X1533267Y1114875D02*
X1531933D01*
G01X1534825Y1114333D02*
X1535158Y1114125D01*
X1535533Y1114000D01*
X1535867D01*
X1536200Y1114125D01*
X1536450Y1114333D01*
X1536575Y1114625D01*
X1536492Y1114917D01*
X1536283Y1115167D01*
X1535908Y1115333D01*
X1535408Y1115417D01*
X1535117Y1115583D01*
X1534992Y1115875D01*
X1535075Y1116167D01*
X1535283Y1116375D01*
X1535575Y1116500D01*
X1535867D01*
X1536158Y1116417D01*
X1536408Y1116208D01*
G01X1538800Y1114000D02*
X1539092Y1114042D01*
X1539425Y1114167D01*
X1539633Y1114375D01*
X1539717Y1114667D01*
X1539633Y1114958D01*
X1539383Y1115208D01*
X1539008Y1115333D01*
X1538592D01*
X1538342Y1115417D01*
X1538133Y1115625D01*
X1538050Y1115917D01*
X1538175Y1116208D01*
X1538467Y1116417D01*
X1538800Y1116500D01*
X1539133Y1116417D01*
X1539425Y1116208D01*
X1539550Y1115917D01*
X1539467Y1115625D01*
X1539258Y1115417D01*
X1539008Y1115333D01*
X1538592D01*
X1538217Y1115208D01*
X1537967Y1114958D01*
X1537883Y1114667D01*
X1537967Y1114375D01*
X1538175Y1114167D01*
X1538508Y1114042D01*
X1538800Y1114000D01*
G01X1500350Y1069500D02*
Y1067000D01*
G01X1499392Y1069500D02*
X1501308D01*
G01X1502617Y1067000D02*
Y1069500D01*
X1503617D01*
X1503950Y1069375D01*
X1504200Y1069083D01*
X1504283Y1068750D01*
X1504200Y1068417D01*
X1503992Y1068167D01*
X1503617Y1068042D01*
X1502617D01*
G01X1505758D02*
X1506050Y1068333D01*
X1506300Y1068500D01*
X1506633Y1068583D01*
X1506925Y1068500D01*
X1507133Y1068333D01*
X1507300Y1068083D01*
X1507342Y1067792D01*
X1507300Y1067542D01*
X1507133Y1067292D01*
X1506883Y1067083D01*
X1506592Y1067000D01*
X1506258Y1067083D01*
X1505967Y1067333D01*
X1505800Y1067708D01*
X1505758Y1068125D01*
X1505842Y1068667D01*
X1505967Y1068958D01*
X1506175Y1069250D01*
X1506467Y1069458D01*
X1506758Y1069500D01*
X1507050Y1069417D01*
X1507258Y1069208D01*
G01X1509650Y1067000D02*
Y1069500D01*
X1509150Y1069000D01*
G01Y1067000D02*
X1510150D01*
G01X1453900Y1051000D02*
X1453567Y1051042D01*
X1453275Y1051208D01*
X1453025Y1051458D01*
X1452858Y1051750D01*
X1452775Y1052083D01*
Y1052417D01*
X1452858Y1052750D01*
X1453025Y1053042D01*
X1453275Y1053292D01*
X1453567Y1053458D01*
X1453900Y1053500D01*
X1454233Y1053458D01*
X1454525Y1053292D01*
X1454775Y1053042D01*
X1454942Y1052750D01*
X1455025Y1052417D01*
Y1052083D01*
X1454942Y1051750D01*
X1454775Y1051458D01*
X1454525Y1051208D01*
X1454233Y1051042D01*
X1453900Y1051000D01*
G01X1454233Y1051667D02*
X1454733Y1051000D01*
G01X1456208Y1053083D02*
X1456458Y1053333D01*
X1456750Y1053458D01*
X1457083Y1053500D01*
X1457500Y1053417D01*
X1457792Y1053208D01*
X1457875Y1052958D01*
X1457833Y1052708D01*
X1457667Y1052500D01*
X1456833Y1052083D01*
X1456458Y1051792D01*
X1456208Y1051375D01*
X1456125Y1051000D01*
X1457875D01*
G01X1460100D02*
X1460392Y1051042D01*
X1460725Y1051167D01*
X1460933Y1051375D01*
X1461017Y1051667D01*
X1460933Y1051958D01*
X1460683Y1052208D01*
X1460308Y1052333D01*
X1459892D01*
X1459642Y1052417D01*
X1459433Y1052625D01*
X1459350Y1052917D01*
X1459475Y1053208D01*
X1459767Y1053417D01*
X1460100Y1053500D01*
X1460433Y1053417D01*
X1460725Y1053208D01*
X1460850Y1052917D01*
X1460767Y1052625D01*
X1460558Y1052417D01*
X1460308Y1052333D01*
X1459892D01*
X1459517Y1052208D01*
X1459267Y1051958D01*
X1459183Y1051667D01*
X1459267Y1051375D01*
X1459475Y1051167D01*
X1459808Y1051042D01*
X1460100Y1051000D01*
G01X1436500Y1059300D02*
Y1053800D01*
G01X1436017Y1071300D02*
Y1073800D01*
X1437058D01*
X1437392Y1073675D01*
X1437600Y1073508D01*
X1437683Y1073175D01*
X1437600Y1072842D01*
X1437350Y1072633D01*
X1437058Y1072508D01*
X1436017D01*
G01X1437058D02*
X1437683Y1071300D01*
G01X1439158Y1073383D02*
X1439408Y1073633D01*
X1439700Y1073758D01*
X1440033Y1073800D01*
X1440450Y1073717D01*
X1440742Y1073508D01*
X1440825Y1073258D01*
X1440783Y1073008D01*
X1440617Y1072800D01*
X1439783Y1072383D01*
X1439408Y1072092D01*
X1439158Y1071675D01*
X1439075Y1071300D01*
X1440825D01*
G01X1442967D02*
X1443050Y1071842D01*
X1443175Y1072300D01*
X1443342Y1072717D01*
X1443550Y1073175D01*
X1443883Y1073800D01*
X1442217D01*
G01X1445358Y1073383D02*
X1445608Y1073633D01*
X1445900Y1073758D01*
X1446233Y1073800D01*
X1446650Y1073717D01*
X1446942Y1073508D01*
X1447025Y1073258D01*
X1446983Y1073008D01*
X1446817Y1072800D01*
X1445983Y1072383D01*
X1445608Y1072092D01*
X1445358Y1071675D01*
X1445275Y1071300D01*
X1447025D01*
G01X1436547Y1095767D02*
X1436422Y1095517D01*
X1436339Y1095225D01*
Y1094892D01*
X1436464Y1094517D01*
X1436672Y1094225D01*
X1436922Y1094017D01*
X1437339Y1093850D01*
X1437714Y1093808D01*
X1438089Y1093892D01*
X1438339Y1094017D01*
X1438589Y1094267D01*
X1438756Y1094558D01*
X1438839Y1094850D01*
Y1095142D01*
X1438756Y1095433D01*
X1438631Y1095683D01*
X1438464Y1095892D01*
G01X1438839Y1097950D02*
X1436339D01*
X1436839Y1097450D01*
G01X1438839D02*
Y1098450D01*
G01X1436756Y1100258D02*
X1436506Y1100508D01*
X1436381Y1100800D01*
X1436339Y1101133D01*
X1436422Y1101550D01*
X1436631Y1101842D01*
X1436881Y1101925D01*
X1437131Y1101883D01*
X1437339Y1101717D01*
X1437756Y1100883D01*
X1438047Y1100508D01*
X1438464Y1100258D01*
X1438839Y1100175D01*
Y1101925D01*
G01Y1104067D02*
X1438297Y1104150D01*
X1437839Y1104275D01*
X1437422Y1104442D01*
X1436964Y1104650D01*
X1436339Y1104983D01*
Y1103317D01*
G01X1484033Y1342233D02*
X1484700Y1342733D01*
X1485200Y1343566D01*
X1485533Y1344733D01*
X1485200Y1345733D01*
X1484533Y1346400D01*
X1483367Y1346900D01*
X1478867D01*
Y1336900D01*
X1484367D01*
X1485533Y1337567D01*
X1486200Y1338567D01*
X1486533Y1339733D01*
X1486200Y1340900D01*
X1485200Y1341900D01*
X1484033Y1342233D01*
X1478867D01*
G01X1495300Y1336900D02*
Y1346900D01*
X1489133Y1339733D01*
X1497467D01*
G01X1503900Y1336900D02*
X1505067Y1337067D01*
X1506400Y1337567D01*
X1507233Y1338400D01*
X1507567Y1339567D01*
X1507233Y1340733D01*
X1506233Y1341733D01*
X1504733Y1342233D01*
X1503067D01*
X1502067Y1342567D01*
X1501233Y1343400D01*
X1500900Y1344567D01*
X1501400Y1345733D01*
X1502566Y1346567D01*
X1503900Y1346900D01*
X1505233Y1346567D01*
X1506400Y1345733D01*
X1506900Y1344567D01*
X1506567Y1343400D01*
X1505733Y1342567D01*
X1504733Y1342233D01*
X1503067D01*
X1501567Y1341733D01*
X1500567Y1340733D01*
X1500233Y1339567D01*
X1500567Y1338400D01*
X1501400Y1337567D01*
X1502733Y1337067D01*
X1503900Y1336900D01*
G01X1514500Y1336567D02*
X1514167Y1336733D01*
Y1337067D01*
X1514500Y1337233D01*
X1514833Y1337067D01*
Y1336733D01*
X1514500Y1336567D01*
G01X1525100Y1346900D02*
X1523766Y1346567D01*
X1522767Y1345733D01*
X1522100Y1344733D01*
X1521600Y1343400D01*
X1521433Y1341900D01*
X1521600Y1340400D01*
X1522100Y1339067D01*
X1522767Y1338066D01*
X1523766Y1337233D01*
X1525100Y1336900D01*
X1526433Y1337233D01*
X1527433Y1338066D01*
X1528100Y1339067D01*
X1528600Y1340400D01*
X1528767Y1341900D01*
X1528600Y1343400D01*
X1528100Y1344733D01*
X1527433Y1345733D01*
X1526433Y1346567D01*
X1525100Y1346900D01*
G01X1535700Y1336900D02*
Y1346900D01*
X1533700Y1344900D01*
G01Y1336900D02*
X1537700D01*
G01X1546300D02*
Y1346900D01*
X1544300Y1344900D01*
G01Y1336900D02*
X1548300D01*
G01X1556900D02*
Y1346900D01*
X1554900Y1344900D01*
G01Y1336900D02*
X1558900D01*
G01X1569500D02*
Y1346900D01*
X1563333Y1339733D01*
X1571667D01*
G01X1578100Y1336567D02*
X1577767Y1336733D01*
Y1337067D01*
X1578100Y1337233D01*
X1578433Y1337067D01*
Y1336733D01*
X1578100Y1336567D01*
G01X1588700Y1346900D02*
X1587366Y1346567D01*
X1586367Y1345733D01*
X1585700Y1344733D01*
X1585200Y1343400D01*
X1585033Y1341900D01*
X1585200Y1340400D01*
X1585700Y1339067D01*
X1586367Y1338066D01*
X1587366Y1337233D01*
X1588700Y1336900D01*
X1590033Y1337233D01*
X1591033Y1338066D01*
X1591700Y1339067D01*
X1592200Y1340400D01*
X1592367Y1341900D01*
X1592200Y1343400D01*
X1591700Y1344733D01*
X1591033Y1345733D01*
X1590033Y1346567D01*
X1588700Y1346900D01*
G01X1599300D02*
X1597966Y1346567D01*
X1596967Y1345733D01*
X1596300Y1344733D01*
X1595800Y1343400D01*
X1595633Y1341900D01*
X1595800Y1340400D01*
X1596300Y1339067D01*
X1596967Y1338066D01*
X1597966Y1337233D01*
X1599300Y1336900D01*
X1600633Y1337233D01*
X1601633Y1338066D01*
X1602300Y1339067D01*
X1602800Y1340400D01*
X1602967Y1341900D01*
X1602800Y1343400D01*
X1602300Y1344733D01*
X1601633Y1345733D01*
X1600633Y1346567D01*
X1599300Y1346900D01*
G01X1609900Y1336900D02*
Y1346900D01*
X1607900Y1344900D01*
G01Y1336900D02*
X1611900D01*
G01X1620500D02*
Y1346900D01*
X1618500Y1344900D01*
G01Y1336900D02*
X1622500D01*
G01X1479267Y1322200D02*
Y1332200D01*
X1483600Y1323867D01*
X1487933Y1332200D01*
Y1322200D01*
G01X1490033D02*
X1494200Y1332200D01*
X1498367Y1322200D01*
G01X1496867Y1325700D02*
X1491533D01*
G01X1501133Y1322200D02*
Y1332200D01*
X1504467D01*
X1505800Y1331700D01*
X1506800Y1331033D01*
X1507633Y1330033D01*
X1508300Y1328866D01*
X1508467Y1327200D01*
X1508300Y1325533D01*
X1507633Y1324367D01*
X1506800Y1323366D01*
X1505800Y1322700D01*
X1504467Y1322200D01*
X1501133D01*
G01X1518733D02*
X1512067D01*
Y1332200D01*
X1518733D01*
G01X1516067Y1327367D02*
X1512067D01*
G01X1534600Y1332200D02*
X1538600D01*
G01X1536600D02*
Y1322200D01*
G01X1534600D02*
X1538600D01*
G01X1543367D02*
Y1332200D01*
X1551033Y1322200D01*
Y1332200D01*
G01X1568400D02*
Y1322200D01*
G01X1564567Y1332200D02*
X1572233D01*
G01X1574833Y1322200D02*
X1579000Y1332200D01*
X1583167Y1322200D01*
G01X1581667Y1325700D02*
X1576333D01*
G01X1587600Y1332200D02*
X1591600D01*
G01X1589600D02*
Y1322200D01*
G01X1587600D02*
X1591600D01*
G01X1595200Y1332200D02*
X1597533Y1322200D01*
X1600200Y1332200D01*
X1602867Y1322200D01*
X1605200Y1332200D01*
G01X1606633Y1322200D02*
X1610800Y1332200D01*
X1614967Y1322200D01*
G01X1613467Y1325700D02*
X1608133D01*
G01X1617567Y1322200D02*
Y1332200D01*
X1625233Y1322200D01*
Y1332200D01*
G01X1483433Y1376333D02*
X1484100Y1376833D01*
X1484600Y1377666D01*
X1484933Y1378833D01*
X1484600Y1379833D01*
X1483933Y1380500D01*
X1482767Y1381000D01*
X1478267D01*
Y1371000D01*
X1483767D01*
X1484933Y1371667D01*
X1485600Y1372667D01*
X1485933Y1373833D01*
X1485600Y1375000D01*
X1484600Y1376000D01*
X1483433Y1376333D01*
X1478267D01*
G01X1490367Y1371000D02*
Y1377666D01*
G01Y1376333D02*
X1491200Y1377000D01*
X1492033Y1377500D01*
X1493200Y1377666D01*
X1494033Y1377500D01*
X1495033Y1377000D01*
G01X1499800Y1368000D02*
X1500800Y1367667D01*
X1502133Y1368000D01*
X1502967Y1368667D01*
X1503633Y1369500D01*
X1504633Y1372166D01*
X1506800Y1377666D01*
G01X1501467D02*
X1504633Y1372166D01*
G01X1516567Y1376833D02*
X1515400Y1377500D01*
X1514400Y1377666D01*
X1513067Y1377333D01*
X1512067Y1376667D01*
X1511400Y1375500D01*
X1511233Y1374333D01*
X1511400Y1373167D01*
X1512067Y1372166D01*
X1513067Y1371333D01*
X1514400Y1371000D01*
X1515567Y1371333D01*
X1516567Y1372000D01*
G01X1522000Y1375500D02*
X1527333D01*
X1526833Y1376667D01*
X1526000Y1377333D01*
X1524833Y1377666D01*
X1523667Y1377500D01*
X1522667Y1377000D01*
X1522000Y1375833D01*
X1521667Y1374833D01*
Y1373833D01*
X1522000Y1372833D01*
X1522833Y1371833D01*
X1523833Y1371167D01*
X1525000Y1371000D01*
X1526167Y1371333D01*
X1527333Y1372333D01*
G01X1549367Y1380167D02*
X1548367Y1380667D01*
X1547200Y1381000D01*
X1545867D01*
X1544366Y1380500D01*
X1543200Y1379667D01*
X1542367Y1378667D01*
X1541700Y1377000D01*
X1541533Y1375500D01*
X1541867Y1374000D01*
X1542367Y1373000D01*
X1543367Y1372000D01*
X1544533Y1371333D01*
X1545700Y1371000D01*
X1546867D01*
X1548033Y1371333D01*
X1549033Y1371833D01*
X1549867Y1372500D01*
G01X1559300Y1371000D02*
Y1377666D01*
G01Y1376500D02*
X1558633Y1377167D01*
X1557633Y1377500D01*
X1556467Y1377666D01*
X1555300Y1377333D01*
X1554300Y1376667D01*
X1553633Y1375667D01*
X1553300Y1374333D01*
X1553633Y1373000D01*
X1554300Y1372000D01*
X1555300Y1371333D01*
X1556467Y1371000D01*
X1557633Y1371167D01*
X1558633Y1371667D01*
X1559300Y1372333D01*
G01X1564067Y1371000D02*
Y1377666D01*
G01Y1376000D02*
X1564733Y1376833D01*
X1565733Y1377500D01*
X1567067Y1377666D01*
X1568233Y1377500D01*
X1569233Y1376833D01*
X1569733Y1375667D01*
Y1371000D01*
G01X1574000Y1368000D02*
X1575000Y1367667D01*
X1576333Y1368000D01*
X1577167Y1368667D01*
X1577833Y1369500D01*
X1578833Y1372166D01*
X1581000Y1377666D01*
G01X1575667D02*
X1578833Y1372166D01*
G01X1588100Y1371000D02*
X1587100Y1371167D01*
X1586100Y1371833D01*
X1585433Y1373000D01*
X1585100Y1374333D01*
X1585433Y1375667D01*
X1586100Y1376833D01*
X1587100Y1377500D01*
X1588100Y1377666D01*
X1589100Y1377500D01*
X1590100Y1376833D01*
X1590767Y1375667D01*
X1590933Y1374333D01*
X1590767Y1373000D01*
X1590100Y1371833D01*
X1589100Y1371167D01*
X1588100Y1371000D01*
G01X1595867D02*
Y1377666D01*
G01Y1376000D02*
X1596533Y1376833D01*
X1597533Y1377500D01*
X1598867Y1377666D01*
X1600033Y1377500D01*
X1601033Y1376833D01*
X1601533Y1375667D01*
Y1371000D01*
G01X1616567D02*
Y1381000D01*
X1620733D01*
X1622067Y1380500D01*
X1622900Y1379833D01*
X1623233Y1378500D01*
X1622900Y1377167D01*
X1621900Y1376333D01*
X1620733Y1375833D01*
X1616567D01*
G01X1620733D02*
X1623233Y1371000D01*
G01X1630500Y1370667D02*
X1630167Y1370833D01*
Y1371167D01*
X1630500Y1371333D01*
X1630833Y1371167D01*
Y1370833D01*
X1630500Y1370667D01*
G01X1637433Y1371000D02*
Y1381000D01*
X1640767D01*
X1642100Y1380500D01*
X1643100Y1379833D01*
X1643933Y1378833D01*
X1644600Y1377666D01*
X1644767Y1376000D01*
X1644600Y1374333D01*
X1643933Y1373167D01*
X1643100Y1372166D01*
X1642100Y1371500D01*
X1640767Y1371000D01*
X1637433D01*
G01X1648367D02*
Y1381000D01*
X1652367D01*
X1653700Y1380500D01*
X1654700Y1379333D01*
X1655033Y1378000D01*
X1654700Y1376667D01*
X1653867Y1375667D01*
X1652367Y1375166D01*
X1648367D01*
G01X1663633Y1376333D02*
X1664300Y1376833D01*
X1664800Y1377666D01*
X1665133Y1378833D01*
X1664800Y1379833D01*
X1664133Y1380500D01*
X1662967Y1381000D01*
X1658467D01*
Y1371000D01*
X1663967D01*
X1665133Y1371667D01*
X1665800Y1372667D01*
X1666133Y1373833D01*
X1665800Y1375000D01*
X1664800Y1376000D01*
X1663633Y1376333D01*
X1658467D01*
G01X1479700Y1353600D02*
Y1363600D01*
X1477700Y1361600D01*
G01Y1353600D02*
X1481700D01*
G01X1487133Y1357766D02*
X1488300Y1358933D01*
X1489300Y1359600D01*
X1490633Y1359933D01*
X1491800Y1359600D01*
X1492633Y1358933D01*
X1493300Y1357933D01*
X1493467Y1356767D01*
X1493300Y1355767D01*
X1492633Y1354766D01*
X1491633Y1353933D01*
X1490467Y1353600D01*
X1489133Y1353933D01*
X1487967Y1354933D01*
X1487300Y1356433D01*
X1487133Y1358100D01*
X1487467Y1360266D01*
X1487967Y1361433D01*
X1488800Y1362600D01*
X1489967Y1363433D01*
X1491133Y1363600D01*
X1492300Y1363267D01*
X1493133Y1362433D01*
G01X1497233Y1355600D02*
X1498233Y1354433D01*
X1499566Y1353767D01*
X1501067Y1353600D01*
X1502400Y1353767D01*
X1503733Y1354600D01*
X1504567Y1355600D01*
X1504733Y1356600D01*
X1504400Y1357766D01*
X1503233Y1358600D01*
X1502067Y1358933D01*
X1500567D01*
G01X1502067D02*
X1503067Y1359433D01*
X1503900Y1360266D01*
X1504233Y1361267D01*
X1503900Y1362267D01*
X1503067Y1363100D01*
X1501567Y1363600D01*
X1500067Y1363433D01*
X1498567Y1362767D01*
G01X1511500Y1353600D02*
Y1363600D01*
X1509500Y1361600D01*
G01Y1353600D02*
X1513500D01*
G01X1521767D02*
X1522100Y1355767D01*
X1522600Y1357600D01*
X1523267Y1359267D01*
X1524100Y1361100D01*
X1525433Y1363600D01*
X1518767D01*
G01X1530533Y1356933D02*
X1534867D01*
G01X1543300Y1353600D02*
Y1363600D01*
X1541300Y1361600D01*
G01Y1353600D02*
X1545300D01*
G01X1626267Y67792D02*
X1626017Y67917D01*
X1625725Y68000D01*
X1625392D01*
X1625017Y67875D01*
X1624725Y67667D01*
X1624517Y67417D01*
X1624350Y67000D01*
X1624308Y66625D01*
X1624392Y66250D01*
X1624517Y66000D01*
X1624767Y65750D01*
X1625058Y65583D01*
X1625350Y65500D01*
X1625642D01*
X1625933Y65583D01*
X1626183Y65708D01*
X1626392Y65875D01*
G01X1628950Y65500D02*
Y68000D01*
X1627408Y66208D01*
X1629492D01*
G01X1630633Y65875D02*
X1630883Y65667D01*
X1631175Y65542D01*
X1631550Y65500D01*
X1631925Y65583D01*
X1632217Y65750D01*
X1632425Y66042D01*
X1632467Y66375D01*
X1632383Y66708D01*
X1632175Y66917D01*
X1631883Y67083D01*
X1631592Y67125D01*
X1631300Y67083D01*
X1630925Y66917D01*
X1631050Y68000D01*
X1632175D01*
G01X1634567Y65500D02*
X1634650Y66042D01*
X1634775Y66500D01*
X1634942Y66917D01*
X1635150Y67375D01*
X1635483Y68000D01*
X1633817D01*
G01X1626183Y63672D02*
X1625933Y63797D01*
X1625641Y63880D01*
X1625308D01*
X1624933Y63755D01*
X1624641Y63547D01*
X1624433Y63297D01*
X1624266Y62880D01*
X1624224Y62505D01*
X1624308Y62130D01*
X1624433Y61880D01*
X1624683Y61630D01*
X1624974Y61463D01*
X1625266Y61380D01*
X1625558D01*
X1625849Y61463D01*
X1626099Y61588D01*
X1626308Y61755D01*
G01X1628866Y61380D02*
Y63880D01*
X1627324Y62088D01*
X1629408D01*
G01X1630549Y61755D02*
X1630799Y61547D01*
X1631091Y61422D01*
X1631466Y61380D01*
X1631841Y61463D01*
X1632133Y61630D01*
X1632341Y61922D01*
X1632383Y62255D01*
X1632299Y62588D01*
X1632091Y62797D01*
X1631799Y62963D01*
X1631508Y63005D01*
X1631216Y62963D01*
X1630841Y62797D01*
X1630966Y63880D01*
X1632091D01*
G01X1634566Y61380D02*
X1634858Y61422D01*
X1635191Y61547D01*
X1635399Y61755D01*
X1635483Y62047D01*
X1635399Y62338D01*
X1635149Y62588D01*
X1634774Y62713D01*
X1634358D01*
X1634108Y62797D01*
X1633899Y63005D01*
X1633816Y63297D01*
X1633941Y63588D01*
X1634233Y63797D01*
X1634566Y63880D01*
X1634899Y63797D01*
X1635191Y63588D01*
X1635316Y63297D01*
X1635233Y63005D01*
X1635024Y62797D01*
X1634774Y62713D01*
X1634358D01*
X1633983Y62588D01*
X1633733Y62338D01*
X1633649Y62047D01*
X1633733Y61755D01*
X1633941Y61547D01*
X1634274Y61422D01*
X1634566Y61380D01*
G01X1544708Y58767D02*
X1544583Y58517D01*
X1544500Y58225D01*
Y57892D01*
X1544625Y57517D01*
X1544833Y57225D01*
X1545083Y57017D01*
X1545500Y56850D01*
X1545875Y56808D01*
X1546250Y56892D01*
X1546500Y57017D01*
X1546750Y57267D01*
X1546917Y57558D01*
X1547000Y57850D01*
Y58142D01*
X1546917Y58433D01*
X1546792Y58683D01*
X1546625Y58892D01*
G01X1547000Y61450D02*
X1544500D01*
X1546292Y59908D01*
Y61992D01*
G01X1546625Y63133D02*
X1546833Y63383D01*
X1546958Y63675D01*
X1547000Y64050D01*
X1546917Y64425D01*
X1546750Y64717D01*
X1546458Y64925D01*
X1546125Y64967D01*
X1545792Y64883D01*
X1545583Y64675D01*
X1545417Y64383D01*
X1545375Y64092D01*
X1545417Y63800D01*
X1545583Y63425D01*
X1544500Y63550D01*
Y64675D01*
G01X1547000Y67650D02*
X1544500D01*
X1546292Y66108D01*
Y68192D01*
G01X1547517Y72500D02*
Y75000D01*
X1548558D01*
X1548892Y74875D01*
X1549100Y74708D01*
X1549183Y74375D01*
X1549100Y74042D01*
X1548850Y73833D01*
X1548558Y73708D01*
X1547517D01*
G01X1548558D02*
X1549183Y72500D01*
G01X1551450D02*
X1551742Y72542D01*
X1552075Y72667D01*
X1552283Y72875D01*
X1552367Y73167D01*
X1552283Y73458D01*
X1552033Y73708D01*
X1551658Y73833D01*
X1551242D01*
X1550992Y73917D01*
X1550783Y74125D01*
X1550700Y74417D01*
X1550825Y74708D01*
X1551117Y74917D01*
X1551450Y75000D01*
X1551783Y74917D01*
X1552075Y74708D01*
X1552200Y74417D01*
X1552117Y74125D01*
X1551908Y73917D01*
X1551658Y73833D01*
X1551242D01*
X1550867Y73708D01*
X1550617Y73458D01*
X1550533Y73167D01*
X1550617Y72875D01*
X1550825Y72667D01*
X1551158Y72542D01*
X1551450Y72500D01*
G01X1554550D02*
Y75000D01*
X1554050Y74500D01*
G01Y72500D02*
X1555050D01*
G01X1556733Y73000D02*
X1556983Y72708D01*
X1557317Y72542D01*
X1557692Y72500D01*
X1558025Y72542D01*
X1558358Y72750D01*
X1558567Y73000D01*
X1558608Y73250D01*
X1558525Y73542D01*
X1558233Y73750D01*
X1557942Y73833D01*
X1557567D01*
G01X1557942D02*
X1558192Y73958D01*
X1558400Y74167D01*
X1558483Y74417D01*
X1558400Y74667D01*
X1558192Y74875D01*
X1557817Y75000D01*
X1557442Y74958D01*
X1557067Y74792D01*
G01X1550000Y71300D02*
Y67300D01*
X1557400D01*
G01X1559339Y17517D02*
X1556839D01*
Y18558D01*
X1556964Y18892D01*
X1557131Y19100D01*
X1557464Y19183D01*
X1557797Y19100D01*
X1558006Y18850D01*
X1558131Y18558D01*
Y17517D01*
G01Y18558D02*
X1559339Y19183D01*
G01Y21450D02*
X1559297Y21742D01*
X1559172Y22075D01*
X1558964Y22283D01*
X1558672Y22367D01*
X1558381Y22283D01*
X1558131Y22033D01*
X1558006Y21658D01*
Y21242D01*
X1557922Y20992D01*
X1557714Y20783D01*
X1557422Y20700D01*
X1557131Y20825D01*
X1556922Y21117D01*
X1556839Y21450D01*
X1556922Y21783D01*
X1557131Y22075D01*
X1557422Y22200D01*
X1557714Y22117D01*
X1557922Y21908D01*
X1558006Y21658D01*
Y21242D01*
X1558131Y20867D01*
X1558381Y20617D01*
X1558672Y20533D01*
X1558964Y20617D01*
X1559172Y20825D01*
X1559297Y21158D01*
X1559339Y21450D01*
G01Y24550D02*
X1556839D01*
X1557339Y24050D01*
G01X1559339D02*
Y25050D01*
G01Y28150D02*
X1556839D01*
X1558631Y26608D01*
Y28692D01*
G01X1555500Y36300D02*
X1559500D01*
Y43700D01*
G01X1573500Y32517D02*
X1571000D01*
Y33558D01*
X1571125Y33892D01*
X1571292Y34100D01*
X1571625Y34183D01*
X1571958Y34100D01*
X1572167Y33850D01*
X1572292Y33558D01*
Y32517D01*
G01Y33558D02*
X1573500Y34183D01*
G01Y36450D02*
X1573458Y36742D01*
X1573333Y37075D01*
X1573125Y37283D01*
X1572833Y37367D01*
X1572542Y37283D01*
X1572292Y37033D01*
X1572167Y36658D01*
Y36242D01*
X1572083Y35992D01*
X1571875Y35783D01*
X1571583Y35700D01*
X1571292Y35825D01*
X1571083Y36117D01*
X1571000Y36450D01*
X1571083Y36783D01*
X1571292Y37075D01*
X1571583Y37200D01*
X1571875Y37117D01*
X1572083Y36908D01*
X1572167Y36658D01*
Y36242D01*
X1572292Y35867D01*
X1572542Y35617D01*
X1572833Y35533D01*
X1573125Y35617D01*
X1573333Y35825D01*
X1573458Y36158D01*
X1573500Y36450D01*
G01Y39550D02*
X1571000D01*
X1571500Y39050D01*
G01X1573500D02*
Y40050D01*
G01X1572458Y41858D02*
X1572167Y42150D01*
X1572000Y42400D01*
X1571917Y42733D01*
X1572000Y43025D01*
X1572167Y43233D01*
X1572417Y43400D01*
X1572708Y43442D01*
X1572958Y43400D01*
X1573208Y43233D01*
X1573417Y42983D01*
X1573500Y42692D01*
X1573417Y42358D01*
X1573167Y42067D01*
X1572792Y41900D01*
X1572375Y41858D01*
X1571833Y41942D01*
X1571542Y42067D01*
X1571250Y42275D01*
X1571042Y42567D01*
X1571000Y42858D01*
X1571083Y43150D01*
X1571292Y43358D01*
G01X1565500Y36300D02*
X1569500D01*
Y43700D01*
G01X1554839Y17517D02*
X1552339D01*
Y18558D01*
X1552464Y18892D01*
X1552631Y19100D01*
X1552964Y19183D01*
X1553297Y19100D01*
X1553506Y18850D01*
X1553631Y18558D01*
Y17517D01*
G01Y18558D02*
X1554839Y19183D01*
G01Y21450D02*
X1554797Y21742D01*
X1554672Y22075D01*
X1554464Y22283D01*
X1554172Y22367D01*
X1553881Y22283D01*
X1553631Y22033D01*
X1553506Y21658D01*
Y21242D01*
X1553422Y20992D01*
X1553214Y20783D01*
X1552922Y20700D01*
X1552631Y20825D01*
X1552422Y21117D01*
X1552339Y21450D01*
X1552422Y21783D01*
X1552631Y22075D01*
X1552922Y22200D01*
X1553214Y22117D01*
X1553422Y21908D01*
X1553506Y21658D01*
Y21242D01*
X1553631Y20867D01*
X1553881Y20617D01*
X1554172Y20533D01*
X1554464Y20617D01*
X1554672Y20825D01*
X1554797Y21158D01*
X1554839Y21450D01*
G01Y24550D02*
X1552339D01*
X1552839Y24050D01*
G01X1554839D02*
Y25050D01*
G01Y27650D02*
X1554797Y27942D01*
X1554672Y28275D01*
X1554464Y28483D01*
X1554172Y28567D01*
X1553881Y28483D01*
X1553631Y28233D01*
X1553506Y27858D01*
Y27442D01*
X1553422Y27192D01*
X1553214Y26983D01*
X1552922Y26900D01*
X1552631Y27025D01*
X1552422Y27317D01*
X1552339Y27650D01*
X1552422Y27983D01*
X1552631Y28275D01*
X1552922Y28400D01*
X1553214Y28317D01*
X1553422Y28108D01*
X1553506Y27858D01*
Y27442D01*
X1553631Y27067D01*
X1553881Y26817D01*
X1554172Y26733D01*
X1554464Y26817D01*
X1554672Y27025D01*
X1554797Y27358D01*
X1554839Y27650D01*
G01X1555000Y43700D02*
X1551000D01*
Y36300D01*
G01X1583800Y45017D02*
X1581300D01*
Y46058D01*
X1581425Y46392D01*
X1581592Y46600D01*
X1581925Y46683D01*
X1582258Y46600D01*
X1582467Y46350D01*
X1582592Y46058D01*
Y45017D01*
G01Y46058D02*
X1583800Y46683D01*
G01Y48950D02*
X1583758Y49242D01*
X1583633Y49575D01*
X1583425Y49783D01*
X1583133Y49867D01*
X1582842Y49783D01*
X1582592Y49533D01*
X1582467Y49158D01*
Y48742D01*
X1582383Y48492D01*
X1582175Y48283D01*
X1581883Y48200D01*
X1581592Y48325D01*
X1581383Y48617D01*
X1581300Y48950D01*
X1581383Y49283D01*
X1581592Y49575D01*
X1581883Y49700D01*
X1582175Y49617D01*
X1582383Y49408D01*
X1582467Y49158D01*
Y48742D01*
X1582592Y48367D01*
X1582842Y48117D01*
X1583133Y48033D01*
X1583425Y48117D01*
X1583633Y48325D01*
X1583758Y48658D01*
X1583800Y48950D01*
G01Y52050D02*
X1581300D01*
X1581800Y51550D01*
G01X1583800D02*
Y52550D01*
G01X1583508Y54442D02*
X1583717Y54733D01*
X1583800Y55067D01*
X1583717Y55400D01*
X1583467Y55692D01*
X1583092Y55900D01*
X1582717Y55983D01*
X1582258D01*
X1581883Y55900D01*
X1581550Y55692D01*
X1581383Y55442D01*
X1581300Y55150D01*
X1581383Y54817D01*
X1581550Y54567D01*
X1581800Y54400D01*
X1582133Y54317D01*
X1582425Y54400D01*
X1582717Y54608D01*
X1582883Y54858D01*
X1582925Y55150D01*
X1582842Y55483D01*
X1582633Y55733D01*
X1582258Y55983D01*
G01X1570000Y48800D02*
X1574000D01*
Y56200D01*
G01X1582500Y58517D02*
X1580000D01*
Y59558D01*
X1580125Y59892D01*
X1580292Y60100D01*
X1580625Y60183D01*
X1580958Y60100D01*
X1581167Y59850D01*
X1581292Y59558D01*
Y58517D01*
G01Y59558D02*
X1582500Y60183D01*
G01Y62450D02*
X1582458Y62742D01*
X1582333Y63075D01*
X1582125Y63283D01*
X1581833Y63367D01*
X1581542Y63283D01*
X1581292Y63033D01*
X1581167Y62658D01*
Y62242D01*
X1581083Y61992D01*
X1580875Y61783D01*
X1580583Y61700D01*
X1580292Y61825D01*
X1580083Y62117D01*
X1580000Y62450D01*
X1580083Y62783D01*
X1580292Y63075D01*
X1580583Y63200D01*
X1580875Y63117D01*
X1581083Y62908D01*
X1581167Y62658D01*
Y62242D01*
X1581292Y61867D01*
X1581542Y61617D01*
X1581833Y61533D01*
X1582125Y61617D01*
X1582333Y61825D01*
X1582458Y62158D01*
X1582500Y62450D01*
G01X1580417Y64758D02*
X1580167Y65008D01*
X1580042Y65300D01*
X1580000Y65633D01*
X1580083Y66050D01*
X1580292Y66342D01*
X1580542Y66425D01*
X1580792Y66383D01*
X1581000Y66217D01*
X1581417Y65383D01*
X1581708Y65008D01*
X1582125Y64758D01*
X1582500Y64675D01*
Y66425D01*
G01X1580417Y67858D02*
X1580167Y68108D01*
X1580042Y68400D01*
X1580000Y68733D01*
X1580083Y69150D01*
X1580292Y69442D01*
X1580542Y69525D01*
X1580792Y69483D01*
X1581000Y69317D01*
X1581417Y68483D01*
X1581708Y68108D01*
X1582125Y67858D01*
X1582500Y67775D01*
Y69525D01*
G01X1561500Y63800D02*
X1565500D01*
Y71200D01*
G01X1579800Y45017D02*
X1577300D01*
Y46058D01*
X1577425Y46392D01*
X1577592Y46600D01*
X1577925Y46683D01*
X1578258Y46600D01*
X1578467Y46350D01*
X1578592Y46058D01*
Y45017D01*
G01Y46058D02*
X1579800Y46683D01*
G01Y48950D02*
X1579758Y49242D01*
X1579633Y49575D01*
X1579425Y49783D01*
X1579133Y49867D01*
X1578842Y49783D01*
X1578592Y49533D01*
X1578467Y49158D01*
Y48742D01*
X1578383Y48492D01*
X1578175Y48283D01*
X1577883Y48200D01*
X1577592Y48325D01*
X1577383Y48617D01*
X1577300Y48950D01*
X1577383Y49283D01*
X1577592Y49575D01*
X1577883Y49700D01*
X1578175Y49617D01*
X1578383Y49408D01*
X1578467Y49158D01*
Y48742D01*
X1578592Y48367D01*
X1578842Y48117D01*
X1579133Y48033D01*
X1579425Y48117D01*
X1579633Y48325D01*
X1579758Y48658D01*
X1579800Y48950D01*
G01X1577717Y51258D02*
X1577467Y51508D01*
X1577342Y51800D01*
X1577300Y52133D01*
X1577383Y52550D01*
X1577592Y52842D01*
X1577842Y52925D01*
X1578092Y52883D01*
X1578300Y52717D01*
X1578717Y51883D01*
X1579008Y51508D01*
X1579425Y51258D01*
X1579800Y51175D01*
Y52925D01*
G01X1579300Y54233D02*
X1579592Y54483D01*
X1579758Y54817D01*
X1579800Y55192D01*
X1579758Y55525D01*
X1579550Y55858D01*
X1579300Y56067D01*
X1579050Y56108D01*
X1578758Y56025D01*
X1578550Y55733D01*
X1578467Y55442D01*
Y55067D01*
G01Y55442D02*
X1578342Y55692D01*
X1578133Y55900D01*
X1577883Y55983D01*
X1577633Y55900D01*
X1577425Y55692D01*
X1577300Y55317D01*
X1577342Y54942D01*
X1577508Y54567D01*
G01X1565500Y48800D02*
X1569500D01*
Y56200D01*
G01X1567200Y90000D02*
X1565100Y91800D01*
X1567200Y94000D01*
G01X1567300Y97600D02*
X1548100D01*
Y86400D01*
X1567300D01*
Y97600D01*
X1566900D01*
G01X1586500Y59983D02*
X1584000D01*
Y60817D01*
X1584125Y61150D01*
X1584292Y61400D01*
X1584542Y61608D01*
X1584833Y61775D01*
X1585250Y61817D01*
X1585667Y61775D01*
X1585958Y61608D01*
X1586208Y61400D01*
X1586375Y61150D01*
X1586500Y60817D01*
Y59983D01*
G01X1586000Y63083D02*
X1586292Y63333D01*
X1586458Y63667D01*
X1586500Y64042D01*
X1586458Y64375D01*
X1586250Y64708D01*
X1586000Y64917D01*
X1585750Y64958D01*
X1585458Y64875D01*
X1585250Y64583D01*
X1585167Y64292D01*
Y63917D01*
G01Y64292D02*
X1585042Y64542D01*
X1584833Y64750D01*
X1584583Y64833D01*
X1584333Y64750D01*
X1584125Y64542D01*
X1584000Y64167D01*
X1584042Y63792D01*
X1584208Y63417D01*
G01X1584417Y66308D02*
X1584167Y66558D01*
X1584042Y66850D01*
X1584000Y67183D01*
X1584083Y67600D01*
X1584292Y67892D01*
X1584542Y67975D01*
X1584792Y67933D01*
X1585000Y67767D01*
X1585417Y66933D01*
X1585708Y66558D01*
X1586125Y66308D01*
X1586500Y66225D01*
Y67975D01*
G01X1573500Y73000D02*
Y56900D01*
G01X1566500Y73000D02*
X1573500D01*
G01X1566500Y56900D02*
Y73000D01*
G01X1573500Y56900D02*
X1566500D01*
G01X1550850Y30500D02*
X1550517Y30542D01*
X1550225Y30708D01*
X1549975Y30958D01*
X1549808Y31250D01*
X1549725Y31583D01*
Y31917D01*
X1549808Y32250D01*
X1549975Y32542D01*
X1550225Y32792D01*
X1550517Y32958D01*
X1550850Y33000D01*
X1551183Y32958D01*
X1551475Y32792D01*
X1551725Y32542D01*
X1551892Y32250D01*
X1551975Y31917D01*
Y31583D01*
X1551892Y31250D01*
X1551725Y30958D01*
X1551475Y30708D01*
X1551183Y30542D01*
X1550850Y30500D01*
G01X1551183Y31167D02*
X1551683Y30500D01*
G01X1553950D02*
Y33000D01*
X1553450Y32500D01*
G01Y30500D02*
X1554450D01*
G01X1556258Y31542D02*
X1556550Y31833D01*
X1556800Y32000D01*
X1557133Y32083D01*
X1557425Y32000D01*
X1557633Y31833D01*
X1557800Y31583D01*
X1557842Y31292D01*
X1557800Y31042D01*
X1557633Y30792D01*
X1557383Y30583D01*
X1557092Y30500D01*
X1556758Y30583D01*
X1556467Y30833D01*
X1556300Y31208D01*
X1556258Y31625D01*
X1556342Y32167D01*
X1556467Y32458D01*
X1556675Y32750D01*
X1556967Y32958D01*
X1557258Y33000D01*
X1557550Y32917D01*
X1557758Y32708D01*
G01X1560067Y30500D02*
X1560150Y31042D01*
X1560275Y31500D01*
X1560442Y31917D01*
X1560650Y32375D01*
X1560983Y33000D01*
X1559317D01*
G01X1546300Y56200D02*
Y44800D01*
G01X1559700Y56200D02*
X1546300D01*
G01X1559700Y44800D02*
Y56200D01*
G01X1546300Y44800D02*
X1559700D01*
G01X1601267Y138292D02*
X1601017Y138417D01*
X1600725Y138500D01*
X1600392D01*
X1600017Y138375D01*
X1599725Y138167D01*
X1599517Y137917D01*
X1599350Y137500D01*
X1599308Y137125D01*
X1599392Y136750D01*
X1599517Y136500D01*
X1599767Y136250D01*
X1600058Y136083D01*
X1600350Y136000D01*
X1600642D01*
X1600933Y136083D01*
X1601183Y136208D01*
X1601392Y136375D01*
G01X1603950Y136000D02*
Y138500D01*
X1602408Y136708D01*
X1604492D01*
G01X1605633Y136375D02*
X1605883Y136167D01*
X1606175Y136042D01*
X1606550Y136000D01*
X1606925Y136083D01*
X1607217Y136250D01*
X1607425Y136542D01*
X1607467Y136875D01*
X1607383Y137208D01*
X1607175Y137417D01*
X1606883Y137583D01*
X1606592Y137625D01*
X1606300Y137583D01*
X1605925Y137417D01*
X1606050Y138500D01*
X1607175D01*
G01X1608733Y136375D02*
X1608983Y136167D01*
X1609275Y136042D01*
X1609650Y136000D01*
X1610025Y136083D01*
X1610317Y136250D01*
X1610525Y136542D01*
X1610567Y136875D01*
X1610483Y137208D01*
X1610275Y137417D01*
X1609983Y137583D01*
X1609692Y137625D01*
X1609400Y137583D01*
X1609025Y137417D01*
X1609150Y138500D01*
X1610275D01*
G01X1600017Y123000D02*
Y125500D01*
X1601058D01*
X1601392Y125375D01*
X1601600Y125208D01*
X1601683Y124875D01*
X1601600Y124542D01*
X1601350Y124333D01*
X1601058Y124208D01*
X1600017D01*
G01X1601058D02*
X1601683Y123000D01*
G01X1603950D02*
X1604242Y123042D01*
X1604575Y123167D01*
X1604783Y123375D01*
X1604867Y123667D01*
X1604783Y123958D01*
X1604533Y124208D01*
X1604158Y124333D01*
X1603742D01*
X1603492Y124417D01*
X1603283Y124625D01*
X1603200Y124917D01*
X1603325Y125208D01*
X1603617Y125417D01*
X1603950Y125500D01*
X1604283Y125417D01*
X1604575Y125208D01*
X1604700Y124917D01*
X1604617Y124625D01*
X1604408Y124417D01*
X1604158Y124333D01*
X1603742D01*
X1603367Y124208D01*
X1603117Y123958D01*
X1603033Y123667D01*
X1603117Y123375D01*
X1603325Y123167D01*
X1603658Y123042D01*
X1603950Y123000D01*
G01X1606258Y125083D02*
X1606508Y125333D01*
X1606800Y125458D01*
X1607133Y125500D01*
X1607550Y125417D01*
X1607842Y125208D01*
X1607925Y124958D01*
X1607883Y124708D01*
X1607717Y124500D01*
X1606883Y124083D01*
X1606508Y123792D01*
X1606258Y123375D01*
X1606175Y123000D01*
X1607925D01*
G01X1610150Y125500D02*
X1609817Y125417D01*
X1609567Y125208D01*
X1609400Y124958D01*
X1609275Y124625D01*
X1609233Y124250D01*
X1609275Y123875D01*
X1609400Y123542D01*
X1609567Y123292D01*
X1609817Y123083D01*
X1610150Y123000D01*
X1610483Y123083D01*
X1610733Y123292D01*
X1610900Y123542D01*
X1611025Y123875D01*
X1611067Y124250D01*
X1611025Y124625D01*
X1610900Y124958D01*
X1610733Y125208D01*
X1610483Y125417D01*
X1610150Y125500D01*
G01X1606600Y127000D02*
Y131000D01*
X1599200D01*
G01X1545208Y159767D02*
X1545083Y159517D01*
X1545000Y159225D01*
Y158892D01*
X1545125Y158517D01*
X1545333Y158225D01*
X1545583Y158017D01*
X1546000Y157850D01*
X1546375Y157808D01*
X1546750Y157892D01*
X1547000Y158017D01*
X1547250Y158267D01*
X1547417Y158558D01*
X1547500Y158850D01*
Y159142D01*
X1547417Y159433D01*
X1547292Y159683D01*
X1547125Y159892D01*
G01X1547500Y162450D02*
X1545000D01*
X1546792Y160908D01*
Y162992D01*
G01X1547500Y165550D02*
X1545000D01*
X1546792Y164008D01*
Y166092D01*
G01X1546458Y167358D02*
X1546167Y167650D01*
X1546000Y167900D01*
X1545917Y168233D01*
X1546000Y168525D01*
X1546167Y168733D01*
X1546417Y168900D01*
X1546708Y168942D01*
X1546958Y168900D01*
X1547208Y168733D01*
X1547417Y168483D01*
X1547500Y168192D01*
X1547417Y167858D01*
X1547167Y167567D01*
X1546792Y167400D01*
X1546375Y167358D01*
X1545833Y167442D01*
X1545542Y167567D01*
X1545250Y167775D01*
X1545042Y168067D01*
X1545000Y168358D01*
X1545083Y168650D01*
X1545292Y168858D01*
G01X1623300Y163000D02*
Y160500D01*
G01X1622342Y163000D02*
X1624258D01*
G01X1625567Y160500D02*
Y163000D01*
X1626567D01*
X1626900Y162875D01*
X1627150Y162583D01*
X1627233Y162250D01*
X1627150Y161917D01*
X1626942Y161667D01*
X1626567Y161542D01*
X1625567D01*
G01X1629500Y160500D02*
Y163000D01*
X1629000Y162500D01*
G01Y160500D02*
X1630000D01*
G01X1632600D02*
X1632892Y160542D01*
X1633225Y160667D01*
X1633433Y160875D01*
X1633517Y161167D01*
X1633433Y161458D01*
X1633183Y161708D01*
X1632808Y161833D01*
X1632392D01*
X1632142Y161917D01*
X1631933Y162125D01*
X1631850Y162417D01*
X1631975Y162708D01*
X1632267Y162917D01*
X1632600Y163000D01*
X1632933Y162917D01*
X1633225Y162708D01*
X1633350Y162417D01*
X1633267Y162125D01*
X1633058Y161917D01*
X1632808Y161833D01*
X1632392D01*
X1632017Y161708D01*
X1631767Y161458D01*
X1631683Y161167D01*
X1631767Y160875D01*
X1631975Y160667D01*
X1632308Y160542D01*
X1632600Y160500D01*
G01X1634908Y161542D02*
X1635200Y161833D01*
X1635450Y162000D01*
X1635783Y162083D01*
X1636075Y162000D01*
X1636283Y161833D01*
X1636450Y161583D01*
X1636492Y161292D01*
X1636450Y161042D01*
X1636283Y160792D01*
X1636033Y160583D01*
X1635742Y160500D01*
X1635408Y160583D01*
X1635117Y160833D01*
X1634950Y161208D01*
X1634908Y161625D01*
X1634992Y162167D01*
X1635117Y162458D01*
X1635325Y162750D01*
X1635617Y162958D01*
X1635908Y163000D01*
X1636200Y162917D01*
X1636408Y162708D01*
G01X1551350Y107500D02*
X1551017Y107542D01*
X1550725Y107708D01*
X1550475Y107958D01*
X1550308Y108250D01*
X1550225Y108583D01*
Y108917D01*
X1550308Y109250D01*
X1550475Y109542D01*
X1550725Y109792D01*
X1551017Y109958D01*
X1551350Y110000D01*
X1551683Y109958D01*
X1551975Y109792D01*
X1552225Y109542D01*
X1552392Y109250D01*
X1552475Y108917D01*
Y108583D01*
X1552392Y108250D01*
X1552225Y107958D01*
X1551975Y107708D01*
X1551683Y107542D01*
X1551350Y107500D01*
G01X1551683Y108167D02*
X1552183Y107500D01*
G01X1554450D02*
Y110000D01*
X1553950Y109500D01*
G01Y107500D02*
X1554950D01*
G01X1556758Y108542D02*
X1557050Y108833D01*
X1557300Y109000D01*
X1557633Y109083D01*
X1557925Y109000D01*
X1558133Y108833D01*
X1558300Y108583D01*
X1558342Y108292D01*
X1558300Y108042D01*
X1558133Y107792D01*
X1557883Y107583D01*
X1557592Y107500D01*
X1557258Y107583D01*
X1556967Y107833D01*
X1556800Y108208D01*
X1556758Y108625D01*
X1556842Y109167D01*
X1556967Y109458D01*
X1557175Y109750D01*
X1557467Y109958D01*
X1557758Y110000D01*
X1558050Y109917D01*
X1558258Y109708D01*
G01X1559733Y107875D02*
X1559983Y107667D01*
X1560275Y107542D01*
X1560650Y107500D01*
X1561025Y107583D01*
X1561317Y107750D01*
X1561525Y108042D01*
X1561567Y108375D01*
X1561483Y108708D01*
X1561275Y108917D01*
X1560983Y109083D01*
X1560692Y109125D01*
X1560400Y109083D01*
X1560025Y108917D01*
X1560150Y110000D01*
X1561275D01*
G01X1584350Y146500D02*
X1584017Y146542D01*
X1583725Y146708D01*
X1583475Y146958D01*
X1583308Y147250D01*
X1583225Y147583D01*
Y147917D01*
X1583308Y148250D01*
X1583475Y148542D01*
X1583725Y148792D01*
X1584017Y148958D01*
X1584350Y149000D01*
X1584683Y148958D01*
X1584975Y148792D01*
X1585225Y148542D01*
X1585392Y148250D01*
X1585475Y147917D01*
Y147583D01*
X1585392Y147250D01*
X1585225Y146958D01*
X1584975Y146708D01*
X1584683Y146542D01*
X1584350Y146500D01*
G01X1584683Y147167D02*
X1585183Y146500D01*
G01X1587450D02*
Y149000D01*
X1586950Y148500D01*
G01Y146500D02*
X1587950D01*
G01X1589758Y147542D02*
X1590050Y147833D01*
X1590300Y148000D01*
X1590633Y148083D01*
X1590925Y148000D01*
X1591133Y147833D01*
X1591300Y147583D01*
X1591342Y147292D01*
X1591300Y147042D01*
X1591133Y146792D01*
X1590883Y146583D01*
X1590592Y146500D01*
X1590258Y146583D01*
X1589967Y146833D01*
X1589800Y147208D01*
X1589758Y147625D01*
X1589842Y148167D01*
X1589967Y148458D01*
X1590175Y148750D01*
X1590467Y148958D01*
X1590758Y149000D01*
X1591050Y148917D01*
X1591258Y148708D01*
G01X1593650Y146500D02*
X1593942Y146542D01*
X1594275Y146667D01*
X1594483Y146875D01*
X1594567Y147167D01*
X1594483Y147458D01*
X1594233Y147708D01*
X1593858Y147833D01*
X1593442D01*
X1593192Y147917D01*
X1592983Y148125D01*
X1592900Y148417D01*
X1593025Y148708D01*
X1593317Y148917D01*
X1593650Y149000D01*
X1593983Y148917D01*
X1594275Y148708D01*
X1594400Y148417D01*
X1594317Y148125D01*
X1594108Y147917D01*
X1593858Y147833D01*
X1593442D01*
X1593067Y147708D01*
X1592817Y147458D01*
X1592733Y147167D01*
X1592817Y146875D01*
X1593025Y146667D01*
X1593358Y146542D01*
X1593650Y146500D01*
G01X1578400Y122800D02*
X1580200Y124900D01*
X1582400Y122800D01*
G01X1586000Y122700D02*
Y141900D01*
X1574800D01*
Y122700D01*
X1586000D01*
Y123100D01*
G01X1626000Y138517D02*
X1623500D01*
Y139558D01*
X1623625Y139892D01*
X1623792Y140100D01*
X1624125Y140183D01*
X1624458Y140100D01*
X1624667Y139850D01*
X1624792Y139558D01*
Y138517D01*
G01Y139558D02*
X1626000Y140183D01*
G01Y142450D02*
X1625958Y142742D01*
X1625833Y143075D01*
X1625625Y143283D01*
X1625333Y143367D01*
X1625042Y143283D01*
X1624792Y143033D01*
X1624667Y142658D01*
Y142242D01*
X1624583Y141992D01*
X1624375Y141783D01*
X1624083Y141700D01*
X1623792Y141825D01*
X1623583Y142117D01*
X1623500Y142450D01*
X1623583Y142783D01*
X1623792Y143075D01*
X1624083Y143200D01*
X1624375Y143117D01*
X1624583Y142908D01*
X1624667Y142658D01*
Y142242D01*
X1624792Y141867D01*
X1625042Y141617D01*
X1625333Y141533D01*
X1625625Y141617D01*
X1625833Y141825D01*
X1625958Y142158D01*
X1626000Y142450D01*
G01X1625500Y144633D02*
X1625792Y144883D01*
X1625958Y145217D01*
X1626000Y145592D01*
X1625958Y145925D01*
X1625750Y146258D01*
X1625500Y146467D01*
X1625250Y146508D01*
X1624958Y146425D01*
X1624750Y146133D01*
X1624667Y145842D01*
Y145467D01*
G01Y145842D02*
X1624542Y146092D01*
X1624333Y146300D01*
X1624083Y146383D01*
X1623833Y146300D01*
X1623625Y146092D01*
X1623500Y145717D01*
X1623542Y145342D01*
X1623708Y144967D01*
G01X1625500Y147733D02*
X1625792Y147983D01*
X1625958Y148317D01*
X1626000Y148692D01*
X1625958Y149025D01*
X1625750Y149358D01*
X1625500Y149567D01*
X1625250Y149608D01*
X1624958Y149525D01*
X1624750Y149233D01*
X1624667Y148942D01*
Y148567D01*
G01Y148942D02*
X1624542Y149192D01*
X1624333Y149400D01*
X1624083Y149483D01*
X1623833Y149400D01*
X1623625Y149192D01*
X1623500Y148817D01*
X1623542Y148442D01*
X1623708Y148067D01*
G01X1549208Y159767D02*
X1549083Y159517D01*
X1549000Y159225D01*
Y158892D01*
X1549125Y158517D01*
X1549333Y158225D01*
X1549583Y158017D01*
X1550000Y157850D01*
X1550375Y157808D01*
X1550750Y157892D01*
X1551000Y158017D01*
X1551250Y158267D01*
X1551417Y158558D01*
X1551500Y158850D01*
Y159142D01*
X1551417Y159433D01*
X1551292Y159683D01*
X1551125Y159892D01*
G01X1551500Y162450D02*
X1549000D01*
X1550792Y160908D01*
Y162992D01*
G01X1551500Y165550D02*
X1549000D01*
X1550792Y164008D01*
Y166092D01*
G01X1551500Y168067D02*
X1550958Y168150D01*
X1550500Y168275D01*
X1550083Y168442D01*
X1549625Y168650D01*
X1549000Y168983D01*
Y167317D01*
G01X1553000Y136200D02*
Y141700D01*
G01X1561000Y136200D02*
X1553000D01*
G01X1561000Y141700D02*
Y136200D01*
G01Y153800D02*
Y148300D01*
G01X1553000Y153800D02*
X1561000D01*
G01X1553000Y148300D02*
Y153800D01*
G01X1548517Y118000D02*
Y120500D01*
X1549558D01*
X1549892Y120375D01*
X1550100Y120208D01*
X1550183Y119875D01*
X1550100Y119542D01*
X1549850Y119333D01*
X1549558Y119208D01*
X1548517D01*
G01X1549558D02*
X1550183Y118000D01*
G01X1552450D02*
X1552742Y118042D01*
X1553075Y118167D01*
X1553283Y118375D01*
X1553367Y118667D01*
X1553283Y118958D01*
X1553033Y119208D01*
X1552658Y119333D01*
X1552242D01*
X1551992Y119417D01*
X1551783Y119625D01*
X1551700Y119917D01*
X1551825Y120208D01*
X1552117Y120417D01*
X1552450Y120500D01*
X1552783Y120417D01*
X1553075Y120208D01*
X1553200Y119917D01*
X1553117Y119625D01*
X1552908Y119417D01*
X1552658Y119333D01*
X1552242D01*
X1551867Y119208D01*
X1551617Y118958D01*
X1551533Y118667D01*
X1551617Y118375D01*
X1551825Y118167D01*
X1552158Y118042D01*
X1552450Y118000D01*
G01X1555550Y120500D02*
X1555217Y120417D01*
X1554967Y120208D01*
X1554800Y119958D01*
X1554675Y119625D01*
X1554633Y119250D01*
X1554675Y118875D01*
X1554800Y118542D01*
X1554967Y118292D01*
X1555217Y118083D01*
X1555550Y118000D01*
X1555883Y118083D01*
X1556133Y118292D01*
X1556300Y118542D01*
X1556425Y118875D01*
X1556467Y119250D01*
X1556425Y119625D01*
X1556300Y119958D01*
X1556133Y120208D01*
X1555883Y120417D01*
X1555550Y120500D01*
G01X1557733Y118375D02*
X1557983Y118167D01*
X1558275Y118042D01*
X1558650Y118000D01*
X1559025Y118083D01*
X1559317Y118250D01*
X1559525Y118542D01*
X1559567Y118875D01*
X1559483Y119208D01*
X1559275Y119417D01*
X1558983Y119583D01*
X1558692Y119625D01*
X1558400Y119583D01*
X1558025Y119417D01*
X1558150Y120500D01*
X1559275D01*
G01X1562300Y130000D02*
Y122000D01*
X1544700D01*
Y130000D01*
X1562300D01*
G01X1559917Y165800D02*
Y168300D01*
X1560958D01*
X1561292Y168175D01*
X1561500Y168008D01*
X1561583Y167675D01*
X1561500Y167342D01*
X1561250Y167133D01*
X1560958Y167008D01*
X1559917D01*
G01X1560958D02*
X1561583Y165800D01*
G01X1563850D02*
X1564142Y165842D01*
X1564475Y165967D01*
X1564683Y166175D01*
X1564767Y166467D01*
X1564683Y166758D01*
X1564433Y167008D01*
X1564058Y167133D01*
X1563642D01*
X1563392Y167217D01*
X1563183Y167425D01*
X1563100Y167717D01*
X1563225Y168008D01*
X1563517Y168217D01*
X1563850Y168300D01*
X1564183Y168217D01*
X1564475Y168008D01*
X1564600Y167717D01*
X1564517Y167425D01*
X1564308Y167217D01*
X1564058Y167133D01*
X1563642D01*
X1563267Y167008D01*
X1563017Y166758D01*
X1562933Y166467D01*
X1563017Y166175D01*
X1563225Y165967D01*
X1563558Y165842D01*
X1563850Y165800D01*
G01X1566950Y168300D02*
X1566617Y168217D01*
X1566367Y168008D01*
X1566200Y167758D01*
X1566075Y167425D01*
X1566033Y167050D01*
X1566075Y166675D01*
X1566200Y166342D01*
X1566367Y166092D01*
X1566617Y165883D01*
X1566950Y165800D01*
X1567283Y165883D01*
X1567533Y166092D01*
X1567700Y166342D01*
X1567825Y166675D01*
X1567867Y167050D01*
X1567825Y167425D01*
X1567700Y167758D01*
X1567533Y168008D01*
X1567283Y168217D01*
X1566950Y168300D01*
G01X1569967Y165800D02*
X1570050Y166342D01*
X1570175Y166800D01*
X1570342Y167217D01*
X1570550Y167675D01*
X1570883Y168300D01*
X1569217D01*
G01X1570700Y163800D02*
Y155800D01*
X1553100D01*
Y163800D01*
X1570700D01*
G01X1624775Y207000D02*
Y209500D01*
G01X1626525D02*
Y207000D01*
G01Y208250D02*
X1624775D01*
G01X1627833Y207000D02*
Y209500D01*
X1628667D01*
X1629000Y209375D01*
X1629250Y209208D01*
X1629458Y208958D01*
X1629625Y208667D01*
X1629667Y208250D01*
X1629625Y207833D01*
X1629458Y207542D01*
X1629250Y207292D01*
X1629000Y207125D01*
X1628667Y207000D01*
X1627833D01*
G01X1630933D02*
Y209500D01*
X1631767D01*
X1632100Y209375D01*
X1632350Y209208D01*
X1632558Y208958D01*
X1632725Y208667D01*
X1632767Y208250D01*
X1632725Y207833D01*
X1632558Y207542D01*
X1632350Y207292D01*
X1632100Y207125D01*
X1631767Y207000D01*
X1630933D01*
G01X1634075Y207333D02*
X1634408Y207125D01*
X1634783Y207000D01*
X1635117D01*
X1635450Y207125D01*
X1635700Y207333D01*
X1635825Y207625D01*
X1635742Y207917D01*
X1635533Y208167D01*
X1635158Y208333D01*
X1634658Y208417D01*
X1634367Y208583D01*
X1634242Y208875D01*
X1634325Y209167D01*
X1634533Y209375D01*
X1634825Y209500D01*
X1635117D01*
X1635408Y209417D01*
X1635658Y209208D01*
G01X1637008Y207000D02*
X1638050Y209500D01*
X1639092Y207000D01*
G01X1638717Y207875D02*
X1637383D01*
G01X1640275Y207333D02*
X1640608Y207125D01*
X1640983Y207000D01*
X1641317D01*
X1641650Y207125D01*
X1641900Y207333D01*
X1642025Y207625D01*
X1641942Y207917D01*
X1641733Y208167D01*
X1641358Y208333D01*
X1640858Y208417D01*
X1640567Y208583D01*
X1640442Y208875D01*
X1640525Y209167D01*
X1640733Y209375D01*
X1641025Y209500D01*
X1641317D01*
X1641608Y209417D01*
X1641858Y209208D01*
G01X1643333Y207500D02*
X1643583Y207208D01*
X1643917Y207042D01*
X1644292Y207000D01*
X1644625Y207042D01*
X1644958Y207250D01*
X1645167Y207500D01*
X1645208Y207750D01*
X1645125Y208042D01*
X1644833Y208250D01*
X1644542Y208333D01*
X1644167D01*
G01X1644542D02*
X1644792Y208458D01*
X1645000Y208667D01*
X1645083Y208917D01*
X1645000Y209167D01*
X1644792Y209375D01*
X1644417Y209500D01*
X1644042Y209458D01*
X1643667Y209292D01*
G01X1646433Y207500D02*
X1646683Y207208D01*
X1647017Y207042D01*
X1647392Y207000D01*
X1647725Y207042D01*
X1648058Y207250D01*
X1648267Y207500D01*
X1648308Y207750D01*
X1648225Y208042D01*
X1647933Y208250D01*
X1647642Y208333D01*
X1647267D01*
G01X1647642D02*
X1647892Y208458D01*
X1648100Y208667D01*
X1648183Y208917D01*
X1648100Y209167D01*
X1647892Y209375D01*
X1647517Y209500D01*
X1647142Y209458D01*
X1646767Y209292D01*
G01X1545708Y193267D02*
X1545583Y193017D01*
X1545500Y192725D01*
Y192392D01*
X1545625Y192017D01*
X1545833Y191725D01*
X1546083Y191517D01*
X1546500Y191350D01*
X1546875Y191308D01*
X1547250Y191392D01*
X1547500Y191517D01*
X1547750Y191767D01*
X1547917Y192058D01*
X1548000Y192350D01*
Y192642D01*
X1547917Y192933D01*
X1547792Y193183D01*
X1547625Y193392D01*
G01X1548000Y195950D02*
X1545500D01*
X1547292Y194408D01*
Y196492D01*
G01X1547625Y197633D02*
X1547833Y197883D01*
X1547958Y198175D01*
X1548000Y198550D01*
X1547917Y198925D01*
X1547750Y199217D01*
X1547458Y199425D01*
X1547125Y199467D01*
X1546792Y199383D01*
X1546583Y199175D01*
X1546417Y198883D01*
X1546375Y198592D01*
X1546417Y198300D01*
X1546583Y197925D01*
X1545500Y198050D01*
Y199175D01*
G01X1545917Y200858D02*
X1545667Y201108D01*
X1545542Y201400D01*
X1545500Y201733D01*
X1545583Y202150D01*
X1545792Y202442D01*
X1546042Y202525D01*
X1546292Y202483D01*
X1546500Y202317D01*
X1546917Y201483D01*
X1547208Y201108D01*
X1547625Y200858D01*
X1548000Y200775D01*
Y202525D01*
G01X1601751Y268532D02*
Y266032D01*
X1603417D01*
G01X1606517D02*
X1604851D01*
Y268532D01*
X1606517D01*
G01X1605851Y267324D02*
X1604851D01*
G01X1607867Y266032D02*
Y268532D01*
X1608701D01*
X1609034Y268407D01*
X1609284Y268240D01*
X1609492Y267990D01*
X1609659Y267699D01*
X1609701Y267282D01*
X1609659Y266865D01*
X1609492Y266574D01*
X1609284Y266324D01*
X1609034Y266157D01*
X1608701Y266032D01*
X1607867D01*
G01X1611092Y268115D02*
X1611342Y268365D01*
X1611634Y268490D01*
X1611967Y268532D01*
X1612384Y268449D01*
X1612676Y268240D01*
X1612759Y267990D01*
X1612717Y267740D01*
X1612551Y267532D01*
X1611717Y267115D01*
X1611342Y266824D01*
X1611092Y266407D01*
X1611009Y266032D01*
X1612759D01*
G01X1614192Y268115D02*
X1614442Y268365D01*
X1614734Y268490D01*
X1615067Y268532D01*
X1615484Y268449D01*
X1615776Y268240D01*
X1615859Y267990D01*
X1615817Y267740D01*
X1615651Y267532D01*
X1614817Y267115D01*
X1614442Y266824D01*
X1614192Y266407D01*
X1614109Y266032D01*
X1615859D01*
G01X1608986Y251880D02*
Y263080D01*
X1617786D01*
Y251880D01*
X1608986D01*
G01X1552547Y193267D02*
X1552422Y193017D01*
X1552339Y192725D01*
Y192392D01*
X1552464Y192017D01*
X1552672Y191725D01*
X1552922Y191517D01*
X1553339Y191350D01*
X1553714Y191308D01*
X1554089Y191392D01*
X1554339Y191517D01*
X1554589Y191767D01*
X1554756Y192058D01*
X1554839Y192350D01*
Y192642D01*
X1554756Y192933D01*
X1554631Y193183D01*
X1554464Y193392D01*
G01X1554839Y195950D02*
X1552339D01*
X1554131Y194408D01*
Y196492D01*
G01X1554464Y197633D02*
X1554672Y197883D01*
X1554797Y198175D01*
X1554839Y198550D01*
X1554756Y198925D01*
X1554589Y199217D01*
X1554297Y199425D01*
X1553964Y199467D01*
X1553631Y199383D01*
X1553422Y199175D01*
X1553256Y198883D01*
X1553214Y198592D01*
X1553256Y198300D01*
X1553422Y197925D01*
X1552339Y198050D01*
Y199175D01*
G01Y201650D02*
X1552422Y201317D01*
X1552631Y201067D01*
X1552881Y200900D01*
X1553214Y200775D01*
X1553589Y200733D01*
X1553964Y200775D01*
X1554297Y200900D01*
X1554547Y201067D01*
X1554756Y201317D01*
X1554839Y201650D01*
X1554756Y201983D01*
X1554547Y202233D01*
X1554297Y202400D01*
X1553964Y202525D01*
X1553589Y202567D01*
X1553214Y202525D01*
X1552881Y202400D01*
X1552631Y202233D01*
X1552422Y201983D01*
X1552339Y201650D01*
G01X1560547Y193267D02*
X1560422Y193017D01*
X1560339Y192725D01*
Y192392D01*
X1560464Y192017D01*
X1560672Y191725D01*
X1560922Y191517D01*
X1561339Y191350D01*
X1561714Y191308D01*
X1562089Y191392D01*
X1562339Y191517D01*
X1562589Y191767D01*
X1562756Y192058D01*
X1562839Y192350D01*
Y192642D01*
X1562756Y192933D01*
X1562631Y193183D01*
X1562464Y193392D01*
G01X1562839Y195950D02*
X1560339D01*
X1562131Y194408D01*
Y196492D01*
G01X1562464Y197633D02*
X1562672Y197883D01*
X1562797Y198175D01*
X1562839Y198550D01*
X1562756Y198925D01*
X1562589Y199217D01*
X1562297Y199425D01*
X1561964Y199467D01*
X1561631Y199383D01*
X1561422Y199175D01*
X1561256Y198883D01*
X1561214Y198592D01*
X1561256Y198300D01*
X1561422Y197925D01*
X1560339Y198050D01*
Y199175D01*
G01X1562839Y201650D02*
X1560339D01*
X1560839Y201150D01*
G01X1562839D02*
Y202150D01*
G01X1595850Y377500D02*
X1595517Y377542D01*
X1595225Y377708D01*
X1594975Y377958D01*
X1594808Y378250D01*
X1594725Y378583D01*
Y378917D01*
X1594808Y379250D01*
X1594975Y379542D01*
X1595225Y379792D01*
X1595517Y379958D01*
X1595850Y380000D01*
X1596183Y379958D01*
X1596475Y379792D01*
X1596725Y379542D01*
X1596892Y379250D01*
X1596975Y378917D01*
Y378583D01*
X1596892Y378250D01*
X1596725Y377958D01*
X1596475Y377708D01*
X1596183Y377542D01*
X1595850Y377500D01*
G01X1596183Y378167D02*
X1596683Y377500D01*
G01X1598158Y379583D02*
X1598408Y379833D01*
X1598700Y379958D01*
X1599033Y380000D01*
X1599450Y379917D01*
X1599742Y379708D01*
X1599825Y379458D01*
X1599783Y379208D01*
X1599617Y379000D01*
X1598783Y378583D01*
X1598408Y378292D01*
X1598158Y377875D01*
X1598075Y377500D01*
X1599825D01*
G01X1602550D02*
Y380000D01*
X1601008Y378208D01*
X1603092D01*
G01X1605150Y380000D02*
X1604817Y379917D01*
X1604567Y379708D01*
X1604400Y379458D01*
X1604275Y379125D01*
X1604233Y378750D01*
X1604275Y378375D01*
X1604400Y378042D01*
X1604567Y377792D01*
X1604817Y377583D01*
X1605150Y377500D01*
X1605483Y377583D01*
X1605733Y377792D01*
X1605900Y378042D01*
X1606025Y378375D01*
X1606067Y378750D01*
X1606025Y379125D01*
X1605900Y379458D01*
X1605733Y379708D01*
X1605483Y379917D01*
X1605150Y380000D01*
G01X1577017Y402000D02*
Y404500D01*
X1578058D01*
X1578392Y404375D01*
X1578600Y404208D01*
X1578683Y403875D01*
X1578600Y403542D01*
X1578350Y403333D01*
X1578058Y403208D01*
X1577017D01*
G01X1578058D02*
X1578683Y402000D01*
G01X1581450D02*
Y404500D01*
X1579908Y402708D01*
X1581992D01*
G01X1584050Y402000D02*
X1584342Y402042D01*
X1584675Y402167D01*
X1584883Y402375D01*
X1584967Y402667D01*
X1584883Y402958D01*
X1584633Y403208D01*
X1584258Y403333D01*
X1583842D01*
X1583592Y403417D01*
X1583383Y403625D01*
X1583300Y403917D01*
X1583425Y404208D01*
X1583717Y404417D01*
X1584050Y404500D01*
X1584383Y404417D01*
X1584675Y404208D01*
X1584800Y403917D01*
X1584717Y403625D01*
X1584508Y403417D01*
X1584258Y403333D01*
X1583842D01*
X1583467Y403208D01*
X1583217Y402958D01*
X1583133Y402667D01*
X1583217Y402375D01*
X1583425Y402167D01*
X1583758Y402042D01*
X1584050Y402000D01*
G01X1587150D02*
Y404500D01*
X1586650Y404000D01*
G01Y402000D02*
X1587650D01*
G01X1591699Y381426D02*
Y385426D01*
X1584299D01*
G01X1595017Y381500D02*
Y384000D01*
X1596058D01*
X1596392Y383875D01*
X1596600Y383708D01*
X1596683Y383375D01*
X1596600Y383042D01*
X1596350Y382833D01*
X1596058Y382708D01*
X1595017D01*
G01X1596058D02*
X1596683Y381500D01*
G01X1599450D02*
Y384000D01*
X1597908Y382208D01*
X1599992D01*
G01X1602050Y381500D02*
X1602342Y381542D01*
X1602675Y381667D01*
X1602883Y381875D01*
X1602967Y382167D01*
X1602883Y382458D01*
X1602633Y382708D01*
X1602258Y382833D01*
X1601842D01*
X1601592Y382917D01*
X1601383Y383125D01*
X1601300Y383417D01*
X1601425Y383708D01*
X1601717Y383917D01*
X1602050Y384000D01*
X1602383Y383917D01*
X1602675Y383708D01*
X1602800Y383417D01*
X1602717Y383125D01*
X1602508Y382917D01*
X1602258Y382833D01*
X1601842D01*
X1601467Y382708D01*
X1601217Y382458D01*
X1601133Y382167D01*
X1601217Y381875D01*
X1601425Y381667D01*
X1601758Y381542D01*
X1602050Y381500D01*
G01X1605150Y384000D02*
X1604817Y383917D01*
X1604567Y383708D01*
X1604400Y383458D01*
X1604275Y383125D01*
X1604233Y382750D01*
X1604275Y382375D01*
X1604400Y382042D01*
X1604567Y381792D01*
X1604817Y381583D01*
X1605150Y381500D01*
X1605483Y381583D01*
X1605733Y381792D01*
X1605900Y382042D01*
X1606025Y382375D01*
X1606067Y382750D01*
X1606025Y383125D01*
X1605900Y383458D01*
X1605733Y383708D01*
X1605483Y383917D01*
X1605150Y384000D01*
G01X1606432Y401203D02*
Y405203D01*
X1599032D01*
G01X1623000Y385517D02*
X1620500D01*
Y386558D01*
X1620625Y386892D01*
X1620792Y387100D01*
X1621125Y387183D01*
X1621458Y387100D01*
X1621667Y386850D01*
X1621792Y386558D01*
Y385517D01*
G01Y386558D02*
X1623000Y387183D01*
G01Y389950D02*
X1620500D01*
X1622292Y388408D01*
Y390492D01*
G01X1623000Y393050D02*
X1620500D01*
X1622292Y391508D01*
Y393592D01*
G01X1623000Y395650D02*
X1622958Y395942D01*
X1622833Y396275D01*
X1622625Y396483D01*
X1622333Y396567D01*
X1622042Y396483D01*
X1621792Y396233D01*
X1621667Y395858D01*
Y395442D01*
X1621583Y395192D01*
X1621375Y394983D01*
X1621083Y394900D01*
X1620792Y395025D01*
X1620583Y395317D01*
X1620500Y395650D01*
X1620583Y395983D01*
X1620792Y396275D01*
X1621083Y396400D01*
X1621375Y396317D01*
X1621583Y396108D01*
X1621667Y395858D01*
Y395442D01*
X1621792Y395067D01*
X1622042Y394817D01*
X1622333Y394733D01*
X1622625Y394817D01*
X1622833Y395025D01*
X1622958Y395358D01*
X1623000Y395650D01*
G01X1627000Y385517D02*
X1624500D01*
Y386558D01*
X1624625Y386892D01*
X1624792Y387100D01*
X1625125Y387183D01*
X1625458Y387100D01*
X1625667Y386850D01*
X1625792Y386558D01*
Y385517D01*
G01Y386558D02*
X1627000Y387183D01*
G01Y389950D02*
X1624500D01*
X1626292Y388408D01*
Y390492D01*
G01X1626625Y391633D02*
X1626833Y391883D01*
X1626958Y392175D01*
X1627000Y392550D01*
X1626917Y392925D01*
X1626750Y393217D01*
X1626458Y393425D01*
X1626125Y393467D01*
X1625792Y393383D01*
X1625583Y393175D01*
X1625417Y392883D01*
X1625375Y392592D01*
X1625417Y392300D01*
X1625583Y391925D01*
X1624500Y392050D01*
Y393175D01*
G01Y395650D02*
X1624583Y395317D01*
X1624792Y395067D01*
X1625042Y394900D01*
X1625375Y394775D01*
X1625750Y394733D01*
X1626125Y394775D01*
X1626458Y394900D01*
X1626708Y395067D01*
X1626917Y395317D01*
X1627000Y395650D01*
X1626917Y395983D01*
X1626708Y396233D01*
X1626458Y396400D01*
X1626125Y396525D01*
X1625750Y396567D01*
X1625375Y396525D01*
X1625042Y396400D01*
X1624792Y396233D01*
X1624583Y395983D01*
X1624500Y395650D01*
G01X1607107Y385744D02*
Y399744D01*
G01X1594107Y385744D02*
X1607107D01*
G01X1594107Y399744D02*
Y385744D01*
G01X1607107Y399744D02*
X1594107D01*
G01X1577850Y406000D02*
X1577517Y406042D01*
X1577225Y406208D01*
X1576975Y406458D01*
X1576808Y406750D01*
X1576725Y407083D01*
Y407417D01*
X1576808Y407750D01*
X1576975Y408042D01*
X1577225Y408292D01*
X1577517Y408458D01*
X1577850Y408500D01*
X1578183Y408458D01*
X1578475Y408292D01*
X1578725Y408042D01*
X1578892Y407750D01*
X1578975Y407417D01*
Y407083D01*
X1578892Y406750D01*
X1578725Y406458D01*
X1578475Y406208D01*
X1578183Y406042D01*
X1577850Y406000D01*
G01X1578183Y406667D02*
X1578683Y406000D01*
G01X1580158Y408083D02*
X1580408Y408333D01*
X1580700Y408458D01*
X1581033Y408500D01*
X1581450Y408417D01*
X1581742Y408208D01*
X1581825Y407958D01*
X1581783Y407708D01*
X1581617Y407500D01*
X1580783Y407083D01*
X1580408Y406792D01*
X1580158Y406375D01*
X1580075Y406000D01*
X1581825D01*
G01X1583258Y407042D02*
X1583550Y407333D01*
X1583800Y407500D01*
X1584133Y407583D01*
X1584425Y407500D01*
X1584633Y407333D01*
X1584800Y407083D01*
X1584842Y406792D01*
X1584800Y406542D01*
X1584633Y406292D01*
X1584383Y406083D01*
X1584092Y406000D01*
X1583758Y406083D01*
X1583467Y406333D01*
X1583300Y406708D01*
X1583258Y407125D01*
X1583342Y407667D01*
X1583467Y407958D01*
X1583675Y408250D01*
X1583967Y408458D01*
X1584258Y408500D01*
X1584550Y408417D01*
X1584758Y408208D01*
G01X1586358Y408083D02*
X1586608Y408333D01*
X1586900Y408458D01*
X1587233Y408500D01*
X1587650Y408417D01*
X1587942Y408208D01*
X1588025Y407958D01*
X1587983Y407708D01*
X1587817Y407500D01*
X1586983Y407083D01*
X1586608Y406792D01*
X1586358Y406375D01*
X1586275Y406000D01*
X1588025D01*
G01X1578999Y386651D02*
X1592999D01*
G01X1578999Y399651D02*
Y386651D01*
G01X1592999Y399651D02*
X1578999D01*
G01X1592999Y386651D02*
Y399651D01*
G01X1626867Y521192D02*
X1626617Y521317D01*
X1626325Y521400D01*
X1625992D01*
X1625617Y521275D01*
X1625325Y521067D01*
X1625117Y520817D01*
X1624950Y520400D01*
X1624908Y520025D01*
X1624992Y519650D01*
X1625117Y519400D01*
X1625367Y519150D01*
X1625658Y518983D01*
X1625950Y518900D01*
X1626242D01*
X1626533Y518983D01*
X1626783Y519108D01*
X1626992Y519275D01*
G01X1628133Y519400D02*
X1628383Y519108D01*
X1628717Y518942D01*
X1629092Y518900D01*
X1629425Y518942D01*
X1629758Y519150D01*
X1629967Y519400D01*
X1630008Y519650D01*
X1629925Y519942D01*
X1629633Y520150D01*
X1629342Y520233D01*
X1628967D01*
G01X1629342D02*
X1629592Y520358D01*
X1629800Y520567D01*
X1629883Y520817D01*
X1629800Y521067D01*
X1629592Y521275D01*
X1629217Y521400D01*
X1628842Y521358D01*
X1628467Y521192D01*
G01X1632150Y521400D02*
X1631817Y521317D01*
X1631567Y521108D01*
X1631400Y520858D01*
X1631275Y520525D01*
X1631233Y520150D01*
X1631275Y519775D01*
X1631400Y519442D01*
X1631567Y519192D01*
X1631817Y518983D01*
X1632150Y518900D01*
X1632483Y518983D01*
X1632733Y519192D01*
X1632900Y519442D01*
X1633025Y519775D01*
X1633067Y520150D01*
X1633025Y520525D01*
X1632900Y520858D01*
X1632733Y521108D01*
X1632483Y521317D01*
X1632150Y521400D01*
G01X1635250Y518900D02*
Y521400D01*
X1634750Y520900D01*
G01Y518900D02*
X1635750D01*
G01X1626783Y517328D02*
X1626533Y517453D01*
X1626241Y517536D01*
X1625908D01*
X1625533Y517411D01*
X1625241Y517203D01*
X1625033Y516953D01*
X1624866Y516536D01*
X1624824Y516161D01*
X1624908Y515786D01*
X1625033Y515536D01*
X1625283Y515286D01*
X1625574Y515119D01*
X1625866Y515036D01*
X1626158D01*
X1626449Y515119D01*
X1626699Y515244D01*
X1626908Y515411D01*
G01X1628049Y515536D02*
X1628299Y515244D01*
X1628633Y515078D01*
X1629008Y515036D01*
X1629341Y515078D01*
X1629674Y515286D01*
X1629883Y515536D01*
X1629924Y515786D01*
X1629841Y516078D01*
X1629549Y516286D01*
X1629258Y516369D01*
X1628883D01*
G01X1629258D02*
X1629508Y516494D01*
X1629716Y516703D01*
X1629799Y516953D01*
X1629716Y517203D01*
X1629508Y517411D01*
X1629133Y517536D01*
X1628758Y517494D01*
X1628383Y517328D01*
G01X1632066Y517536D02*
X1631733Y517453D01*
X1631483Y517244D01*
X1631316Y516994D01*
X1631191Y516661D01*
X1631149Y516286D01*
X1631191Y515911D01*
X1631316Y515578D01*
X1631483Y515328D01*
X1631733Y515119D01*
X1632066Y515036D01*
X1632399Y515119D01*
X1632649Y515328D01*
X1632816Y515578D01*
X1632941Y515911D01*
X1632983Y516286D01*
X1632941Y516661D01*
X1632816Y516994D01*
X1632649Y517244D01*
X1632399Y517453D01*
X1632066Y517536D01*
G01X1634374Y517119D02*
X1634624Y517369D01*
X1634916Y517494D01*
X1635249Y517536D01*
X1635666Y517453D01*
X1635958Y517244D01*
X1636041Y516994D01*
X1635999Y516744D01*
X1635833Y516536D01*
X1634999Y516119D01*
X1634624Y515828D01*
X1634374Y515411D01*
X1634291Y515036D01*
X1636041D01*
G01X1544708Y534767D02*
X1544583Y534517D01*
X1544500Y534225D01*
Y533892D01*
X1544625Y533517D01*
X1544833Y533225D01*
X1545083Y533017D01*
X1545500Y532850D01*
X1545875Y532808D01*
X1546250Y532892D01*
X1546500Y533017D01*
X1546750Y533267D01*
X1546917Y533558D01*
X1547000Y533850D01*
Y534142D01*
X1546917Y534433D01*
X1546792Y534683D01*
X1546625Y534892D01*
G01X1544917Y536158D02*
X1544667Y536408D01*
X1544542Y536700D01*
X1544500Y537033D01*
X1544583Y537450D01*
X1544792Y537742D01*
X1545042Y537825D01*
X1545292Y537783D01*
X1545500Y537617D01*
X1545917Y536783D01*
X1546208Y536408D01*
X1546625Y536158D01*
X1547000Y536075D01*
Y537825D01*
G01X1546708Y539342D02*
X1546917Y539633D01*
X1547000Y539967D01*
X1546917Y540300D01*
X1546667Y540592D01*
X1546292Y540800D01*
X1545917Y540883D01*
X1545458D01*
X1545083Y540800D01*
X1544750Y540592D01*
X1544583Y540342D01*
X1544500Y540050D01*
X1544583Y539717D01*
X1544750Y539467D01*
X1545000Y539300D01*
X1545333Y539217D01*
X1545625Y539300D01*
X1545917Y539508D01*
X1546083Y539758D01*
X1546125Y540050D01*
X1546042Y540383D01*
X1545833Y540633D01*
X1545458Y540883D01*
G01X1547000Y543150D02*
X1546958Y543442D01*
X1546833Y543775D01*
X1546625Y543983D01*
X1546333Y544067D01*
X1546042Y543983D01*
X1545792Y543733D01*
X1545667Y543358D01*
Y542942D01*
X1545583Y542692D01*
X1545375Y542483D01*
X1545083Y542400D01*
X1544792Y542525D01*
X1544583Y542817D01*
X1544500Y543150D01*
X1544583Y543483D01*
X1544792Y543775D01*
X1545083Y543900D01*
X1545375Y543817D01*
X1545583Y543608D01*
X1545667Y543358D01*
Y542942D01*
X1545792Y542567D01*
X1546042Y542317D01*
X1546333Y542233D01*
X1546625Y542317D01*
X1546833Y542525D01*
X1546958Y542858D01*
X1547000Y543150D01*
G01X1589767Y566953D02*
X1589517Y567078D01*
X1589225Y567161D01*
X1588892D01*
X1588517Y567036D01*
X1588225Y566828D01*
X1588017Y566578D01*
X1587850Y566161D01*
X1587808Y565786D01*
X1587892Y565411D01*
X1588017Y565161D01*
X1588267Y564911D01*
X1588558Y564744D01*
X1588850Y564661D01*
X1589142D01*
X1589433Y564744D01*
X1589683Y564869D01*
X1589892Y565036D01*
G01X1591158Y566744D02*
X1591408Y566994D01*
X1591700Y567119D01*
X1592033Y567161D01*
X1592450Y567078D01*
X1592742Y566869D01*
X1592825Y566619D01*
X1592783Y566369D01*
X1592617Y566161D01*
X1591783Y565744D01*
X1591408Y565453D01*
X1591158Y565036D01*
X1591075Y564661D01*
X1592825D01*
G01X1594342Y564953D02*
X1594633Y564744D01*
X1594967Y564661D01*
X1595300Y564744D01*
X1595592Y564994D01*
X1595800Y565369D01*
X1595883Y565744D01*
Y566203D01*
X1595800Y566578D01*
X1595592Y566911D01*
X1595342Y567078D01*
X1595050Y567161D01*
X1594717Y567078D01*
X1594467Y566911D01*
X1594300Y566661D01*
X1594217Y566328D01*
X1594300Y566036D01*
X1594508Y565744D01*
X1594758Y565578D01*
X1595050Y565536D01*
X1595383Y565619D01*
X1595633Y565828D01*
X1595883Y566203D01*
G01X1597442Y564953D02*
X1597733Y564744D01*
X1598067Y564661D01*
X1598400Y564744D01*
X1598692Y564994D01*
X1598900Y565369D01*
X1598983Y565744D01*
Y566203D01*
X1598900Y566578D01*
X1598692Y566911D01*
X1598442Y567078D01*
X1598150Y567161D01*
X1597817Y567078D01*
X1597567Y566911D01*
X1597400Y566661D01*
X1597317Y566328D01*
X1597400Y566036D01*
X1597608Y565744D01*
X1597858Y565578D01*
X1598150Y565536D01*
X1598483Y565619D01*
X1598733Y565828D01*
X1598983Y566203D01*
G01X1547000Y519517D02*
X1544500D01*
Y520558D01*
X1544625Y520892D01*
X1544792Y521100D01*
X1545125Y521183D01*
X1545458Y521100D01*
X1545667Y520850D01*
X1545792Y520558D01*
Y519517D01*
G01Y520558D02*
X1547000Y521183D01*
G01X1546625Y522533D02*
X1546833Y522783D01*
X1546958Y523075D01*
X1547000Y523450D01*
X1546917Y523825D01*
X1546750Y524117D01*
X1546458Y524325D01*
X1546125Y524367D01*
X1545792Y524283D01*
X1545583Y524075D01*
X1545417Y523783D01*
X1545375Y523492D01*
X1545417Y523200D01*
X1545583Y522825D01*
X1544500Y522950D01*
Y524075D01*
G01X1546500Y525633D02*
X1546792Y525883D01*
X1546958Y526217D01*
X1547000Y526592D01*
X1546958Y526925D01*
X1546750Y527258D01*
X1546500Y527467D01*
X1546250Y527508D01*
X1545958Y527425D01*
X1545750Y527133D01*
X1545667Y526842D01*
Y526467D01*
G01Y526842D02*
X1545542Y527092D01*
X1545333Y527300D01*
X1545083Y527383D01*
X1544833Y527300D01*
X1544625Y527092D01*
X1544500Y526717D01*
X1544542Y526342D01*
X1544708Y525967D01*
G01X1547000Y529567D02*
X1546458Y529650D01*
X1546000Y529775D01*
X1545583Y529942D01*
X1545125Y530150D01*
X1544500Y530483D01*
Y528817D01*
G01X1550000Y531800D02*
Y527800D01*
X1557400D01*
G01X1553000Y496517D02*
X1550500D01*
Y497558D01*
X1550625Y497892D01*
X1550792Y498100D01*
X1551125Y498183D01*
X1551458Y498100D01*
X1551667Y497850D01*
X1551792Y497558D01*
Y496517D01*
G01Y497558D02*
X1553000Y498183D01*
G01X1552625Y499533D02*
X1552833Y499783D01*
X1552958Y500075D01*
X1553000Y500450D01*
X1552917Y500825D01*
X1552750Y501117D01*
X1552458Y501325D01*
X1552125Y501367D01*
X1551792Y501283D01*
X1551583Y501075D01*
X1551417Y500783D01*
X1551375Y500492D01*
X1551417Y500200D01*
X1551583Y499825D01*
X1550500Y499950D01*
Y501075D01*
G01X1552500Y502633D02*
X1552792Y502883D01*
X1552958Y503217D01*
X1553000Y503592D01*
X1552958Y503925D01*
X1552750Y504258D01*
X1552500Y504467D01*
X1552250Y504508D01*
X1551958Y504425D01*
X1551750Y504133D01*
X1551667Y503842D01*
Y503467D01*
G01Y503842D02*
X1551542Y504092D01*
X1551333Y504300D01*
X1551083Y504383D01*
X1550833Y504300D01*
X1550625Y504092D01*
X1550500Y503717D01*
X1550542Y503342D01*
X1550708Y502967D01*
G01X1553000Y506650D02*
X1552958Y506942D01*
X1552833Y507275D01*
X1552625Y507483D01*
X1552333Y507567D01*
X1552042Y507483D01*
X1551792Y507233D01*
X1551667Y506858D01*
Y506442D01*
X1551583Y506192D01*
X1551375Y505983D01*
X1551083Y505900D01*
X1550792Y506025D01*
X1550583Y506317D01*
X1550500Y506650D01*
X1550583Y506983D01*
X1550792Y507275D01*
X1551083Y507400D01*
X1551375Y507317D01*
X1551583Y507108D01*
X1551667Y506858D01*
Y506442D01*
X1551792Y506067D01*
X1552042Y505817D01*
X1552333Y505733D01*
X1552625Y505817D01*
X1552833Y506025D01*
X1552958Y506358D01*
X1553000Y506650D01*
G01X1558500Y502800D02*
X1562500D01*
Y510200D01*
G01X1578500Y500017D02*
X1576000D01*
Y501058D01*
X1576125Y501392D01*
X1576292Y501600D01*
X1576625Y501683D01*
X1576958Y501600D01*
X1577167Y501350D01*
X1577292Y501058D01*
Y500017D01*
G01Y501058D02*
X1578500Y501683D01*
G01X1578125Y503033D02*
X1578333Y503283D01*
X1578458Y503575D01*
X1578500Y503950D01*
X1578417Y504325D01*
X1578250Y504617D01*
X1577958Y504825D01*
X1577625Y504867D01*
X1577292Y504783D01*
X1577083Y504575D01*
X1576917Y504283D01*
X1576875Y503992D01*
X1576917Y503700D01*
X1577083Y503325D01*
X1576000Y503450D01*
Y504575D01*
G01X1578500Y507550D02*
X1576000D01*
X1577792Y506008D01*
Y508092D01*
G01X1576000Y510150D02*
X1576083Y509817D01*
X1576292Y509567D01*
X1576542Y509400D01*
X1576875Y509275D01*
X1577250Y509233D01*
X1577625Y509275D01*
X1577958Y509400D01*
X1578208Y509567D01*
X1578417Y509817D01*
X1578500Y510150D01*
X1578417Y510483D01*
X1578208Y510733D01*
X1577958Y510900D01*
X1577625Y511025D01*
X1577250Y511067D01*
X1576875Y511025D01*
X1576542Y510900D01*
X1576292Y510733D01*
X1576083Y510483D01*
X1576000Y510150D01*
G01X1568500Y502800D02*
X1572500D01*
Y510200D01*
G01X1549000Y496517D02*
X1546500D01*
Y497558D01*
X1546625Y497892D01*
X1546792Y498100D01*
X1547125Y498183D01*
X1547458Y498100D01*
X1547667Y497850D01*
X1547792Y497558D01*
Y496517D01*
G01Y497558D02*
X1549000Y498183D01*
G01X1548625Y499533D02*
X1548833Y499783D01*
X1548958Y500075D01*
X1549000Y500450D01*
X1548917Y500825D01*
X1548750Y501117D01*
X1548458Y501325D01*
X1548125Y501367D01*
X1547792Y501283D01*
X1547583Y501075D01*
X1547417Y500783D01*
X1547375Y500492D01*
X1547417Y500200D01*
X1547583Y499825D01*
X1546500Y499950D01*
Y501075D01*
G01X1549000Y504050D02*
X1546500D01*
X1548292Y502508D01*
Y504592D01*
G01X1546917Y505858D02*
X1546667Y506108D01*
X1546542Y506400D01*
X1546500Y506733D01*
X1546583Y507150D01*
X1546792Y507442D01*
X1547042Y507525D01*
X1547292Y507483D01*
X1547500Y507317D01*
X1547917Y506483D01*
X1548208Y506108D01*
X1548625Y505858D01*
X1549000Y505775D01*
Y507525D01*
G01X1558000Y510200D02*
X1554000D01*
Y502800D01*
G01X1586500Y511017D02*
X1584000D01*
Y512058D01*
X1584125Y512392D01*
X1584292Y512600D01*
X1584625Y512683D01*
X1584958Y512600D01*
X1585167Y512350D01*
X1585292Y512058D01*
Y511017D01*
G01Y512058D02*
X1586500Y512683D01*
G01X1586125Y514033D02*
X1586333Y514283D01*
X1586458Y514575D01*
X1586500Y514950D01*
X1586417Y515325D01*
X1586250Y515617D01*
X1585958Y515825D01*
X1585625Y515867D01*
X1585292Y515783D01*
X1585083Y515575D01*
X1584917Y515283D01*
X1584875Y514992D01*
X1584917Y514700D01*
X1585083Y514325D01*
X1584000Y514450D01*
Y515575D01*
G01X1586500Y518550D02*
X1584000D01*
X1585792Y517008D01*
Y519092D01*
G01X1586500Y521650D02*
X1584000D01*
X1585792Y520108D01*
Y522192D01*
G01X1573000Y515300D02*
X1577000D01*
Y522700D01*
G01X1588017Y560661D02*
Y563161D01*
X1589058D01*
X1589392Y563036D01*
X1589600Y562869D01*
X1589683Y562536D01*
X1589600Y562203D01*
X1589350Y561994D01*
X1589058Y561869D01*
X1588017D01*
G01X1589058D02*
X1589683Y560661D01*
G01X1591033Y561036D02*
X1591283Y560828D01*
X1591575Y560703D01*
X1591950Y560661D01*
X1592325Y560744D01*
X1592617Y560911D01*
X1592825Y561203D01*
X1592867Y561536D01*
X1592783Y561869D01*
X1592575Y562078D01*
X1592283Y562244D01*
X1591992Y562286D01*
X1591700Y562244D01*
X1591325Y562078D01*
X1591450Y563161D01*
X1592575D01*
G01X1595550Y560661D02*
Y563161D01*
X1594008Y561369D01*
X1596092D01*
G01X1597233Y561036D02*
X1597483Y560828D01*
X1597775Y560703D01*
X1598150Y560661D01*
X1598525Y560744D01*
X1598817Y560911D01*
X1599025Y561203D01*
X1599067Y561536D01*
X1598983Y561869D01*
X1598775Y562078D01*
X1598483Y562244D01*
X1598192Y562286D01*
X1597900Y562244D01*
X1597525Y562078D01*
X1597650Y563161D01*
X1598775D01*
G01X1585700Y560500D02*
Y564500D01*
X1578300D01*
G01X1588017Y532500D02*
Y535000D01*
X1589058D01*
X1589392Y534875D01*
X1589600Y534708D01*
X1589683Y534375D01*
X1589600Y534042D01*
X1589350Y533833D01*
X1589058Y533708D01*
X1588017D01*
G01X1589058D02*
X1589683Y532500D01*
G01X1591033Y532875D02*
X1591283Y532667D01*
X1591575Y532542D01*
X1591950Y532500D01*
X1592325Y532583D01*
X1592617Y532750D01*
X1592825Y533042D01*
X1592867Y533375D01*
X1592783Y533708D01*
X1592575Y533917D01*
X1592283Y534083D01*
X1591992Y534125D01*
X1591700Y534083D01*
X1591325Y533917D01*
X1591450Y535000D01*
X1592575D01*
G01X1595550Y532500D02*
Y535000D01*
X1594008Y533208D01*
X1596092D01*
G01X1597358Y533542D02*
X1597650Y533833D01*
X1597900Y534000D01*
X1598233Y534083D01*
X1598525Y534000D01*
X1598733Y533833D01*
X1598900Y533583D01*
X1598942Y533292D01*
X1598900Y533042D01*
X1598733Y532792D01*
X1598483Y532583D01*
X1598192Y532500D01*
X1597858Y532583D01*
X1597567Y532833D01*
X1597400Y533208D01*
X1597358Y533625D01*
X1597442Y534167D01*
X1597567Y534458D01*
X1597775Y534750D01*
X1598067Y534958D01*
X1598358Y535000D01*
X1598650Y534917D01*
X1598858Y534708D01*
G01X1575800Y535500D02*
Y531500D01*
X1583200D01*
G01X1582500Y511017D02*
X1580000D01*
Y512058D01*
X1580125Y512392D01*
X1580292Y512600D01*
X1580625Y512683D01*
X1580958Y512600D01*
X1581167Y512350D01*
X1581292Y512058D01*
Y511017D01*
G01Y512058D02*
X1582500Y512683D01*
G01X1582125Y514033D02*
X1582333Y514283D01*
X1582458Y514575D01*
X1582500Y514950D01*
X1582417Y515325D01*
X1582250Y515617D01*
X1581958Y515825D01*
X1581625Y515867D01*
X1581292Y515783D01*
X1581083Y515575D01*
X1580917Y515283D01*
X1580875Y514992D01*
X1580917Y514700D01*
X1581083Y514325D01*
X1580000Y514450D01*
Y515575D01*
G01X1582500Y518550D02*
X1580000D01*
X1581792Y517008D01*
Y519092D01*
G01X1582500Y521067D02*
X1581958Y521150D01*
X1581500Y521275D01*
X1581083Y521442D01*
X1580625Y521650D01*
X1580000Y521983D01*
Y520317D01*
G01X1568500Y515300D02*
X1572500D01*
Y522700D01*
G01X1553400Y559500D02*
X1553067Y559542D01*
X1552775Y559708D01*
X1552525Y559958D01*
X1552358Y560250D01*
X1552275Y560583D01*
Y560917D01*
X1552358Y561250D01*
X1552525Y561542D01*
X1552775Y561792D01*
X1553067Y561958D01*
X1553400Y562000D01*
X1553733Y561958D01*
X1554025Y561792D01*
X1554275Y561542D01*
X1554442Y561250D01*
X1554525Y560917D01*
Y560583D01*
X1554442Y560250D01*
X1554275Y559958D01*
X1554025Y559708D01*
X1553733Y559542D01*
X1553400Y559500D01*
G01X1553733Y560167D02*
X1554233Y559500D01*
G01X1555792Y559792D02*
X1556083Y559583D01*
X1556417Y559500D01*
X1556750Y559583D01*
X1557042Y559833D01*
X1557250Y560208D01*
X1557333Y560583D01*
Y561042D01*
X1557250Y561417D01*
X1557042Y561750D01*
X1556792Y561917D01*
X1556500Y562000D01*
X1556167Y561917D01*
X1555917Y561750D01*
X1555750Y561500D01*
X1555667Y561167D01*
X1555750Y560875D01*
X1555958Y560583D01*
X1556208Y560417D01*
X1556500Y560375D01*
X1556833Y560458D01*
X1557083Y560667D01*
X1557333Y561042D01*
G01X1558683Y560000D02*
X1558933Y559708D01*
X1559267Y559542D01*
X1559642Y559500D01*
X1559975Y559542D01*
X1560308Y559750D01*
X1560517Y560000D01*
X1560558Y560250D01*
X1560475Y560542D01*
X1560183Y560750D01*
X1559892Y560833D01*
X1559517D01*
G01X1559892D02*
X1560142Y560958D01*
X1560350Y561167D01*
X1560433Y561417D01*
X1560350Y561667D01*
X1560142Y561875D01*
X1559767Y562000D01*
X1559392Y561958D01*
X1559017Y561792D01*
G01X1569000Y557700D02*
X1567200Y555600D01*
X1565000Y557700D01*
G01X1561400Y557800D02*
Y538600D01*
X1572600D01*
Y557800D01*
X1561400D01*
Y557400D01*
G01X1586483Y527000D02*
Y529500D01*
X1587317D01*
X1587650Y529375D01*
X1587900Y529208D01*
X1588108Y528958D01*
X1588275Y528667D01*
X1588317Y528250D01*
X1588275Y527833D01*
X1588108Y527542D01*
X1587900Y527292D01*
X1587650Y527125D01*
X1587317Y527000D01*
X1586483D01*
G01X1589708Y529083D02*
X1589958Y529333D01*
X1590250Y529458D01*
X1590583Y529500D01*
X1591000Y529417D01*
X1591292Y529208D01*
X1591375Y528958D01*
X1591333Y528708D01*
X1591167Y528500D01*
X1590333Y528083D01*
X1589958Y527792D01*
X1589708Y527375D01*
X1589625Y527000D01*
X1591375D01*
G01X1593600Y529500D02*
X1593267Y529417D01*
X1593017Y529208D01*
X1592850Y528958D01*
X1592725Y528625D01*
X1592683Y528250D01*
X1592725Y527875D01*
X1592850Y527542D01*
X1593017Y527292D01*
X1593267Y527083D01*
X1593600Y527000D01*
X1593933Y527083D01*
X1594183Y527292D01*
X1594350Y527542D01*
X1594475Y527875D01*
X1594517Y528250D01*
X1594475Y528625D01*
X1594350Y528958D01*
X1594183Y529208D01*
X1593933Y529417D01*
X1593600Y529500D01*
G01X1585000Y523500D02*
X1568900D01*
G01X1585000Y530500D02*
Y523500D01*
G01X1568900Y530500D02*
X1585000D01*
G01X1568900Y523500D02*
Y530500D01*
G01X1547500Y510400D02*
X1547458Y510067D01*
X1547292Y509775D01*
X1547042Y509525D01*
X1546750Y509358D01*
X1546417Y509275D01*
X1546083D01*
X1545750Y509358D01*
X1545458Y509525D01*
X1545208Y509775D01*
X1545042Y510067D01*
X1545000Y510400D01*
X1545042Y510733D01*
X1545208Y511025D01*
X1545458Y511275D01*
X1545750Y511442D01*
X1546083Y511525D01*
X1546417D01*
X1546750Y511442D01*
X1547042Y511275D01*
X1547292Y511025D01*
X1547458Y510733D01*
X1547500Y510400D01*
G01X1546833Y510733D02*
X1547500Y511233D01*
G01X1547208Y512792D02*
X1547417Y513083D01*
X1547500Y513417D01*
X1547417Y513750D01*
X1547167Y514042D01*
X1546792Y514250D01*
X1546417Y514333D01*
X1545958D01*
X1545583Y514250D01*
X1545250Y514042D01*
X1545083Y513792D01*
X1545000Y513500D01*
X1545083Y513167D01*
X1545250Y512917D01*
X1545500Y512750D01*
X1545833Y512667D01*
X1546125Y512750D01*
X1546417Y512958D01*
X1546583Y513208D01*
X1546625Y513500D01*
X1546542Y513833D01*
X1546333Y514083D01*
X1545958Y514333D01*
G01X1547125Y515683D02*
X1547333Y515933D01*
X1547458Y516225D01*
X1547500Y516600D01*
X1547417Y516975D01*
X1547250Y517267D01*
X1546958Y517475D01*
X1546625Y517517D01*
X1546292Y517433D01*
X1546083Y517225D01*
X1545917Y516933D01*
X1545875Y516642D01*
X1545917Y516350D01*
X1546083Y515975D01*
X1545000Y516100D01*
Y517225D01*
G01X1549300Y522700D02*
Y511300D01*
G01X1562700Y522700D02*
X1549300D01*
G01X1562700Y511300D02*
Y522700D01*
G01X1549300Y511300D02*
X1562700D01*
G01X1550017Y570500D02*
Y573000D01*
X1551058D01*
X1551392Y572875D01*
X1551600Y572708D01*
X1551683Y572375D01*
X1551600Y572042D01*
X1551350Y571833D01*
X1551058Y571708D01*
X1550017D01*
G01X1551058D02*
X1551683Y570500D01*
G01X1553033Y570875D02*
X1553283Y570667D01*
X1553575Y570542D01*
X1553950Y570500D01*
X1554325Y570583D01*
X1554617Y570750D01*
X1554825Y571042D01*
X1554867Y571375D01*
X1554783Y571708D01*
X1554575Y571917D01*
X1554283Y572083D01*
X1553992Y572125D01*
X1553700Y572083D01*
X1553325Y571917D01*
X1553450Y573000D01*
X1554575D01*
G01X1556258Y572583D02*
X1556508Y572833D01*
X1556800Y572958D01*
X1557133Y573000D01*
X1557550Y572917D01*
X1557842Y572708D01*
X1557925Y572458D01*
X1557883Y572208D01*
X1557717Y572000D01*
X1556883Y571583D01*
X1556508Y571292D01*
X1556258Y570875D01*
X1556175Y570500D01*
X1557925D01*
G01X1559442Y570792D02*
X1559733Y570583D01*
X1560067Y570500D01*
X1560400Y570583D01*
X1560692Y570833D01*
X1560900Y571208D01*
X1560983Y571583D01*
Y572042D01*
X1560900Y572417D01*
X1560692Y572750D01*
X1560442Y572917D01*
X1560150Y573000D01*
X1559817Y572917D01*
X1559567Y572750D01*
X1559400Y572500D01*
X1559317Y572167D01*
X1559400Y571875D01*
X1559608Y571583D01*
X1559858Y571417D01*
X1560150Y571375D01*
X1560483Y571458D01*
X1560733Y571667D01*
X1560983Y572042D01*
G01X1545208Y609767D02*
X1545083Y609517D01*
X1545000Y609225D01*
Y608892D01*
X1545125Y608517D01*
X1545333Y608225D01*
X1545583Y608017D01*
X1546000Y607850D01*
X1546375Y607808D01*
X1546750Y607892D01*
X1547000Y608017D01*
X1547250Y608267D01*
X1547417Y608558D01*
X1547500Y608850D01*
Y609142D01*
X1547417Y609433D01*
X1547292Y609683D01*
X1547125Y609892D01*
G01X1545417Y611158D02*
X1545167Y611408D01*
X1545042Y611700D01*
X1545000Y612033D01*
X1545083Y612450D01*
X1545292Y612742D01*
X1545542Y612825D01*
X1545792Y612783D01*
X1546000Y612617D01*
X1546417Y611783D01*
X1546708Y611408D01*
X1547125Y611158D01*
X1547500Y611075D01*
Y612825D01*
G01X1547208Y614342D02*
X1547417Y614633D01*
X1547500Y614967D01*
X1547417Y615300D01*
X1547167Y615592D01*
X1546792Y615800D01*
X1546417Y615883D01*
X1545958D01*
X1545583Y615800D01*
X1545250Y615592D01*
X1545083Y615342D01*
X1545000Y615050D01*
X1545083Y614717D01*
X1545250Y614467D01*
X1545500Y614300D01*
X1545833Y614217D01*
X1546125Y614300D01*
X1546417Y614508D01*
X1546583Y614758D01*
X1546625Y615050D01*
X1546542Y615383D01*
X1546333Y615633D01*
X1545958Y615883D01*
G01X1545000Y618150D02*
X1545083Y617817D01*
X1545292Y617567D01*
X1545542Y617400D01*
X1545875Y617275D01*
X1546250Y617233D01*
X1546625Y617275D01*
X1546958Y617400D01*
X1547208Y617567D01*
X1547417Y617817D01*
X1547500Y618150D01*
X1547417Y618483D01*
X1547208Y618733D01*
X1546958Y618900D01*
X1546625Y619025D01*
X1546250Y619067D01*
X1545875Y619025D01*
X1545542Y618900D01*
X1545292Y618733D01*
X1545083Y618483D01*
X1545000Y618150D01*
G01X1545708Y643267D02*
X1545583Y643017D01*
X1545500Y642725D01*
Y642392D01*
X1545625Y642017D01*
X1545833Y641725D01*
X1546083Y641517D01*
X1546500Y641350D01*
X1546875Y641308D01*
X1547250Y641392D01*
X1547500Y641517D01*
X1547750Y641767D01*
X1547917Y642058D01*
X1548000Y642350D01*
Y642642D01*
X1547917Y642933D01*
X1547792Y643183D01*
X1547625Y643392D01*
G01X1545917Y644658D02*
X1545667Y644908D01*
X1545542Y645200D01*
X1545500Y645533D01*
X1545583Y645950D01*
X1545792Y646242D01*
X1546042Y646325D01*
X1546292Y646283D01*
X1546500Y646117D01*
X1546917Y645283D01*
X1547208Y644908D01*
X1547625Y644658D01*
X1548000Y644575D01*
Y646325D01*
G01X1547708Y647842D02*
X1547917Y648133D01*
X1548000Y648467D01*
X1547917Y648800D01*
X1547667Y649092D01*
X1547292Y649300D01*
X1546917Y649383D01*
X1546458D01*
X1546083Y649300D01*
X1545750Y649092D01*
X1545583Y648842D01*
X1545500Y648550D01*
X1545583Y648217D01*
X1545750Y647967D01*
X1546000Y647800D01*
X1546333Y647717D01*
X1546625Y647800D01*
X1546917Y648008D01*
X1547083Y648258D01*
X1547125Y648550D01*
X1547042Y648883D01*
X1546833Y649133D01*
X1546458Y649383D01*
G01X1546958Y650858D02*
X1546667Y651150D01*
X1546500Y651400D01*
X1546417Y651733D01*
X1546500Y652025D01*
X1546667Y652233D01*
X1546917Y652400D01*
X1547208Y652442D01*
X1547458Y652400D01*
X1547708Y652233D01*
X1547917Y651983D01*
X1548000Y651692D01*
X1547917Y651358D01*
X1547667Y651067D01*
X1547292Y650900D01*
X1546875Y650858D01*
X1546333Y650942D01*
X1546042Y651067D01*
X1545750Y651275D01*
X1545542Y651567D01*
X1545500Y651858D01*
X1545583Y652150D01*
X1545792Y652358D01*
G01X1622800Y615500D02*
Y613000D01*
G01X1621842Y615500D02*
X1623758D01*
G01X1625067Y613000D02*
Y615500D01*
X1626067D01*
X1626400Y615375D01*
X1626650Y615083D01*
X1626733Y614750D01*
X1626650Y614417D01*
X1626442Y614167D01*
X1626067Y614042D01*
X1625067D01*
G01X1629000Y613000D02*
Y615500D01*
X1628500Y615000D01*
G01Y613000D02*
X1629500D01*
G01X1631308Y615083D02*
X1631558Y615333D01*
X1631850Y615458D01*
X1632183Y615500D01*
X1632600Y615417D01*
X1632892Y615208D01*
X1632975Y614958D01*
X1632933Y614708D01*
X1632767Y614500D01*
X1631933Y614083D01*
X1631558Y613792D01*
X1631308Y613375D01*
X1631225Y613000D01*
X1632975D01*
G01X1634408Y614042D02*
X1634700Y614333D01*
X1634950Y614500D01*
X1635283Y614583D01*
X1635575Y614500D01*
X1635783Y614333D01*
X1635950Y614083D01*
X1635992Y613792D01*
X1635950Y613542D01*
X1635783Y613292D01*
X1635533Y613083D01*
X1635242Y613000D01*
X1634908Y613083D01*
X1634617Y613333D01*
X1634450Y613708D01*
X1634408Y614125D01*
X1634492Y614667D01*
X1634617Y614958D01*
X1634825Y615250D01*
X1635117Y615458D01*
X1635408Y615500D01*
X1635700Y615417D01*
X1635908Y615208D01*
G01X1577400Y598500D02*
X1577067Y598542D01*
X1576775Y598708D01*
X1576525Y598958D01*
X1576358Y599250D01*
X1576275Y599583D01*
Y599917D01*
X1576358Y600250D01*
X1576525Y600542D01*
X1576775Y600792D01*
X1577067Y600958D01*
X1577400Y601000D01*
X1577733Y600958D01*
X1578025Y600792D01*
X1578275Y600542D01*
X1578442Y600250D01*
X1578525Y599917D01*
Y599583D01*
X1578442Y599250D01*
X1578275Y598958D01*
X1578025Y598708D01*
X1577733Y598542D01*
X1577400Y598500D01*
G01X1577733Y599167D02*
X1578233Y598500D01*
G01X1579792Y598792D02*
X1580083Y598583D01*
X1580417Y598500D01*
X1580750Y598583D01*
X1581042Y598833D01*
X1581250Y599208D01*
X1581333Y599583D01*
Y600042D01*
X1581250Y600417D01*
X1581042Y600750D01*
X1580792Y600917D01*
X1580500Y601000D01*
X1580167Y600917D01*
X1579917Y600750D01*
X1579750Y600500D01*
X1579667Y600167D01*
X1579750Y599875D01*
X1579958Y599583D01*
X1580208Y599417D01*
X1580500Y599375D01*
X1580833Y599458D01*
X1581083Y599667D01*
X1581333Y600042D01*
G01X1582808Y599542D02*
X1583100Y599833D01*
X1583350Y600000D01*
X1583683Y600083D01*
X1583975Y600000D01*
X1584183Y599833D01*
X1584350Y599583D01*
X1584392Y599292D01*
X1584350Y599042D01*
X1584183Y598792D01*
X1583933Y598583D01*
X1583642Y598500D01*
X1583308Y598583D01*
X1583017Y598833D01*
X1582850Y599208D01*
X1582808Y599625D01*
X1582892Y600167D01*
X1583017Y600458D01*
X1583225Y600750D01*
X1583517Y600958D01*
X1583808Y601000D01*
X1584100Y600917D01*
X1584308Y600708D01*
G01X1563800Y585000D02*
X1565900Y583200D01*
X1563800Y581000D01*
G01X1563700Y577400D02*
X1582900D01*
Y588600D01*
X1563700D01*
Y577400D01*
X1564100D01*
G01X1627000Y582517D02*
X1624500D01*
Y583558D01*
X1624625Y583892D01*
X1624792Y584100D01*
X1625125Y584183D01*
X1625458Y584100D01*
X1625667Y583850D01*
X1625792Y583558D01*
Y582517D01*
G01Y583558D02*
X1627000Y584183D01*
G01X1626625Y585533D02*
X1626833Y585783D01*
X1626958Y586075D01*
X1627000Y586450D01*
X1626917Y586825D01*
X1626750Y587117D01*
X1626458Y587325D01*
X1626125Y587367D01*
X1625792Y587283D01*
X1625583Y587075D01*
X1625417Y586783D01*
X1625375Y586492D01*
X1625417Y586200D01*
X1625583Y585825D01*
X1624500Y585950D01*
Y587075D01*
G01X1626625Y588633D02*
X1626833Y588883D01*
X1626958Y589175D01*
X1627000Y589550D01*
X1626917Y589925D01*
X1626750Y590217D01*
X1626458Y590425D01*
X1626125Y590467D01*
X1625792Y590383D01*
X1625583Y590175D01*
X1625417Y589883D01*
X1625375Y589592D01*
X1625417Y589300D01*
X1625583Y588925D01*
X1624500Y589050D01*
Y590175D01*
G01X1627000Y592567D02*
X1626458Y592650D01*
X1626000Y592775D01*
X1625583Y592942D01*
X1625125Y593150D01*
X1624500Y593483D01*
Y591817D01*
G01X1549708Y609267D02*
X1549583Y609017D01*
X1549500Y608725D01*
Y608392D01*
X1549625Y608017D01*
X1549833Y607725D01*
X1550083Y607517D01*
X1550500Y607350D01*
X1550875Y607308D01*
X1551250Y607392D01*
X1551500Y607517D01*
X1551750Y607767D01*
X1551917Y608058D01*
X1552000Y608350D01*
Y608642D01*
X1551917Y608933D01*
X1551792Y609183D01*
X1551625Y609392D01*
G01X1549917Y610658D02*
X1549667Y610908D01*
X1549542Y611200D01*
X1549500Y611533D01*
X1549583Y611950D01*
X1549792Y612242D01*
X1550042Y612325D01*
X1550292Y612283D01*
X1550500Y612117D01*
X1550917Y611283D01*
X1551208Y610908D01*
X1551625Y610658D01*
X1552000Y610575D01*
Y612325D01*
G01X1551708Y613842D02*
X1551917Y614133D01*
X1552000Y614467D01*
X1551917Y614800D01*
X1551667Y615092D01*
X1551292Y615300D01*
X1550917Y615383D01*
X1550458D01*
X1550083Y615300D01*
X1549750Y615092D01*
X1549583Y614842D01*
X1549500Y614550D01*
X1549583Y614217D01*
X1549750Y613967D01*
X1550000Y613800D01*
X1550333Y613717D01*
X1550625Y613800D01*
X1550917Y614008D01*
X1551083Y614258D01*
X1551125Y614550D01*
X1551042Y614883D01*
X1550833Y615133D01*
X1550458Y615383D01*
G01X1552000Y617650D02*
X1549500D01*
X1550000Y617150D01*
G01X1552000D02*
Y618150D01*
G01X1553000Y589200D02*
Y594700D01*
G01X1561000Y589200D02*
X1553000D01*
G01X1561000Y594700D02*
Y589200D01*
G01Y606800D02*
Y601300D01*
G01X1553000Y606800D02*
X1561000D01*
G01X1553000Y601300D02*
Y606800D01*
G01X1562300Y583000D02*
Y575000D01*
X1544700D01*
Y583000D01*
X1562300D01*
G01X1560317Y618100D02*
Y620600D01*
X1561358D01*
X1561692Y620475D01*
X1561900Y620308D01*
X1561983Y619975D01*
X1561900Y619642D01*
X1561650Y619433D01*
X1561358Y619308D01*
X1560317D01*
G01X1561358D02*
X1561983Y618100D01*
G01X1563333Y618475D02*
X1563583Y618267D01*
X1563875Y618142D01*
X1564250Y618100D01*
X1564625Y618183D01*
X1564917Y618350D01*
X1565125Y618642D01*
X1565167Y618975D01*
X1565083Y619308D01*
X1564875Y619517D01*
X1564583Y619683D01*
X1564292Y619725D01*
X1564000Y619683D01*
X1563625Y619517D01*
X1563750Y620600D01*
X1564875D01*
G01X1566433Y618600D02*
X1566683Y618308D01*
X1567017Y618142D01*
X1567392Y618100D01*
X1567725Y618142D01*
X1568058Y618350D01*
X1568267Y618600D01*
X1568308Y618850D01*
X1568225Y619142D01*
X1567933Y619350D01*
X1567642Y619433D01*
X1567267D01*
G01X1567642D02*
X1567892Y619558D01*
X1568100Y619767D01*
X1568183Y620017D01*
X1568100Y620267D01*
X1567892Y620475D01*
X1567517Y620600D01*
X1567142Y620558D01*
X1566767Y620392D01*
G01X1570450Y618100D02*
Y620600D01*
X1569950Y620100D01*
G01Y618100D02*
X1570950D01*
G01X1570600Y616600D02*
Y608600D01*
X1553000D01*
Y616600D01*
X1570600D01*
G01X1552208Y643267D02*
X1552083Y643017D01*
X1552000Y642725D01*
Y642392D01*
X1552125Y642017D01*
X1552333Y641725D01*
X1552583Y641517D01*
X1553000Y641350D01*
X1553375Y641308D01*
X1553750Y641392D01*
X1554000Y641517D01*
X1554250Y641767D01*
X1554417Y642058D01*
X1554500Y642350D01*
Y642642D01*
X1554417Y642933D01*
X1554292Y643183D01*
X1554125Y643392D01*
G01X1552417Y644658D02*
X1552167Y644908D01*
X1552042Y645200D01*
X1552000Y645533D01*
X1552083Y645950D01*
X1552292Y646242D01*
X1552542Y646325D01*
X1552792Y646283D01*
X1553000Y646117D01*
X1553417Y645283D01*
X1553708Y644908D01*
X1554125Y644658D01*
X1554500Y644575D01*
Y646325D01*
G01X1554208Y647842D02*
X1554417Y648133D01*
X1554500Y648467D01*
X1554417Y648800D01*
X1554167Y649092D01*
X1553792Y649300D01*
X1553417Y649383D01*
X1552958D01*
X1552583Y649300D01*
X1552250Y649092D01*
X1552083Y648842D01*
X1552000Y648550D01*
X1552083Y648217D01*
X1552250Y647967D01*
X1552500Y647800D01*
X1552833Y647717D01*
X1553125Y647800D01*
X1553417Y648008D01*
X1553583Y648258D01*
X1553625Y648550D01*
X1553542Y648883D01*
X1553333Y649133D01*
X1552958Y649383D01*
G01X1554500Y652150D02*
X1552000D01*
X1553792Y650608D01*
Y652692D01*
G01X1560208Y643267D02*
X1560083Y643017D01*
X1560000Y642725D01*
Y642392D01*
X1560125Y642017D01*
X1560333Y641725D01*
X1560583Y641517D01*
X1561000Y641350D01*
X1561375Y641308D01*
X1561750Y641392D01*
X1562000Y641517D01*
X1562250Y641767D01*
X1562417Y642058D01*
X1562500Y642350D01*
Y642642D01*
X1562417Y642933D01*
X1562292Y643183D01*
X1562125Y643392D01*
G01X1560417Y644658D02*
X1560167Y644908D01*
X1560042Y645200D01*
X1560000Y645533D01*
X1560083Y645950D01*
X1560292Y646242D01*
X1560542Y646325D01*
X1560792Y646283D01*
X1561000Y646117D01*
X1561417Y645283D01*
X1561708Y644908D01*
X1562125Y644658D01*
X1562500Y644575D01*
Y646325D01*
G01X1562208Y647842D02*
X1562417Y648133D01*
X1562500Y648467D01*
X1562417Y648800D01*
X1562167Y649092D01*
X1561792Y649300D01*
X1561417Y649383D01*
X1560958D01*
X1560583Y649300D01*
X1560250Y649092D01*
X1560083Y648842D01*
X1560000Y648550D01*
X1560083Y648217D01*
X1560250Y647967D01*
X1560500Y647800D01*
X1560833Y647717D01*
X1561125Y647800D01*
X1561417Y648008D01*
X1561583Y648258D01*
X1561625Y648550D01*
X1561542Y648883D01*
X1561333Y649133D01*
X1560958Y649383D01*
G01X1562125Y650733D02*
X1562333Y650983D01*
X1562458Y651275D01*
X1562500Y651650D01*
X1562417Y652025D01*
X1562250Y652317D01*
X1561958Y652525D01*
X1561625Y652567D01*
X1561292Y652483D01*
X1561083Y652275D01*
X1560917Y651983D01*
X1560875Y651692D01*
X1560917Y651400D01*
X1561083Y651025D01*
X1560000Y651150D01*
Y652275D01*
G01X1606467Y721000D02*
Y718500D01*
X1608133D01*
G01X1611233D02*
X1609567D01*
Y721000D01*
X1611233D01*
G01X1610567Y719792D02*
X1609567D01*
G01X1612583Y718500D02*
Y721000D01*
X1613417D01*
X1613750Y720875D01*
X1614000Y720708D01*
X1614208Y720458D01*
X1614375Y720167D01*
X1614417Y719750D01*
X1614375Y719333D01*
X1614208Y719042D01*
X1614000Y718792D01*
X1613750Y718625D01*
X1613417Y718500D01*
X1612583D01*
G01X1616600D02*
Y721000D01*
X1616100Y720500D01*
G01Y718500D02*
X1617100D01*
G01X1619700Y721000D02*
X1619367Y720917D01*
X1619117Y720708D01*
X1618950Y720458D01*
X1618825Y720125D01*
X1618783Y719750D01*
X1618825Y719375D01*
X1618950Y719042D01*
X1619117Y718792D01*
X1619367Y718583D01*
X1619700Y718500D01*
X1620033Y718583D01*
X1620283Y718792D01*
X1620450Y719042D01*
X1620575Y719375D01*
X1620617Y719750D01*
X1620575Y720125D01*
X1620450Y720458D01*
X1620283Y720708D01*
X1620033Y720917D01*
X1619700Y721000D01*
G01X1608986Y704636D02*
Y715836D01*
X1617786D01*
Y704636D01*
X1608986D01*
G01X1571517Y834500D02*
Y837000D01*
X1572558D01*
X1572892Y836875D01*
X1573100Y836708D01*
X1573183Y836375D01*
X1573100Y836042D01*
X1572850Y835833D01*
X1572558Y835708D01*
X1571517D01*
G01X1572558D02*
X1573183Y834500D01*
G01X1574658Y836583D02*
X1574908Y836833D01*
X1575200Y836958D01*
X1575533Y837000D01*
X1575950Y836917D01*
X1576242Y836708D01*
X1576325Y836458D01*
X1576283Y836208D01*
X1576117Y836000D01*
X1575283Y835583D01*
X1574908Y835292D01*
X1574658Y834875D01*
X1574575Y834500D01*
X1576325D01*
G01X1577842Y834792D02*
X1578133Y834583D01*
X1578467Y834500D01*
X1578800Y834583D01*
X1579092Y834833D01*
X1579300Y835208D01*
X1579383Y835583D01*
Y836042D01*
X1579300Y836417D01*
X1579092Y836750D01*
X1578842Y836917D01*
X1578550Y837000D01*
X1578217Y836917D01*
X1577967Y836750D01*
X1577800Y836500D01*
X1577717Y836167D01*
X1577800Y835875D01*
X1578008Y835583D01*
X1578258Y835417D01*
X1578550Y835375D01*
X1578883Y835458D01*
X1579133Y835667D01*
X1579383Y836042D01*
G01X1580733Y835000D02*
X1580983Y834708D01*
X1581317Y834542D01*
X1581692Y834500D01*
X1582025Y834542D01*
X1582358Y834750D01*
X1582567Y835000D01*
X1582608Y835250D01*
X1582525Y835542D01*
X1582233Y835750D01*
X1581942Y835833D01*
X1581567D01*
G01X1581942D02*
X1582192Y835958D01*
X1582400Y836167D01*
X1582483Y836417D01*
X1582400Y836667D01*
X1582192Y836875D01*
X1581817Y837000D01*
X1581442Y836958D01*
X1581067Y836792D01*
G01X1591699Y834182D02*
Y838182D01*
X1584299D01*
G01X1606432Y853959D02*
Y857959D01*
X1599032D01*
G01X1612100Y852717D02*
X1609600D01*
Y853758D01*
X1609725Y854092D01*
X1609892Y854300D01*
X1610225Y854383D01*
X1610558Y854300D01*
X1610767Y854050D01*
X1610892Y853758D01*
Y852717D01*
G01Y853758D02*
X1612100Y854383D01*
G01X1611600Y855733D02*
X1611892Y855983D01*
X1612058Y856317D01*
X1612100Y856692D01*
X1612058Y857025D01*
X1611850Y857358D01*
X1611600Y857567D01*
X1611350Y857608D01*
X1611058Y857525D01*
X1610850Y857233D01*
X1610767Y856942D01*
Y856567D01*
G01Y856942D02*
X1610642Y857192D01*
X1610433Y857400D01*
X1610183Y857483D01*
X1609933Y857400D01*
X1609725Y857192D01*
X1609600Y856817D01*
X1609642Y856442D01*
X1609808Y856067D01*
G01X1612100Y860250D02*
X1609600D01*
X1611392Y858708D01*
Y860792D01*
G01X1612100Y862850D02*
X1612058Y863142D01*
X1611933Y863475D01*
X1611725Y863683D01*
X1611433Y863767D01*
X1611142Y863683D01*
X1610892Y863433D01*
X1610767Y863058D01*
Y862642D01*
X1610683Y862392D01*
X1610475Y862183D01*
X1610183Y862100D01*
X1609892Y862225D01*
X1609683Y862517D01*
X1609600Y862850D01*
X1609683Y863183D01*
X1609892Y863475D01*
X1610183Y863600D01*
X1610475Y863517D01*
X1610683Y863308D01*
X1610767Y863058D01*
Y862642D01*
X1610892Y862267D01*
X1611142Y862017D01*
X1611433Y861933D01*
X1611725Y862017D01*
X1611933Y862225D01*
X1612058Y862558D01*
X1612100Y862850D01*
G01X1616100Y852717D02*
X1613600D01*
Y853758D01*
X1613725Y854092D01*
X1613892Y854300D01*
X1614225Y854383D01*
X1614558Y854300D01*
X1614767Y854050D01*
X1614892Y853758D01*
Y852717D01*
G01Y853758D02*
X1616100Y854383D01*
G01X1615600Y855733D02*
X1615892Y855983D01*
X1616058Y856317D01*
X1616100Y856692D01*
X1616058Y857025D01*
X1615850Y857358D01*
X1615600Y857567D01*
X1615350Y857608D01*
X1615058Y857525D01*
X1614850Y857233D01*
X1614767Y856942D01*
Y856567D01*
G01Y856942D02*
X1614642Y857192D01*
X1614433Y857400D01*
X1614183Y857483D01*
X1613933Y857400D01*
X1613725Y857192D01*
X1613600Y856817D01*
X1613642Y856442D01*
X1613808Y856067D01*
G01X1616100Y860250D02*
X1613600D01*
X1615392Y858708D01*
Y860792D01*
G01X1615808Y862142D02*
X1616017Y862433D01*
X1616100Y862767D01*
X1616017Y863100D01*
X1615767Y863392D01*
X1615392Y863600D01*
X1615017Y863683D01*
X1614558D01*
X1614183Y863600D01*
X1613850Y863392D01*
X1613683Y863142D01*
X1613600Y862850D01*
X1613683Y862517D01*
X1613850Y862267D01*
X1614100Y862100D01*
X1614433Y862017D01*
X1614725Y862100D01*
X1615017Y862308D01*
X1615183Y862558D01*
X1615225Y862850D01*
X1615142Y863183D01*
X1614933Y863433D01*
X1614558Y863683D01*
G01X1597850Y834500D02*
X1597517Y834542D01*
X1597225Y834708D01*
X1596975Y834958D01*
X1596808Y835250D01*
X1596725Y835583D01*
Y835917D01*
X1596808Y836250D01*
X1596975Y836542D01*
X1597225Y836792D01*
X1597517Y836958D01*
X1597850Y837000D01*
X1598183Y836958D01*
X1598475Y836792D01*
X1598725Y836542D01*
X1598892Y836250D01*
X1598975Y835917D01*
Y835583D01*
X1598892Y835250D01*
X1598725Y834958D01*
X1598475Y834708D01*
X1598183Y834542D01*
X1597850Y834500D01*
G01X1598183Y835167D02*
X1598683Y834500D01*
G01X1600158Y836583D02*
X1600408Y836833D01*
X1600700Y836958D01*
X1601033Y837000D01*
X1601450Y836917D01*
X1601742Y836708D01*
X1601825Y836458D01*
X1601783Y836208D01*
X1601617Y836000D01*
X1600783Y835583D01*
X1600408Y835292D01*
X1600158Y834875D01*
X1600075Y834500D01*
X1601825D01*
G01X1603258Y836583D02*
X1603508Y836833D01*
X1603800Y836958D01*
X1604133Y837000D01*
X1604550Y836917D01*
X1604842Y836708D01*
X1604925Y836458D01*
X1604883Y836208D01*
X1604717Y836000D01*
X1603883Y835583D01*
X1603508Y835292D01*
X1603258Y834875D01*
X1603175Y834500D01*
X1604925D01*
G01X1607150D02*
X1607442Y834542D01*
X1607775Y834667D01*
X1607983Y834875D01*
X1608067Y835167D01*
X1607983Y835458D01*
X1607733Y835708D01*
X1607358Y835833D01*
X1606942D01*
X1606692Y835917D01*
X1606483Y836125D01*
X1606400Y836417D01*
X1606525Y836708D01*
X1606817Y836917D01*
X1607150Y837000D01*
X1607483Y836917D01*
X1607775Y836708D01*
X1607900Y836417D01*
X1607817Y836125D01*
X1607608Y835917D01*
X1607358Y835833D01*
X1606942D01*
X1606567Y835708D01*
X1606317Y835458D01*
X1606233Y835167D01*
X1606317Y834875D01*
X1606525Y834667D01*
X1606858Y834542D01*
X1607150Y834500D01*
G01X1607107Y838500D02*
Y852500D01*
G01X1594107Y838500D02*
X1607107D01*
G01X1594107Y852500D02*
Y838500D01*
G01X1607107Y852500D02*
X1594107D01*
G01X1581650Y855100D02*
X1581317Y855142D01*
X1581025Y855308D01*
X1580775Y855558D01*
X1580608Y855850D01*
X1580525Y856183D01*
Y856517D01*
X1580608Y856850D01*
X1580775Y857142D01*
X1581025Y857392D01*
X1581317Y857558D01*
X1581650Y857600D01*
X1581983Y857558D01*
X1582275Y857392D01*
X1582525Y857142D01*
X1582692Y856850D01*
X1582775Y856517D01*
Y856183D01*
X1582692Y855850D01*
X1582525Y855558D01*
X1582275Y855308D01*
X1581983Y855142D01*
X1581650Y855100D01*
G01X1581983Y855767D02*
X1582483Y855100D01*
G01X1583958Y857183D02*
X1584208Y857433D01*
X1584500Y857558D01*
X1584833Y857600D01*
X1585250Y857517D01*
X1585542Y857308D01*
X1585625Y857058D01*
X1585583Y856808D01*
X1585417Y856600D01*
X1584583Y856183D01*
X1584208Y855892D01*
X1583958Y855475D01*
X1583875Y855100D01*
X1585625D01*
G01X1586933Y855475D02*
X1587183Y855267D01*
X1587475Y855142D01*
X1587850Y855100D01*
X1588225Y855183D01*
X1588517Y855350D01*
X1588725Y855642D01*
X1588767Y855975D01*
X1588683Y856308D01*
X1588475Y856517D01*
X1588183Y856683D01*
X1587892Y856725D01*
X1587600Y856683D01*
X1587225Y856517D01*
X1587350Y857600D01*
X1588475D01*
G01X1590158Y857183D02*
X1590408Y857433D01*
X1590700Y857558D01*
X1591033Y857600D01*
X1591450Y857517D01*
X1591742Y857308D01*
X1591825Y857058D01*
X1591783Y856808D01*
X1591617Y856600D01*
X1590783Y856183D01*
X1590408Y855892D01*
X1590158Y855475D01*
X1590075Y855100D01*
X1591825D01*
G01X1578999Y839407D02*
X1592999D01*
G01X1578999Y852407D02*
Y839407D01*
G01X1592999Y852407D02*
X1578999D01*
G01X1592999Y839407D02*
Y852407D01*
G01X1553000Y951517D02*
X1550500D01*
Y952558D01*
X1550625Y952892D01*
X1550792Y953100D01*
X1551125Y953183D01*
X1551458Y953100D01*
X1551667Y952850D01*
X1551792Y952558D01*
Y951517D01*
G01Y952558D02*
X1553000Y953183D01*
G01X1550917Y954658D02*
X1550667Y954908D01*
X1550542Y955200D01*
X1550500Y955533D01*
X1550583Y955950D01*
X1550792Y956242D01*
X1551042Y956325D01*
X1551292Y956283D01*
X1551500Y956117D01*
X1551917Y955283D01*
X1552208Y954908D01*
X1552625Y954658D01*
X1553000Y954575D01*
Y956325D01*
G01X1552708Y957842D02*
X1552917Y958133D01*
X1553000Y958467D01*
X1552917Y958800D01*
X1552667Y959092D01*
X1552292Y959300D01*
X1551917Y959383D01*
X1551458D01*
X1551083Y959300D01*
X1550750Y959092D01*
X1550583Y958842D01*
X1550500Y958550D01*
X1550583Y958217D01*
X1550750Y957967D01*
X1551000Y957800D01*
X1551333Y957717D01*
X1551625Y957800D01*
X1551917Y958008D01*
X1552083Y958258D01*
X1552125Y958550D01*
X1552042Y958883D01*
X1551833Y959133D01*
X1551458Y959383D01*
G01X1550917Y960858D02*
X1550667Y961108D01*
X1550542Y961400D01*
X1550500Y961733D01*
X1550583Y962150D01*
X1550792Y962442D01*
X1551042Y962525D01*
X1551292Y962483D01*
X1551500Y962317D01*
X1551917Y961483D01*
X1552208Y961108D01*
X1552625Y960858D01*
X1553000Y960775D01*
Y962525D01*
G01X1578000Y951517D02*
X1575500D01*
Y952558D01*
X1575625Y952892D01*
X1575792Y953100D01*
X1576125Y953183D01*
X1576458Y953100D01*
X1576667Y952850D01*
X1576792Y952558D01*
Y951517D01*
G01Y952558D02*
X1578000Y953183D01*
G01X1575917Y954658D02*
X1575667Y954908D01*
X1575542Y955200D01*
X1575500Y955533D01*
X1575583Y955950D01*
X1575792Y956242D01*
X1576042Y956325D01*
X1576292Y956283D01*
X1576500Y956117D01*
X1576917Y955283D01*
X1577208Y954908D01*
X1577625Y954658D01*
X1578000Y954575D01*
Y956325D01*
G01X1577708Y957842D02*
X1577917Y958133D01*
X1578000Y958467D01*
X1577917Y958800D01*
X1577667Y959092D01*
X1577292Y959300D01*
X1576917Y959383D01*
X1576458D01*
X1576083Y959300D01*
X1575750Y959092D01*
X1575583Y958842D01*
X1575500Y958550D01*
X1575583Y958217D01*
X1575750Y957967D01*
X1576000Y957800D01*
X1576333Y957717D01*
X1576625Y957800D01*
X1576917Y958008D01*
X1577083Y958258D01*
X1577125Y958550D01*
X1577042Y958883D01*
X1576833Y959133D01*
X1576458Y959383D01*
G01X1578000Y962150D02*
X1575500D01*
X1577292Y960608D01*
Y962692D01*
G01X1549000Y951517D02*
X1546500D01*
Y952558D01*
X1546625Y952892D01*
X1546792Y953100D01*
X1547125Y953183D01*
X1547458Y953100D01*
X1547667Y952850D01*
X1547792Y952558D01*
Y951517D01*
G01Y952558D02*
X1549000Y953183D01*
G01X1546917Y954658D02*
X1546667Y954908D01*
X1546542Y955200D01*
X1546500Y955533D01*
X1546583Y955950D01*
X1546792Y956242D01*
X1547042Y956325D01*
X1547292Y956283D01*
X1547500Y956117D01*
X1547917Y955283D01*
X1548208Y954908D01*
X1548625Y954658D01*
X1549000Y954575D01*
Y956325D01*
G01X1548708Y957842D02*
X1548917Y958133D01*
X1549000Y958467D01*
X1548917Y958800D01*
X1548667Y959092D01*
X1548292Y959300D01*
X1547917Y959383D01*
X1547458D01*
X1547083Y959300D01*
X1546750Y959092D01*
X1546583Y958842D01*
X1546500Y958550D01*
X1546583Y958217D01*
X1546750Y957967D01*
X1547000Y957800D01*
X1547333Y957717D01*
X1547625Y957800D01*
X1547917Y958008D01*
X1548083Y958258D01*
X1548125Y958550D01*
X1548042Y958883D01*
X1547833Y959133D01*
X1547458Y959383D01*
G01X1548625Y960733D02*
X1548833Y960983D01*
X1548958Y961275D01*
X1549000Y961650D01*
X1548917Y962025D01*
X1548750Y962317D01*
X1548458Y962525D01*
X1548125Y962567D01*
X1547792Y962483D01*
X1547583Y962275D01*
X1547417Y961983D01*
X1547375Y961692D01*
X1547417Y961400D01*
X1547583Y961025D01*
X1546500Y961150D01*
Y962275D01*
G01X1596517Y860000D02*
Y862500D01*
X1597558D01*
X1597892Y862375D01*
X1598100Y862208D01*
X1598183Y861875D01*
X1598100Y861542D01*
X1597850Y861333D01*
X1597558Y861208D01*
X1596517D01*
G01X1597558D02*
X1598183Y860000D01*
G01X1599658Y862083D02*
X1599908Y862333D01*
X1600200Y862458D01*
X1600533Y862500D01*
X1600950Y862417D01*
X1601242Y862208D01*
X1601325Y861958D01*
X1601283Y861708D01*
X1601117Y861500D01*
X1600283Y861083D01*
X1599908Y860792D01*
X1599658Y860375D01*
X1599575Y860000D01*
X1601325D01*
G01X1602842Y860292D02*
X1603133Y860083D01*
X1603467Y860000D01*
X1603800Y860083D01*
X1604092Y860333D01*
X1604300Y860708D01*
X1604383Y861083D01*
Y861542D01*
X1604300Y861917D01*
X1604092Y862250D01*
X1603842Y862417D01*
X1603550Y862500D01*
X1603217Y862417D01*
X1602967Y862250D01*
X1602800Y862000D01*
X1602717Y861667D01*
X1602800Y861375D01*
X1603008Y861083D01*
X1603258Y860917D01*
X1603550Y860875D01*
X1603883Y860958D01*
X1604133Y861167D01*
X1604383Y861542D01*
G01X1606650Y862500D02*
X1606317Y862417D01*
X1606067Y862208D01*
X1605900Y861958D01*
X1605775Y861625D01*
X1605733Y861250D01*
X1605775Y860875D01*
X1605900Y860542D01*
X1606067Y860292D01*
X1606317Y860083D01*
X1606650Y860000D01*
X1606983Y860083D01*
X1607233Y860292D01*
X1607400Y860542D01*
X1607525Y860875D01*
X1607567Y861250D01*
X1607525Y861625D01*
X1607400Y861958D01*
X1607233Y862208D01*
X1606983Y862417D01*
X1606650Y862500D01*
G01X1544708Y990267D02*
X1544583Y990017D01*
X1544500Y989725D01*
Y989392D01*
X1544625Y989017D01*
X1544833Y988725D01*
X1545083Y988517D01*
X1545500Y988350D01*
X1545875Y988308D01*
X1546250Y988392D01*
X1546500Y988517D01*
X1546750Y988767D01*
X1546917Y989058D01*
X1547000Y989350D01*
Y989642D01*
X1546917Y989933D01*
X1546792Y990183D01*
X1546625Y990392D01*
G01X1547000Y992450D02*
X1544500D01*
X1545000Y991950D01*
G01X1547000D02*
Y992950D01*
G01Y996050D02*
X1544500D01*
X1546292Y994508D01*
Y996592D01*
G01X1544917Y997858D02*
X1544667Y998108D01*
X1544542Y998400D01*
X1544500Y998733D01*
X1544583Y999150D01*
X1544792Y999442D01*
X1545042Y999525D01*
X1545292Y999483D01*
X1545500Y999317D01*
X1545917Y998483D01*
X1546208Y998108D01*
X1546625Y997858D01*
X1547000Y997775D01*
Y999525D01*
G01X1589267Y1020292D02*
X1589017Y1020417D01*
X1588725Y1020500D01*
X1588392D01*
X1588017Y1020375D01*
X1587725Y1020167D01*
X1587517Y1019917D01*
X1587350Y1019500D01*
X1587308Y1019125D01*
X1587392Y1018750D01*
X1587517Y1018500D01*
X1587767Y1018250D01*
X1588058Y1018083D01*
X1588350Y1018000D01*
X1588642D01*
X1588933Y1018083D01*
X1589183Y1018208D01*
X1589392Y1018375D01*
G01X1591450Y1018000D02*
Y1020500D01*
X1590950Y1020000D01*
G01Y1018000D02*
X1591950D01*
G01X1595050D02*
Y1020500D01*
X1593508Y1018708D01*
X1595592D01*
G01X1596733Y1018500D02*
X1596983Y1018208D01*
X1597317Y1018042D01*
X1597692Y1018000D01*
X1598025Y1018042D01*
X1598358Y1018250D01*
X1598567Y1018500D01*
X1598608Y1018750D01*
X1598525Y1019042D01*
X1598233Y1019250D01*
X1597942Y1019333D01*
X1597567D01*
G01X1597942D02*
X1598192Y1019458D01*
X1598400Y1019667D01*
X1598483Y1019917D01*
X1598400Y1020167D01*
X1598192Y1020375D01*
X1597817Y1020500D01*
X1597442Y1020458D01*
X1597067Y1020292D01*
G01X1547000Y975517D02*
X1544500D01*
Y976558D01*
X1544625Y976892D01*
X1544792Y977100D01*
X1545125Y977183D01*
X1545458Y977100D01*
X1545667Y976850D01*
X1545792Y976558D01*
Y975517D01*
G01Y976558D02*
X1547000Y977183D01*
G01X1544917Y978658D02*
X1544667Y978908D01*
X1544542Y979200D01*
X1544500Y979533D01*
X1544583Y979950D01*
X1544792Y980242D01*
X1545042Y980325D01*
X1545292Y980283D01*
X1545500Y980117D01*
X1545917Y979283D01*
X1546208Y978908D01*
X1546625Y978658D01*
X1547000Y978575D01*
Y980325D01*
G01X1546708Y981842D02*
X1546917Y982133D01*
X1547000Y982467D01*
X1546917Y982800D01*
X1546667Y983092D01*
X1546292Y983300D01*
X1545917Y983383D01*
X1545458D01*
X1545083Y983300D01*
X1544750Y983092D01*
X1544583Y982842D01*
X1544500Y982550D01*
X1544583Y982217D01*
X1544750Y981967D01*
X1545000Y981800D01*
X1545333Y981717D01*
X1545625Y981800D01*
X1545917Y982008D01*
X1546083Y982258D01*
X1546125Y982550D01*
X1546042Y982883D01*
X1545833Y983133D01*
X1545458Y983383D01*
G01X1547000Y985650D02*
X1544500D01*
X1545000Y985150D01*
G01X1547000D02*
Y986150D01*
G01X1550300Y984600D02*
Y980600D01*
X1557700D01*
G01X1558500Y955300D02*
X1562500D01*
Y962700D01*
G01X1568500Y955300D02*
X1572500D01*
Y962700D01*
G01X1558000D02*
X1554000D01*
Y955300D01*
G01X1586000Y963017D02*
X1583500D01*
Y964058D01*
X1583625Y964392D01*
X1583792Y964600D01*
X1584125Y964683D01*
X1584458Y964600D01*
X1584667Y964350D01*
X1584792Y964058D01*
Y963017D01*
G01Y964058D02*
X1586000Y964683D01*
G01X1583917Y966158D02*
X1583667Y966408D01*
X1583542Y966700D01*
X1583500Y967033D01*
X1583583Y967450D01*
X1583792Y967742D01*
X1584042Y967825D01*
X1584292Y967783D01*
X1584500Y967617D01*
X1584917Y966783D01*
X1585208Y966408D01*
X1585625Y966158D01*
X1586000Y966075D01*
Y967825D01*
G01X1585708Y969342D02*
X1585917Y969633D01*
X1586000Y969967D01*
X1585917Y970300D01*
X1585667Y970592D01*
X1585292Y970800D01*
X1584917Y970883D01*
X1584458D01*
X1584083Y970800D01*
X1583750Y970592D01*
X1583583Y970342D01*
X1583500Y970050D01*
X1583583Y969717D01*
X1583750Y969467D01*
X1584000Y969300D01*
X1584333Y969217D01*
X1584625Y969300D01*
X1584917Y969508D01*
X1585083Y969758D01*
X1585125Y970050D01*
X1585042Y970383D01*
X1584833Y970633D01*
X1584458Y970883D01*
G01X1584958Y972358D02*
X1584667Y972650D01*
X1584500Y972900D01*
X1584417Y973233D01*
X1584500Y973525D01*
X1584667Y973733D01*
X1584917Y973900D01*
X1585208Y973942D01*
X1585458Y973900D01*
X1585708Y973733D01*
X1585917Y973483D01*
X1586000Y973192D01*
X1585917Y972858D01*
X1585667Y972567D01*
X1585292Y972400D01*
X1584875Y972358D01*
X1584333Y972442D01*
X1584042Y972567D01*
X1583750Y972775D01*
X1583542Y973067D01*
X1583500Y973358D01*
X1583583Y973650D01*
X1583792Y973858D01*
G01X1573000Y967800D02*
X1577000D01*
Y975200D01*
G01X1587517Y1014000D02*
Y1016500D01*
X1588558D01*
X1588892Y1016375D01*
X1589100Y1016208D01*
X1589183Y1015875D01*
X1589100Y1015542D01*
X1588850Y1015333D01*
X1588558Y1015208D01*
X1587517D01*
G01X1588558D02*
X1589183Y1014000D01*
G01X1590658Y1016083D02*
X1590908Y1016333D01*
X1591200Y1016458D01*
X1591533Y1016500D01*
X1591950Y1016417D01*
X1592242Y1016208D01*
X1592325Y1015958D01*
X1592283Y1015708D01*
X1592117Y1015500D01*
X1591283Y1015083D01*
X1590908Y1014792D01*
X1590658Y1014375D01*
X1590575Y1014000D01*
X1592325D01*
G01X1593842Y1014292D02*
X1594133Y1014083D01*
X1594467Y1014000D01*
X1594800Y1014083D01*
X1595092Y1014333D01*
X1595300Y1014708D01*
X1595383Y1015083D01*
Y1015542D01*
X1595300Y1015917D01*
X1595092Y1016250D01*
X1594842Y1016417D01*
X1594550Y1016500D01*
X1594217Y1016417D01*
X1593967Y1016250D01*
X1593800Y1016000D01*
X1593717Y1015667D01*
X1593800Y1015375D01*
X1594008Y1015083D01*
X1594258Y1014917D01*
X1594550Y1014875D01*
X1594883Y1014958D01*
X1595133Y1015167D01*
X1595383Y1015542D01*
G01X1597567Y1014000D02*
X1597650Y1014542D01*
X1597775Y1015000D01*
X1597942Y1015417D01*
X1598150Y1015875D01*
X1598483Y1016500D01*
X1596817D01*
G01X1585700Y1013000D02*
Y1017000D01*
X1578300D01*
G01X1589517Y985000D02*
Y987500D01*
X1590558D01*
X1590892Y987375D01*
X1591100Y987208D01*
X1591183Y986875D01*
X1591100Y986542D01*
X1590850Y986333D01*
X1590558Y986208D01*
X1589517D01*
G01X1590558D02*
X1591183Y985000D01*
G01X1592658Y987083D02*
X1592908Y987333D01*
X1593200Y987458D01*
X1593533Y987500D01*
X1593950Y987417D01*
X1594242Y987208D01*
X1594325Y986958D01*
X1594283Y986708D01*
X1594117Y986500D01*
X1593283Y986083D01*
X1592908Y985792D01*
X1592658Y985375D01*
X1592575Y985000D01*
X1594325D01*
G01X1595842Y985292D02*
X1596133Y985083D01*
X1596467Y985000D01*
X1596800Y985083D01*
X1597092Y985333D01*
X1597300Y985708D01*
X1597383Y986083D01*
Y986542D01*
X1597300Y986917D01*
X1597092Y987250D01*
X1596842Y987417D01*
X1596550Y987500D01*
X1596217Y987417D01*
X1595967Y987250D01*
X1595800Y987000D01*
X1595717Y986667D01*
X1595800Y986375D01*
X1596008Y986083D01*
X1596258Y985917D01*
X1596550Y985875D01*
X1596883Y985958D01*
X1597133Y986167D01*
X1597383Y986542D01*
G01X1599650Y985000D02*
X1599942Y985042D01*
X1600275Y985167D01*
X1600483Y985375D01*
X1600567Y985667D01*
X1600483Y985958D01*
X1600233Y986208D01*
X1599858Y986333D01*
X1599442D01*
X1599192Y986417D01*
X1598983Y986625D01*
X1598900Y986917D01*
X1599025Y987208D01*
X1599317Y987417D01*
X1599650Y987500D01*
X1599983Y987417D01*
X1600275Y987208D01*
X1600400Y986917D01*
X1600317Y986625D01*
X1600108Y986417D01*
X1599858Y986333D01*
X1599442D01*
X1599067Y986208D01*
X1598817Y985958D01*
X1598733Y985667D01*
X1598817Y985375D01*
X1599025Y985167D01*
X1599358Y985042D01*
X1599650Y985000D01*
G01X1575800Y988000D02*
Y984000D01*
X1583200D01*
G01X1582000Y963017D02*
X1579500D01*
Y964058D01*
X1579625Y964392D01*
X1579792Y964600D01*
X1580125Y964683D01*
X1580458Y964600D01*
X1580667Y964350D01*
X1580792Y964058D01*
Y963017D01*
G01Y964058D02*
X1582000Y964683D01*
G01X1579917Y966158D02*
X1579667Y966408D01*
X1579542Y966700D01*
X1579500Y967033D01*
X1579583Y967450D01*
X1579792Y967742D01*
X1580042Y967825D01*
X1580292Y967783D01*
X1580500Y967617D01*
X1580917Y966783D01*
X1581208Y966408D01*
X1581625Y966158D01*
X1582000Y966075D01*
Y967825D01*
G01X1581708Y969342D02*
X1581917Y969633D01*
X1582000Y969967D01*
X1581917Y970300D01*
X1581667Y970592D01*
X1581292Y970800D01*
X1580917Y970883D01*
X1580458D01*
X1580083Y970800D01*
X1579750Y970592D01*
X1579583Y970342D01*
X1579500Y970050D01*
X1579583Y969717D01*
X1579750Y969467D01*
X1580000Y969300D01*
X1580333Y969217D01*
X1580625Y969300D01*
X1580917Y969508D01*
X1581083Y969758D01*
X1581125Y970050D01*
X1581042Y970383D01*
X1580833Y970633D01*
X1580458Y970883D01*
G01X1581708Y972442D02*
X1581917Y972733D01*
X1582000Y973067D01*
X1581917Y973400D01*
X1581667Y973692D01*
X1581292Y973900D01*
X1580917Y973983D01*
X1580458D01*
X1580083Y973900D01*
X1579750Y973692D01*
X1579583Y973442D01*
X1579500Y973150D01*
X1579583Y972817D01*
X1579750Y972567D01*
X1580000Y972400D01*
X1580333Y972317D01*
X1580625Y972400D01*
X1580917Y972608D01*
X1581083Y972858D01*
X1581125Y973150D01*
X1581042Y973483D01*
X1580833Y973733D01*
X1580458Y973983D01*
G01X1568500Y967800D02*
X1572500D01*
Y975200D01*
G01X1553900Y1012000D02*
X1553567Y1012042D01*
X1553275Y1012208D01*
X1553025Y1012458D01*
X1552858Y1012750D01*
X1552775Y1013083D01*
Y1013417D01*
X1552858Y1013750D01*
X1553025Y1014042D01*
X1553275Y1014292D01*
X1553567Y1014458D01*
X1553900Y1014500D01*
X1554233Y1014458D01*
X1554525Y1014292D01*
X1554775Y1014042D01*
X1554942Y1013750D01*
X1555025Y1013417D01*
Y1013083D01*
X1554942Y1012750D01*
X1554775Y1012458D01*
X1554525Y1012208D01*
X1554233Y1012042D01*
X1553900Y1012000D01*
G01X1554233Y1012667D02*
X1554733Y1012000D01*
G01X1556083Y1012500D02*
X1556333Y1012208D01*
X1556667Y1012042D01*
X1557042Y1012000D01*
X1557375Y1012042D01*
X1557708Y1012250D01*
X1557917Y1012500D01*
X1557958Y1012750D01*
X1557875Y1013042D01*
X1557583Y1013250D01*
X1557292Y1013333D01*
X1556917D01*
G01X1557292D02*
X1557542Y1013458D01*
X1557750Y1013667D01*
X1557833Y1013917D01*
X1557750Y1014167D01*
X1557542Y1014375D01*
X1557167Y1014500D01*
X1556792Y1014458D01*
X1556417Y1014292D01*
G01X1560100Y1014500D02*
X1559767Y1014417D01*
X1559517Y1014208D01*
X1559350Y1013958D01*
X1559225Y1013625D01*
X1559183Y1013250D01*
X1559225Y1012875D01*
X1559350Y1012542D01*
X1559517Y1012292D01*
X1559767Y1012083D01*
X1560100Y1012000D01*
X1560433Y1012083D01*
X1560683Y1012292D01*
X1560850Y1012542D01*
X1560975Y1012875D01*
X1561017Y1013250D01*
X1560975Y1013625D01*
X1560850Y1013958D01*
X1560683Y1014208D01*
X1560433Y1014417D01*
X1560100Y1014500D01*
G01X1569000Y1010200D02*
X1567200Y1008100D01*
X1565000Y1010200D01*
G01X1561400Y1010300D02*
Y991100D01*
X1572600D01*
Y1010300D01*
X1561400D01*
Y1009900D01*
G01X1563800Y1037500D02*
X1565900Y1035700D01*
X1563800Y1033500D01*
G01X1563700Y1029900D02*
X1582900D01*
Y1041100D01*
X1563700D01*
Y1029900D01*
X1564100D01*
G01X1627000Y1035517D02*
X1624500D01*
Y1036558D01*
X1624625Y1036892D01*
X1624792Y1037100D01*
X1625125Y1037183D01*
X1625458Y1037100D01*
X1625667Y1036850D01*
X1625792Y1036558D01*
Y1035517D01*
G01Y1036558D02*
X1627000Y1037183D01*
G01X1626500Y1038533D02*
X1626792Y1038783D01*
X1626958Y1039117D01*
X1627000Y1039492D01*
X1626958Y1039825D01*
X1626750Y1040158D01*
X1626500Y1040367D01*
X1626250Y1040408D01*
X1625958Y1040325D01*
X1625750Y1040033D01*
X1625667Y1039742D01*
Y1039367D01*
G01Y1039742D02*
X1625542Y1039992D01*
X1625333Y1040200D01*
X1625083Y1040283D01*
X1624833Y1040200D01*
X1624625Y1039992D01*
X1624500Y1039617D01*
X1624542Y1039242D01*
X1624708Y1038867D01*
G01X1624500Y1042550D02*
X1624583Y1042217D01*
X1624792Y1041967D01*
X1625042Y1041800D01*
X1625375Y1041675D01*
X1625750Y1041633D01*
X1626125Y1041675D01*
X1626458Y1041800D01*
X1626708Y1041967D01*
X1626917Y1042217D01*
X1627000Y1042550D01*
X1626917Y1042883D01*
X1626708Y1043133D01*
X1626458Y1043300D01*
X1626125Y1043425D01*
X1625750Y1043467D01*
X1625375Y1043425D01*
X1625042Y1043300D01*
X1624792Y1043133D01*
X1624583Y1042883D01*
X1624500Y1042550D01*
G01X1626625Y1044733D02*
X1626833Y1044983D01*
X1626958Y1045275D01*
X1627000Y1045650D01*
X1626917Y1046025D01*
X1626750Y1046317D01*
X1626458Y1046525D01*
X1626125Y1046567D01*
X1625792Y1046483D01*
X1625583Y1046275D01*
X1625417Y1045983D01*
X1625375Y1045692D01*
X1625417Y1045400D01*
X1625583Y1045025D01*
X1624500Y1045150D01*
Y1046275D01*
G01X1553000Y1041700D02*
Y1047200D01*
G01X1561000Y1041700D02*
X1553000D01*
G01X1561000Y1047200D02*
Y1041700D01*
G01X1587033Y977500D02*
Y980000D01*
X1587867D01*
X1588200Y979875D01*
X1588450Y979708D01*
X1588658Y979458D01*
X1588825Y979167D01*
X1588867Y978750D01*
X1588825Y978333D01*
X1588658Y978042D01*
X1588450Y977792D01*
X1588200Y977625D01*
X1587867Y977500D01*
X1587033D01*
G01X1591050D02*
X1591342Y977542D01*
X1591675Y977667D01*
X1591883Y977875D01*
X1591967Y978167D01*
X1591883Y978458D01*
X1591633Y978708D01*
X1591258Y978833D01*
X1590842D01*
X1590592Y978917D01*
X1590383Y979125D01*
X1590300Y979417D01*
X1590425Y979708D01*
X1590717Y979917D01*
X1591050Y980000D01*
X1591383Y979917D01*
X1591675Y979708D01*
X1591800Y979417D01*
X1591717Y979125D01*
X1591508Y978917D01*
X1591258Y978833D01*
X1590842D01*
X1590467Y978708D01*
X1590217Y978458D01*
X1590133Y978167D01*
X1590217Y977875D01*
X1590425Y977667D01*
X1590758Y977542D01*
X1591050Y977500D01*
G01X1585000Y976000D02*
X1568900D01*
G01X1585000Y983000D02*
Y976000D01*
G01X1568900Y983000D02*
X1585000D01*
G01X1568900Y976000D02*
Y983000D01*
G01X1547000Y966400D02*
X1546958Y966067D01*
X1546792Y965775D01*
X1546542Y965525D01*
X1546250Y965358D01*
X1545917Y965275D01*
X1545583D01*
X1545250Y965358D01*
X1544958Y965525D01*
X1544708Y965775D01*
X1544542Y966067D01*
X1544500Y966400D01*
X1544542Y966733D01*
X1544708Y967025D01*
X1544958Y967275D01*
X1545250Y967442D01*
X1545583Y967525D01*
X1545917D01*
X1546250Y967442D01*
X1546542Y967275D01*
X1546792Y967025D01*
X1546958Y966733D01*
X1547000Y966400D01*
G01X1546333Y966733D02*
X1547000Y967233D01*
G01X1546500Y968583D02*
X1546792Y968833D01*
X1546958Y969167D01*
X1547000Y969542D01*
X1546958Y969875D01*
X1546750Y970208D01*
X1546500Y970417D01*
X1546250Y970458D01*
X1545958Y970375D01*
X1545750Y970083D01*
X1545667Y969792D01*
Y969417D01*
G01Y969792D02*
X1545542Y970042D01*
X1545333Y970250D01*
X1545083Y970333D01*
X1544833Y970250D01*
X1544625Y970042D01*
X1544500Y969667D01*
X1544542Y969292D01*
X1544708Y968917D01*
G01X1547000Y972600D02*
X1544500D01*
X1545000Y972100D01*
G01X1547000D02*
Y973100D01*
G01X1549300Y975200D02*
Y963800D01*
G01X1562700Y975200D02*
X1549300D01*
G01X1562700Y963800D02*
Y975200D01*
G01X1549300Y963800D02*
X1562700D01*
G01X1548517Y1023500D02*
Y1026000D01*
X1549558D01*
X1549892Y1025875D01*
X1550100Y1025708D01*
X1550183Y1025375D01*
X1550100Y1025042D01*
X1549850Y1024833D01*
X1549558Y1024708D01*
X1548517D01*
G01X1549558D02*
X1550183Y1023500D01*
G01X1551658Y1025583D02*
X1551908Y1025833D01*
X1552200Y1025958D01*
X1552533Y1026000D01*
X1552950Y1025917D01*
X1553242Y1025708D01*
X1553325Y1025458D01*
X1553283Y1025208D01*
X1553117Y1025000D01*
X1552283Y1024583D01*
X1551908Y1024292D01*
X1551658Y1023875D01*
X1551575Y1023500D01*
X1553325D01*
G01X1555550D02*
X1555842Y1023542D01*
X1556175Y1023667D01*
X1556383Y1023875D01*
X1556467Y1024167D01*
X1556383Y1024458D01*
X1556133Y1024708D01*
X1555758Y1024833D01*
X1555342D01*
X1555092Y1024917D01*
X1554883Y1025125D01*
X1554800Y1025417D01*
X1554925Y1025708D01*
X1555217Y1025917D01*
X1555550Y1026000D01*
X1555883Y1025917D01*
X1556175Y1025708D01*
X1556300Y1025417D01*
X1556217Y1025125D01*
X1556008Y1024917D01*
X1555758Y1024833D01*
X1555342D01*
X1554967Y1024708D01*
X1554717Y1024458D01*
X1554633Y1024167D01*
X1554717Y1023875D01*
X1554925Y1023667D01*
X1555258Y1023542D01*
X1555550Y1023500D01*
G01X1557858Y1024542D02*
X1558150Y1024833D01*
X1558400Y1025000D01*
X1558733Y1025083D01*
X1559025Y1025000D01*
X1559233Y1024833D01*
X1559400Y1024583D01*
X1559442Y1024292D01*
X1559400Y1024042D01*
X1559233Y1023792D01*
X1558983Y1023583D01*
X1558692Y1023500D01*
X1558358Y1023583D01*
X1558067Y1023833D01*
X1557900Y1024208D01*
X1557858Y1024625D01*
X1557942Y1025167D01*
X1558067Y1025458D01*
X1558275Y1025750D01*
X1558567Y1025958D01*
X1558858Y1026000D01*
X1559150Y1025917D01*
X1559358Y1025708D01*
G01X1562300Y1035500D02*
Y1027500D01*
X1544700D01*
Y1035500D01*
X1562300D01*
G01X1545208Y1062767D02*
X1545083Y1062517D01*
X1545000Y1062225D01*
Y1061892D01*
X1545125Y1061517D01*
X1545333Y1061225D01*
X1545583Y1061017D01*
X1546000Y1060850D01*
X1546375Y1060808D01*
X1546750Y1060892D01*
X1547000Y1061017D01*
X1547250Y1061267D01*
X1547417Y1061558D01*
X1547500Y1061850D01*
Y1062142D01*
X1547417Y1062433D01*
X1547292Y1062683D01*
X1547125Y1062892D01*
G01X1547500Y1064950D02*
X1545000D01*
X1545500Y1064450D01*
G01X1547500D02*
Y1065450D01*
G01X1547000Y1067133D02*
X1547292Y1067383D01*
X1547458Y1067717D01*
X1547500Y1068092D01*
X1547458Y1068425D01*
X1547250Y1068758D01*
X1547000Y1068967D01*
X1546750Y1069008D01*
X1546458Y1068925D01*
X1546250Y1068633D01*
X1546167Y1068342D01*
Y1067967D01*
G01Y1068342D02*
X1546042Y1068592D01*
X1545833Y1068800D01*
X1545583Y1068883D01*
X1545333Y1068800D01*
X1545125Y1068592D01*
X1545000Y1068217D01*
X1545042Y1067842D01*
X1545208Y1067467D01*
G01X1547500Y1071650D02*
X1545000D01*
X1546792Y1070108D01*
Y1072192D01*
G01X1545708Y1094767D02*
X1545583Y1094517D01*
X1545500Y1094225D01*
Y1093892D01*
X1545625Y1093517D01*
X1545833Y1093225D01*
X1546083Y1093017D01*
X1546500Y1092850D01*
X1546875Y1092808D01*
X1547250Y1092892D01*
X1547500Y1093017D01*
X1547750Y1093267D01*
X1547917Y1093558D01*
X1548000Y1093850D01*
Y1094142D01*
X1547917Y1094433D01*
X1547792Y1094683D01*
X1547625Y1094892D01*
G01X1548000Y1096950D02*
X1545500D01*
X1546000Y1096450D01*
G01X1548000D02*
Y1097450D01*
G01Y1100550D02*
X1545500D01*
X1547292Y1099008D01*
Y1101092D01*
G01X1545500Y1103150D02*
X1545583Y1102817D01*
X1545792Y1102567D01*
X1546042Y1102400D01*
X1546375Y1102275D01*
X1546750Y1102233D01*
X1547125Y1102275D01*
X1547458Y1102400D01*
X1547708Y1102567D01*
X1547917Y1102817D01*
X1548000Y1103150D01*
X1547917Y1103483D01*
X1547708Y1103733D01*
X1547458Y1103900D01*
X1547125Y1104025D01*
X1546750Y1104067D01*
X1546375Y1104025D01*
X1546042Y1103900D01*
X1545792Y1103733D01*
X1545583Y1103483D01*
X1545500Y1103150D01*
G01X1625850Y1068500D02*
Y1066000D01*
G01X1624892Y1068500D02*
X1626808D01*
G01X1628117Y1066000D02*
Y1068500D01*
X1629117D01*
X1629450Y1068375D01*
X1629700Y1068083D01*
X1629783Y1067750D01*
X1629700Y1067417D01*
X1629492Y1067167D01*
X1629117Y1067042D01*
X1628117D01*
G01X1631258D02*
X1631550Y1067333D01*
X1631800Y1067500D01*
X1632133Y1067583D01*
X1632425Y1067500D01*
X1632633Y1067333D01*
X1632800Y1067083D01*
X1632842Y1066792D01*
X1632800Y1066542D01*
X1632633Y1066292D01*
X1632383Y1066083D01*
X1632092Y1066000D01*
X1631758Y1066083D01*
X1631467Y1066333D01*
X1631300Y1066708D01*
X1631258Y1067125D01*
X1631342Y1067667D01*
X1631467Y1067958D01*
X1631675Y1068250D01*
X1631967Y1068458D01*
X1632258Y1068500D01*
X1632550Y1068417D01*
X1632758Y1068208D01*
G01X1634358Y1067042D02*
X1634650Y1067333D01*
X1634900Y1067500D01*
X1635233Y1067583D01*
X1635525Y1067500D01*
X1635733Y1067333D01*
X1635900Y1067083D01*
X1635942Y1066792D01*
X1635900Y1066542D01*
X1635733Y1066292D01*
X1635483Y1066083D01*
X1635192Y1066000D01*
X1634858Y1066083D01*
X1634567Y1066333D01*
X1634400Y1066708D01*
X1634358Y1067125D01*
X1634442Y1067667D01*
X1634567Y1067958D01*
X1634775Y1068250D01*
X1635067Y1068458D01*
X1635358Y1068500D01*
X1635650Y1068417D01*
X1635858Y1068208D01*
G01X1577900Y1050500D02*
X1577567Y1050542D01*
X1577275Y1050708D01*
X1577025Y1050958D01*
X1576858Y1051250D01*
X1576775Y1051583D01*
Y1051917D01*
X1576858Y1052250D01*
X1577025Y1052542D01*
X1577275Y1052792D01*
X1577567Y1052958D01*
X1577900Y1053000D01*
X1578233Y1052958D01*
X1578525Y1052792D01*
X1578775Y1052542D01*
X1578942Y1052250D01*
X1579025Y1051917D01*
Y1051583D01*
X1578942Y1051250D01*
X1578775Y1050958D01*
X1578525Y1050708D01*
X1578233Y1050542D01*
X1577900Y1050500D01*
G01X1578233Y1051167D02*
X1578733Y1050500D01*
G01X1580083Y1051000D02*
X1580333Y1050708D01*
X1580667Y1050542D01*
X1581042Y1050500D01*
X1581375Y1050542D01*
X1581708Y1050750D01*
X1581917Y1051000D01*
X1581958Y1051250D01*
X1581875Y1051542D01*
X1581583Y1051750D01*
X1581292Y1051833D01*
X1580917D01*
G01X1581292D02*
X1581542Y1051958D01*
X1581750Y1052167D01*
X1581833Y1052417D01*
X1581750Y1052667D01*
X1581542Y1052875D01*
X1581167Y1053000D01*
X1580792Y1052958D01*
X1580417Y1052792D01*
G01X1583308Y1052583D02*
X1583558Y1052833D01*
X1583850Y1052958D01*
X1584183Y1053000D01*
X1584600Y1052917D01*
X1584892Y1052708D01*
X1584975Y1052458D01*
X1584933Y1052208D01*
X1584767Y1052000D01*
X1583933Y1051583D01*
X1583558Y1051292D01*
X1583308Y1050875D01*
X1583225Y1050500D01*
X1584975D01*
G01X1549708Y1061767D02*
X1549583Y1061517D01*
X1549500Y1061225D01*
Y1060892D01*
X1549625Y1060517D01*
X1549833Y1060225D01*
X1550083Y1060017D01*
X1550500Y1059850D01*
X1550875Y1059808D01*
X1551250Y1059892D01*
X1551500Y1060017D01*
X1551750Y1060267D01*
X1551917Y1060558D01*
X1552000Y1060850D01*
Y1061142D01*
X1551917Y1061433D01*
X1551792Y1061683D01*
X1551625Y1061892D01*
G01X1552000Y1063950D02*
X1549500D01*
X1550000Y1063450D01*
G01X1552000D02*
Y1064450D01*
G01X1551500Y1066133D02*
X1551792Y1066383D01*
X1551958Y1066717D01*
X1552000Y1067092D01*
X1551958Y1067425D01*
X1551750Y1067758D01*
X1551500Y1067967D01*
X1551250Y1068008D01*
X1550958Y1067925D01*
X1550750Y1067633D01*
X1550667Y1067342D01*
Y1066967D01*
G01Y1067342D02*
X1550542Y1067592D01*
X1550333Y1067800D01*
X1550083Y1067883D01*
X1549833Y1067800D01*
X1549625Y1067592D01*
X1549500Y1067217D01*
X1549542Y1066842D01*
X1549708Y1066467D01*
G01X1551625Y1069233D02*
X1551833Y1069483D01*
X1551958Y1069775D01*
X1552000Y1070150D01*
X1551917Y1070525D01*
X1551750Y1070817D01*
X1551458Y1071025D01*
X1551125Y1071067D01*
X1550792Y1070983D01*
X1550583Y1070775D01*
X1550417Y1070483D01*
X1550375Y1070192D01*
X1550417Y1069900D01*
X1550583Y1069525D01*
X1549500Y1069650D01*
Y1070775D01*
G01X1561000Y1059300D02*
Y1053800D01*
G01X1553000Y1059300D02*
X1561000D01*
G01X1553000Y1053800D02*
Y1059300D01*
G01X1559517Y1070500D02*
Y1073000D01*
X1560558D01*
X1560892Y1072875D01*
X1561100Y1072708D01*
X1561183Y1072375D01*
X1561100Y1072042D01*
X1560850Y1071833D01*
X1560558Y1071708D01*
X1559517D01*
G01X1560558D02*
X1561183Y1070500D01*
G01X1562658Y1072583D02*
X1562908Y1072833D01*
X1563200Y1072958D01*
X1563533Y1073000D01*
X1563950Y1072917D01*
X1564242Y1072708D01*
X1564325Y1072458D01*
X1564283Y1072208D01*
X1564117Y1072000D01*
X1563283Y1071583D01*
X1562908Y1071292D01*
X1562658Y1070875D01*
X1562575Y1070500D01*
X1564325D01*
G01X1566550D02*
X1566842Y1070542D01*
X1567175Y1070667D01*
X1567383Y1070875D01*
X1567467Y1071167D01*
X1567383Y1071458D01*
X1567133Y1071708D01*
X1566758Y1071833D01*
X1566342D01*
X1566092Y1071917D01*
X1565883Y1072125D01*
X1565800Y1072417D01*
X1565925Y1072708D01*
X1566217Y1072917D01*
X1566550Y1073000D01*
X1566883Y1072917D01*
X1567175Y1072708D01*
X1567300Y1072417D01*
X1567217Y1072125D01*
X1567008Y1071917D01*
X1566758Y1071833D01*
X1566342D01*
X1565967Y1071708D01*
X1565717Y1071458D01*
X1565633Y1071167D01*
X1565717Y1070875D01*
X1565925Y1070667D01*
X1566258Y1070542D01*
X1566550Y1070500D01*
G01X1569650D02*
X1569942Y1070542D01*
X1570275Y1070667D01*
X1570483Y1070875D01*
X1570567Y1071167D01*
X1570483Y1071458D01*
X1570233Y1071708D01*
X1569858Y1071833D01*
X1569442D01*
X1569192Y1071917D01*
X1568983Y1072125D01*
X1568900Y1072417D01*
X1569025Y1072708D01*
X1569317Y1072917D01*
X1569650Y1073000D01*
X1569983Y1072917D01*
X1570275Y1072708D01*
X1570400Y1072417D01*
X1570317Y1072125D01*
X1570108Y1071917D01*
X1569858Y1071833D01*
X1569442D01*
X1569067Y1071708D01*
X1568817Y1071458D01*
X1568733Y1071167D01*
X1568817Y1070875D01*
X1569025Y1070667D01*
X1569358Y1070542D01*
X1569650Y1070500D01*
G01X1570900Y1069500D02*
Y1061500D01*
X1553300D01*
Y1069500D01*
X1570900D01*
G01X1552708Y1094767D02*
X1552583Y1094517D01*
X1552500Y1094225D01*
Y1093892D01*
X1552625Y1093517D01*
X1552833Y1093225D01*
X1553083Y1093017D01*
X1553500Y1092850D01*
X1553875Y1092808D01*
X1554250Y1092892D01*
X1554500Y1093017D01*
X1554750Y1093267D01*
X1554917Y1093558D01*
X1555000Y1093850D01*
Y1094142D01*
X1554917Y1094433D01*
X1554792Y1094683D01*
X1554625Y1094892D01*
G01X1555000Y1096950D02*
X1552500D01*
X1553000Y1096450D01*
G01X1555000D02*
Y1097450D01*
G01X1554500Y1099133D02*
X1554792Y1099383D01*
X1554958Y1099717D01*
X1555000Y1100092D01*
X1554958Y1100425D01*
X1554750Y1100758D01*
X1554500Y1100967D01*
X1554250Y1101008D01*
X1553958Y1100925D01*
X1553750Y1100633D01*
X1553667Y1100342D01*
Y1099967D01*
G01Y1100342D02*
X1553542Y1100592D01*
X1553333Y1100800D01*
X1553083Y1100883D01*
X1552833Y1100800D01*
X1552625Y1100592D01*
X1552500Y1100217D01*
X1552542Y1099842D01*
X1552708Y1099467D01*
G01X1555000Y1103150D02*
X1554958Y1103442D01*
X1554833Y1103775D01*
X1554625Y1103983D01*
X1554333Y1104067D01*
X1554042Y1103983D01*
X1553792Y1103733D01*
X1553667Y1103358D01*
Y1102942D01*
X1553583Y1102692D01*
X1553375Y1102483D01*
X1553083Y1102400D01*
X1552792Y1102525D01*
X1552583Y1102817D01*
X1552500Y1103150D01*
X1552583Y1103483D01*
X1552792Y1103775D01*
X1553083Y1103900D01*
X1553375Y1103817D01*
X1553583Y1103608D01*
X1553667Y1103358D01*
Y1102942D01*
X1553792Y1102567D01*
X1554042Y1102317D01*
X1554333Y1102233D01*
X1554625Y1102317D01*
X1554833Y1102525D01*
X1554958Y1102858D01*
X1555000Y1103150D01*
G01X1560047Y1094767D02*
X1559922Y1094517D01*
X1559839Y1094225D01*
Y1093892D01*
X1559964Y1093517D01*
X1560172Y1093225D01*
X1560422Y1093017D01*
X1560839Y1092850D01*
X1561214Y1092808D01*
X1561589Y1092892D01*
X1561839Y1093017D01*
X1562089Y1093267D01*
X1562256Y1093558D01*
X1562339Y1093850D01*
Y1094142D01*
X1562256Y1094433D01*
X1562131Y1094683D01*
X1561964Y1094892D01*
G01X1562339Y1096950D02*
X1559839D01*
X1560339Y1096450D01*
G01X1562339D02*
Y1097450D01*
G01X1561839Y1099133D02*
X1562131Y1099383D01*
X1562297Y1099717D01*
X1562339Y1100092D01*
X1562297Y1100425D01*
X1562089Y1100758D01*
X1561839Y1100967D01*
X1561589Y1101008D01*
X1561297Y1100925D01*
X1561089Y1100633D01*
X1561006Y1100342D01*
Y1099967D01*
G01Y1100342D02*
X1560881Y1100592D01*
X1560672Y1100800D01*
X1560422Y1100883D01*
X1560172Y1100800D01*
X1559964Y1100592D01*
X1559839Y1100217D01*
X1559881Y1099842D01*
X1560047Y1099467D01*
G01X1562047Y1102442D02*
X1562256Y1102733D01*
X1562339Y1103067D01*
X1562256Y1103400D01*
X1562006Y1103692D01*
X1561631Y1103900D01*
X1561256Y1103983D01*
X1560797D01*
X1560422Y1103900D01*
X1560089Y1103692D01*
X1559922Y1103442D01*
X1559839Y1103150D01*
X1559922Y1102817D01*
X1560089Y1102567D01*
X1560339Y1102400D01*
X1560672Y1102317D01*
X1560964Y1102400D01*
X1561256Y1102608D01*
X1561422Y1102858D01*
X1561464Y1103150D01*
X1561381Y1103483D01*
X1561172Y1103733D01*
X1560797Y1103983D01*
G01X1627500Y1449517D02*
X1625000D01*
Y1450558D01*
X1625125Y1450892D01*
X1625292Y1451100D01*
X1625625Y1451183D01*
X1625958Y1451100D01*
X1626167Y1450850D01*
X1626292Y1450558D01*
Y1449517D01*
G01Y1450558D02*
X1627500Y1451183D01*
G01X1627208Y1452742D02*
X1627417Y1453033D01*
X1627500Y1453367D01*
X1627417Y1453700D01*
X1627167Y1453992D01*
X1626792Y1454200D01*
X1626417Y1454283D01*
X1625958D01*
X1625583Y1454200D01*
X1625250Y1453992D01*
X1625083Y1453742D01*
X1625000Y1453450D01*
X1625083Y1453117D01*
X1625250Y1452867D01*
X1625500Y1452700D01*
X1625833Y1452617D01*
X1626125Y1452700D01*
X1626417Y1452908D01*
X1626583Y1453158D01*
X1626625Y1453450D01*
X1626542Y1453783D01*
X1626333Y1454033D01*
X1625958Y1454283D01*
G01X1627125Y1455633D02*
X1627333Y1455883D01*
X1627458Y1456175D01*
X1627500Y1456550D01*
X1627417Y1456925D01*
X1627250Y1457217D01*
X1626958Y1457425D01*
X1626625Y1457467D01*
X1626292Y1457383D01*
X1626083Y1457175D01*
X1625917Y1456883D01*
X1625875Y1456592D01*
X1625917Y1456300D01*
X1626083Y1455925D01*
X1625000Y1456050D01*
Y1457175D01*
G01X1627125Y1458733D02*
X1627333Y1458983D01*
X1627458Y1459275D01*
X1627500Y1459650D01*
X1627417Y1460025D01*
X1627250Y1460317D01*
X1626958Y1460525D01*
X1626625Y1460567D01*
X1626292Y1460483D01*
X1626083Y1460275D01*
X1625917Y1459983D01*
X1625875Y1459692D01*
X1625917Y1459400D01*
X1626083Y1459025D01*
X1625000Y1459150D01*
Y1460275D01*
G01X1637431Y107319D02*
X1642481D01*
Y206019D01*
X1667131D01*
Y21619D01*
X1642481D01*
Y80319D01*
X1637431D01*
Y107319D01*
G01X1669708Y83767D02*
X1669583Y83517D01*
X1669500Y83225D01*
Y82892D01*
X1669625Y82517D01*
X1669833Y82225D01*
X1670083Y82017D01*
X1670500Y81850D01*
X1670875Y81808D01*
X1671250Y81892D01*
X1671500Y82017D01*
X1671750Y82267D01*
X1671917Y82558D01*
X1672000Y82850D01*
Y83142D01*
X1671917Y83433D01*
X1671792Y83683D01*
X1671625Y83892D01*
G01X1672000Y86450D02*
X1669500D01*
X1671292Y84908D01*
Y86992D01*
G01X1670958Y88258D02*
X1670667Y88550D01*
X1670500Y88800D01*
X1670417Y89133D01*
X1670500Y89425D01*
X1670667Y89633D01*
X1670917Y89800D01*
X1671208Y89842D01*
X1671458Y89800D01*
X1671708Y89633D01*
X1671917Y89383D01*
X1672000Y89092D01*
X1671917Y88758D01*
X1671667Y88467D01*
X1671292Y88300D01*
X1670875Y88258D01*
X1670333Y88342D01*
X1670042Y88467D01*
X1669750Y88675D01*
X1669542Y88967D01*
X1669500Y89258D01*
X1669583Y89550D01*
X1669792Y89758D01*
G01X1672000Y92067D02*
X1671458Y92150D01*
X1671000Y92275D01*
X1670583Y92442D01*
X1670125Y92650D01*
X1669500Y92983D01*
Y91317D01*
G01X1671500Y68517D02*
X1669000D01*
Y69558D01*
X1669125Y69892D01*
X1669292Y70100D01*
X1669625Y70183D01*
X1669958Y70100D01*
X1670167Y69850D01*
X1670292Y69558D01*
Y68517D01*
G01Y69558D02*
X1671500Y70183D01*
G01Y72450D02*
X1671458Y72742D01*
X1671333Y73075D01*
X1671125Y73283D01*
X1670833Y73367D01*
X1670542Y73283D01*
X1670292Y73033D01*
X1670167Y72658D01*
Y72242D01*
X1670083Y71992D01*
X1669875Y71783D01*
X1669583Y71700D01*
X1669292Y71825D01*
X1669083Y72117D01*
X1669000Y72450D01*
X1669083Y72783D01*
X1669292Y73075D01*
X1669583Y73200D01*
X1669875Y73117D01*
X1670083Y72908D01*
X1670167Y72658D01*
Y72242D01*
X1670292Y71867D01*
X1670542Y71617D01*
X1670833Y71533D01*
X1671125Y71617D01*
X1671333Y71825D01*
X1671458Y72158D01*
X1671500Y72450D01*
G01X1671000Y74633D02*
X1671292Y74883D01*
X1671458Y75217D01*
X1671500Y75592D01*
X1671458Y75925D01*
X1671250Y76258D01*
X1671000Y76467D01*
X1670750Y76508D01*
X1670458Y76425D01*
X1670250Y76133D01*
X1670167Y75842D01*
Y75467D01*
G01Y75842D02*
X1670042Y76092D01*
X1669833Y76300D01*
X1669583Y76383D01*
X1669333Y76300D01*
X1669125Y76092D01*
X1669000Y75717D01*
X1669042Y75342D01*
X1669208Y74967D01*
G01X1670458Y77858D02*
X1670167Y78150D01*
X1670000Y78400D01*
X1669917Y78733D01*
X1670000Y79025D01*
X1670167Y79233D01*
X1670417Y79400D01*
X1670708Y79442D01*
X1670958Y79400D01*
X1671208Y79233D01*
X1671417Y78983D01*
X1671500Y78692D01*
X1671417Y78358D01*
X1671167Y78067D01*
X1670792Y77900D01*
X1670375Y77858D01*
X1669833Y77942D01*
X1669542Y78067D01*
X1669250Y78275D01*
X1669042Y78567D01*
X1669000Y78858D01*
X1669083Y79150D01*
X1669292Y79358D01*
G01X1674200Y79000D02*
Y75000D01*
X1681600D01*
G01X1677000Y42017D02*
X1674500D01*
Y43058D01*
X1674625Y43392D01*
X1674792Y43600D01*
X1675125Y43683D01*
X1675458Y43600D01*
X1675667Y43350D01*
X1675792Y43058D01*
Y42017D01*
G01Y43058D02*
X1677000Y43683D01*
G01Y45950D02*
X1676958Y46242D01*
X1676833Y46575D01*
X1676625Y46783D01*
X1676333Y46867D01*
X1676042Y46783D01*
X1675792Y46533D01*
X1675667Y46158D01*
Y45742D01*
X1675583Y45492D01*
X1675375Y45283D01*
X1675083Y45200D01*
X1674792Y45325D01*
X1674583Y45617D01*
X1674500Y45950D01*
X1674583Y46283D01*
X1674792Y46575D01*
X1675083Y46700D01*
X1675375Y46617D01*
X1675583Y46408D01*
X1675667Y46158D01*
Y45742D01*
X1675792Y45367D01*
X1676042Y45117D01*
X1676333Y45033D01*
X1676625Y45117D01*
X1676833Y45325D01*
X1676958Y45658D01*
X1677000Y45950D01*
G01X1676500Y48133D02*
X1676792Y48383D01*
X1676958Y48717D01*
X1677000Y49092D01*
X1676958Y49425D01*
X1676750Y49758D01*
X1676500Y49967D01*
X1676250Y50008D01*
X1675958Y49925D01*
X1675750Y49633D01*
X1675667Y49342D01*
Y48967D01*
G01Y49342D02*
X1675542Y49592D01*
X1675333Y49800D01*
X1675083Y49883D01*
X1674833Y49800D01*
X1674625Y49592D01*
X1674500Y49217D01*
X1674542Y48842D01*
X1674708Y48467D01*
G01X1677000Y52067D02*
X1676458Y52150D01*
X1676000Y52275D01*
X1675583Y52442D01*
X1675125Y52650D01*
X1674500Y52983D01*
Y51317D01*
G01X1682500Y49800D02*
X1686500D01*
Y57200D01*
G01X1700500Y46517D02*
X1698000D01*
Y47558D01*
X1698125Y47892D01*
X1698292Y48100D01*
X1698625Y48183D01*
X1698958Y48100D01*
X1699167Y47850D01*
X1699292Y47558D01*
Y46517D01*
G01Y47558D02*
X1700500Y48183D01*
G01Y50450D02*
X1700458Y50742D01*
X1700333Y51075D01*
X1700125Y51283D01*
X1699833Y51367D01*
X1699542Y51283D01*
X1699292Y51033D01*
X1699167Y50658D01*
Y50242D01*
X1699083Y49992D01*
X1698875Y49783D01*
X1698583Y49700D01*
X1698292Y49825D01*
X1698083Y50117D01*
X1698000Y50450D01*
X1698083Y50783D01*
X1698292Y51075D01*
X1698583Y51200D01*
X1698875Y51117D01*
X1699083Y50908D01*
X1699167Y50658D01*
Y50242D01*
X1699292Y49867D01*
X1699542Y49617D01*
X1699833Y49533D01*
X1700125Y49617D01*
X1700333Y49825D01*
X1700458Y50158D01*
X1700500Y50450D01*
G01X1700000Y52633D02*
X1700292Y52883D01*
X1700458Y53217D01*
X1700500Y53592D01*
X1700458Y53925D01*
X1700250Y54258D01*
X1700000Y54467D01*
X1699750Y54508D01*
X1699458Y54425D01*
X1699250Y54133D01*
X1699167Y53842D01*
Y53467D01*
G01Y53842D02*
X1699042Y54092D01*
X1698833Y54300D01*
X1698583Y54383D01*
X1698333Y54300D01*
X1698125Y54092D01*
X1698000Y53717D01*
X1698042Y53342D01*
X1698208Y52967D01*
G01X1700208Y55942D02*
X1700417Y56233D01*
X1700500Y56567D01*
X1700417Y56900D01*
X1700167Y57192D01*
X1699792Y57400D01*
X1699417Y57483D01*
X1698958D01*
X1698583Y57400D01*
X1698250Y57192D01*
X1698083Y56942D01*
X1698000Y56650D01*
X1698083Y56317D01*
X1698250Y56067D01*
X1698500Y55900D01*
X1698833Y55817D01*
X1699125Y55900D01*
X1699417Y56108D01*
X1699583Y56358D01*
X1699625Y56650D01*
X1699542Y56983D01*
X1699333Y57233D01*
X1698958Y57483D01*
G01X1692500Y49800D02*
X1696500D01*
Y57200D01*
G01X1673000Y42017D02*
X1670500D01*
Y43058D01*
X1670625Y43392D01*
X1670792Y43600D01*
X1671125Y43683D01*
X1671458Y43600D01*
X1671667Y43350D01*
X1671792Y43058D01*
Y42017D01*
G01Y43058D02*
X1673000Y43683D01*
G01Y45950D02*
X1672958Y46242D01*
X1672833Y46575D01*
X1672625Y46783D01*
X1672333Y46867D01*
X1672042Y46783D01*
X1671792Y46533D01*
X1671667Y46158D01*
Y45742D01*
X1671583Y45492D01*
X1671375Y45283D01*
X1671083Y45200D01*
X1670792Y45325D01*
X1670583Y45617D01*
X1670500Y45950D01*
X1670583Y46283D01*
X1670792Y46575D01*
X1671083Y46700D01*
X1671375Y46617D01*
X1671583Y46408D01*
X1671667Y46158D01*
Y45742D01*
X1671792Y45367D01*
X1672042Y45117D01*
X1672333Y45033D01*
X1672625Y45117D01*
X1672833Y45325D01*
X1672958Y45658D01*
X1673000Y45950D01*
G01Y49550D02*
X1670500D01*
X1672292Y48008D01*
Y50092D01*
G01X1673000Y52150D02*
X1670500D01*
X1671000Y51650D01*
G01X1673000D02*
Y52650D01*
G01X1682000Y57200D02*
X1678000D01*
Y49800D01*
G01X1709000Y58017D02*
X1706500D01*
Y59058D01*
X1706625Y59392D01*
X1706792Y59600D01*
X1707125Y59683D01*
X1707458Y59600D01*
X1707667Y59350D01*
X1707792Y59058D01*
Y58017D01*
G01Y59058D02*
X1709000Y59683D01*
G01Y61950D02*
X1708958Y62242D01*
X1708833Y62575D01*
X1708625Y62783D01*
X1708333Y62867D01*
X1708042Y62783D01*
X1707792Y62533D01*
X1707667Y62158D01*
Y61742D01*
X1707583Y61492D01*
X1707375Y61283D01*
X1707083Y61200D01*
X1706792Y61325D01*
X1706583Y61617D01*
X1706500Y61950D01*
X1706583Y62283D01*
X1706792Y62575D01*
X1707083Y62700D01*
X1707375Y62617D01*
X1707583Y62408D01*
X1707667Y62158D01*
Y61742D01*
X1707792Y61367D01*
X1708042Y61117D01*
X1708333Y61033D01*
X1708625Y61117D01*
X1708833Y61325D01*
X1708958Y61658D01*
X1709000Y61950D01*
G01Y65550D02*
X1706500D01*
X1708292Y64008D01*
Y66092D01*
G01X1706917Y67358D02*
X1706667Y67608D01*
X1706542Y67900D01*
X1706500Y68233D01*
X1706583Y68650D01*
X1706792Y68942D01*
X1707042Y69025D01*
X1707292Y68983D01*
X1707500Y68817D01*
X1707917Y67983D01*
X1708208Y67608D01*
X1708625Y67358D01*
X1709000Y67275D01*
Y69025D01*
G01X1697000Y62300D02*
X1701000D01*
Y69700D01*
G01X1711517Y79500D02*
Y82000D01*
X1712558D01*
X1712892Y81875D01*
X1713100Y81708D01*
X1713183Y81375D01*
X1713100Y81042D01*
X1712850Y80833D01*
X1712558Y80708D01*
X1711517D01*
G01X1712558D02*
X1713183Y79500D01*
G01X1715450D02*
X1715742Y79542D01*
X1716075Y79667D01*
X1716283Y79875D01*
X1716367Y80167D01*
X1716283Y80458D01*
X1716033Y80708D01*
X1715658Y80833D01*
X1715242D01*
X1714992Y80917D01*
X1714783Y81125D01*
X1714700Y81417D01*
X1714825Y81708D01*
X1715117Y81917D01*
X1715450Y82000D01*
X1715783Y81917D01*
X1716075Y81708D01*
X1716200Y81417D01*
X1716117Y81125D01*
X1715908Y80917D01*
X1715658Y80833D01*
X1715242D01*
X1714867Y80708D01*
X1714617Y80458D01*
X1714533Y80167D01*
X1714617Y79875D01*
X1714825Y79667D01*
X1715158Y79542D01*
X1715450Y79500D01*
G01X1719050D02*
Y82000D01*
X1717508Y80208D01*
X1719592D01*
G01X1720733Y79875D02*
X1720983Y79667D01*
X1721275Y79542D01*
X1721650Y79500D01*
X1722025Y79583D01*
X1722317Y79750D01*
X1722525Y80042D01*
X1722567Y80375D01*
X1722483Y80708D01*
X1722275Y80917D01*
X1721983Y81083D01*
X1721692Y81125D01*
X1721400Y81083D01*
X1721025Y80917D01*
X1721150Y82000D01*
X1722275D01*
G01X1699800Y82500D02*
Y78500D01*
X1707200D01*
G01X1705000Y58017D02*
X1702500D01*
Y59058D01*
X1702625Y59392D01*
X1702792Y59600D01*
X1703125Y59683D01*
X1703458Y59600D01*
X1703667Y59350D01*
X1703792Y59058D01*
Y58017D01*
G01Y59058D02*
X1705000Y59683D01*
G01Y61950D02*
X1704958Y62242D01*
X1704833Y62575D01*
X1704625Y62783D01*
X1704333Y62867D01*
X1704042Y62783D01*
X1703792Y62533D01*
X1703667Y62158D01*
Y61742D01*
X1703583Y61492D01*
X1703375Y61283D01*
X1703083Y61200D01*
X1702792Y61325D01*
X1702583Y61617D01*
X1702500Y61950D01*
X1702583Y62283D01*
X1702792Y62575D01*
X1703083Y62700D01*
X1703375Y62617D01*
X1703583Y62408D01*
X1703667Y62158D01*
Y61742D01*
X1703792Y61367D01*
X1704042Y61117D01*
X1704333Y61033D01*
X1704625Y61117D01*
X1704833Y61325D01*
X1704958Y61658D01*
X1705000Y61950D01*
G01Y65550D02*
X1702500D01*
X1704292Y64008D01*
Y66092D01*
G01X1703958Y67358D02*
X1703667Y67650D01*
X1703500Y67900D01*
X1703417Y68233D01*
X1703500Y68525D01*
X1703667Y68733D01*
X1703917Y68900D01*
X1704208Y68942D01*
X1704458Y68900D01*
X1704708Y68733D01*
X1704917Y68483D01*
X1705000Y68192D01*
X1704917Y67858D01*
X1704667Y67567D01*
X1704292Y67400D01*
X1703875Y67358D01*
X1703333Y67442D01*
X1703042Y67567D01*
X1702750Y67775D01*
X1702542Y68067D01*
X1702500Y68358D01*
X1702583Y68650D01*
X1702792Y68858D01*
G01X1692500Y62300D02*
X1696500D01*
Y69700D01*
G01X1685400Y104800D02*
Y85600D01*
X1696600D01*
Y104800D01*
X1685400D01*
Y104400D01*
G01X1710983Y73000D02*
Y75500D01*
X1711817D01*
X1712150Y75375D01*
X1712400Y75208D01*
X1712608Y74958D01*
X1712775Y74667D01*
X1712817Y74250D01*
X1712775Y73833D01*
X1712608Y73542D01*
X1712400Y73292D01*
X1712150Y73125D01*
X1711817Y73000D01*
X1710983D01*
G01X1714083Y73500D02*
X1714333Y73208D01*
X1714667Y73042D01*
X1715042Y73000D01*
X1715375Y73042D01*
X1715708Y73250D01*
X1715917Y73500D01*
X1715958Y73750D01*
X1715875Y74042D01*
X1715583Y74250D01*
X1715292Y74333D01*
X1714917D01*
G01X1715292D02*
X1715542Y74458D01*
X1715750Y74667D01*
X1715833Y74917D01*
X1715750Y75167D01*
X1715542Y75375D01*
X1715167Y75500D01*
X1714792Y75458D01*
X1714417Y75292D01*
G01X1717183Y73500D02*
X1717433Y73208D01*
X1717767Y73042D01*
X1718142Y73000D01*
X1718475Y73042D01*
X1718808Y73250D01*
X1719017Y73500D01*
X1719058Y73750D01*
X1718975Y74042D01*
X1718683Y74250D01*
X1718392Y74333D01*
X1718017D01*
G01X1718392D02*
X1718642Y74458D01*
X1718850Y74667D01*
X1718933Y74917D01*
X1718850Y75167D01*
X1718642Y75375D01*
X1718267Y75500D01*
X1717892Y75458D01*
X1717517Y75292D01*
G01X1709000Y70500D02*
X1692900D01*
G01X1709000Y77500D02*
Y70500D01*
G01X1692900Y77500D02*
X1709000D01*
G01X1692900Y70500D02*
Y77500D01*
G01X1671500Y55850D02*
X1671458Y55517D01*
X1671292Y55225D01*
X1671042Y54975D01*
X1670750Y54808D01*
X1670417Y54725D01*
X1670083D01*
X1669750Y54808D01*
X1669458Y54975D01*
X1669208Y55225D01*
X1669042Y55517D01*
X1669000Y55850D01*
X1669042Y56183D01*
X1669208Y56475D01*
X1669458Y56725D01*
X1669750Y56892D01*
X1670083Y56975D01*
X1670417D01*
X1670750Y56892D01*
X1671042Y56725D01*
X1671292Y56475D01*
X1671458Y56183D01*
X1671500Y55850D01*
G01X1670833Y56183D02*
X1671500Y56683D01*
G01Y58950D02*
X1669000D01*
X1669500Y58450D01*
G01X1671500D02*
Y59450D01*
G01Y61967D02*
X1670958Y62050D01*
X1670500Y62175D01*
X1670083Y62342D01*
X1669625Y62550D01*
X1669000Y62883D01*
Y61217D01*
G01X1671000Y64233D02*
X1671292Y64483D01*
X1671458Y64817D01*
X1671500Y65192D01*
X1671458Y65525D01*
X1671250Y65858D01*
X1671000Y66067D01*
X1670750Y66108D01*
X1670458Y66025D01*
X1670250Y65733D01*
X1670167Y65442D01*
Y65067D01*
G01Y65442D02*
X1670042Y65692D01*
X1669833Y65900D01*
X1669583Y65983D01*
X1669333Y65900D01*
X1669125Y65692D01*
X1669000Y65317D01*
X1669042Y64942D01*
X1669208Y64567D01*
G01X1673300Y69700D02*
Y58300D01*
G01X1686700Y69700D02*
X1673300D01*
G01X1686700Y58300D02*
Y69700D01*
G01X1673300Y58300D02*
X1686700D01*
G01X1637847Y131367D02*
X1637722Y131117D01*
X1637639Y130825D01*
Y130492D01*
X1637764Y130117D01*
X1637972Y129825D01*
X1638222Y129617D01*
X1638639Y129450D01*
X1639014Y129408D01*
X1639389Y129492D01*
X1639639Y129617D01*
X1639889Y129867D01*
X1640056Y130158D01*
X1640139Y130450D01*
Y130742D01*
X1640056Y131033D01*
X1639931Y131283D01*
X1639764Y131492D01*
G01X1640139Y134050D02*
X1637639D01*
X1639431Y132508D01*
Y134592D01*
G01X1639097Y135858D02*
X1638806Y136150D01*
X1638639Y136400D01*
X1638556Y136733D01*
X1638639Y137025D01*
X1638806Y137233D01*
X1639056Y137400D01*
X1639347Y137442D01*
X1639597Y137400D01*
X1639847Y137233D01*
X1640056Y136983D01*
X1640139Y136692D01*
X1640056Y136358D01*
X1639806Y136067D01*
X1639431Y135900D01*
X1639014Y135858D01*
X1638472Y135942D01*
X1638181Y136067D01*
X1637889Y136275D01*
X1637681Y136567D01*
X1637639Y136858D01*
X1637722Y137150D01*
X1637931Y137358D01*
G01X1640139Y139750D02*
X1637639D01*
X1638139Y139250D01*
G01X1640139D02*
Y140250D01*
G01X1713167Y115492D02*
X1712917Y115617D01*
X1712625Y115700D01*
X1712292D01*
X1711917Y115575D01*
X1711625Y115367D01*
X1711417Y115117D01*
X1711250Y114700D01*
X1711208Y114325D01*
X1711292Y113950D01*
X1711417Y113700D01*
X1711667Y113450D01*
X1711958Y113283D01*
X1712250Y113200D01*
X1712542D01*
X1712833Y113283D01*
X1713083Y113408D01*
X1713292Y113575D01*
G01X1715850Y113200D02*
Y115700D01*
X1714308Y113908D01*
X1716392D01*
G01X1717658Y114242D02*
X1717950Y114533D01*
X1718200Y114700D01*
X1718533Y114783D01*
X1718825Y114700D01*
X1719033Y114533D01*
X1719200Y114283D01*
X1719242Y113992D01*
X1719200Y113742D01*
X1719033Y113492D01*
X1718783Y113283D01*
X1718492Y113200D01*
X1718158Y113283D01*
X1717867Y113533D01*
X1717700Y113908D01*
X1717658Y114325D01*
X1717742Y114867D01*
X1717867Y115158D01*
X1718075Y115450D01*
X1718367Y115658D01*
X1718658Y115700D01*
X1718950Y115617D01*
X1719158Y115408D01*
G01X1721550Y113200D02*
X1721842Y113242D01*
X1722175Y113367D01*
X1722383Y113575D01*
X1722467Y113867D01*
X1722383Y114158D01*
X1722133Y114408D01*
X1721758Y114533D01*
X1721342D01*
X1721092Y114617D01*
X1720883Y114825D01*
X1720800Y115117D01*
X1720925Y115408D01*
X1721217Y115617D01*
X1721550Y115700D01*
X1721883Y115617D01*
X1722175Y115408D01*
X1722300Y115117D01*
X1722217Y114825D01*
X1722008Y114617D01*
X1721758Y114533D01*
X1721342D01*
X1720967Y114408D01*
X1720717Y114158D01*
X1720633Y113867D01*
X1720717Y113575D01*
X1720925Y113367D01*
X1721258Y113242D01*
X1721550Y113200D01*
G01X1636139Y129617D02*
X1633639D01*
Y130658D01*
X1633764Y130992D01*
X1633931Y131200D01*
X1634264Y131283D01*
X1634597Y131200D01*
X1634806Y130950D01*
X1634931Y130658D01*
Y129617D01*
G01Y130658D02*
X1636139Y131283D01*
G01Y133550D02*
X1636097Y133842D01*
X1635972Y134175D01*
X1635764Y134383D01*
X1635472Y134467D01*
X1635181Y134383D01*
X1634931Y134133D01*
X1634806Y133758D01*
Y133342D01*
X1634722Y133092D01*
X1634514Y132883D01*
X1634222Y132800D01*
X1633931Y132925D01*
X1633722Y133217D01*
X1633639Y133550D01*
X1633722Y133883D01*
X1633931Y134175D01*
X1634222Y134300D01*
X1634514Y134217D01*
X1634722Y134008D01*
X1634806Y133758D01*
Y133342D01*
X1634931Y132967D01*
X1635181Y132717D01*
X1635472Y132633D01*
X1635764Y132717D01*
X1635972Y132925D01*
X1636097Y133258D01*
X1636139Y133550D01*
G01X1634056Y135858D02*
X1633806Y136108D01*
X1633681Y136400D01*
X1633639Y136733D01*
X1633722Y137150D01*
X1633931Y137442D01*
X1634181Y137525D01*
X1634431Y137483D01*
X1634639Y137317D01*
X1635056Y136483D01*
X1635347Y136108D01*
X1635764Y135858D01*
X1636139Y135775D01*
Y137525D01*
G01X1635847Y139042D02*
X1636056Y139333D01*
X1636139Y139667D01*
X1636056Y140000D01*
X1635806Y140292D01*
X1635431Y140500D01*
X1635056Y140583D01*
X1634597D01*
X1634222Y140500D01*
X1633889Y140292D01*
X1633722Y140042D01*
X1633639Y139750D01*
X1633722Y139417D01*
X1633889Y139167D01*
X1634139Y139000D01*
X1634472Y138917D01*
X1634764Y139000D01*
X1635056Y139208D01*
X1635222Y139458D01*
X1635264Y139750D01*
X1635181Y140083D01*
X1634972Y140333D01*
X1634597Y140583D01*
G01X1633300Y120900D02*
X1637300D01*
Y128300D01*
G01X1711617Y107200D02*
Y109700D01*
X1712658D01*
X1712992Y109575D01*
X1713200Y109408D01*
X1713283Y109075D01*
X1713200Y108742D01*
X1712950Y108533D01*
X1712658Y108408D01*
X1711617D01*
G01X1712658D02*
X1713283Y107200D01*
G01X1715550D02*
X1715842Y107242D01*
X1716175Y107367D01*
X1716383Y107575D01*
X1716467Y107867D01*
X1716383Y108158D01*
X1716133Y108408D01*
X1715758Y108533D01*
X1715342D01*
X1715092Y108617D01*
X1714883Y108825D01*
X1714800Y109117D01*
X1714925Y109408D01*
X1715217Y109617D01*
X1715550Y109700D01*
X1715883Y109617D01*
X1716175Y109408D01*
X1716300Y109117D01*
X1716217Y108825D01*
X1716008Y108617D01*
X1715758Y108533D01*
X1715342D01*
X1714967Y108408D01*
X1714717Y108158D01*
X1714633Y107867D01*
X1714717Y107575D01*
X1714925Y107367D01*
X1715258Y107242D01*
X1715550Y107200D01*
G01X1719150D02*
Y109700D01*
X1717608Y107908D01*
X1719692D01*
G01X1720833Y107700D02*
X1721083Y107408D01*
X1721417Y107242D01*
X1721792Y107200D01*
X1722125Y107242D01*
X1722458Y107450D01*
X1722667Y107700D01*
X1722708Y107950D01*
X1722625Y108242D01*
X1722333Y108450D01*
X1722042Y108533D01*
X1721667D01*
G01X1722042D02*
X1722292Y108658D01*
X1722500Y108867D01*
X1722583Y109117D01*
X1722500Y109367D01*
X1722292Y109575D01*
X1721917Y109700D01*
X1721542Y109658D01*
X1721167Y109492D01*
G01X1709700Y107500D02*
Y111500D01*
X1702300D01*
G01X1669208Y157267D02*
X1669083Y157017D01*
X1669000Y156725D01*
Y156392D01*
X1669125Y156017D01*
X1669333Y155725D01*
X1669583Y155517D01*
X1670000Y155350D01*
X1670375Y155308D01*
X1670750Y155392D01*
X1671000Y155517D01*
X1671250Y155767D01*
X1671417Y156058D01*
X1671500Y156350D01*
Y156642D01*
X1671417Y156933D01*
X1671292Y157183D01*
X1671125Y157392D01*
G01X1671500Y159950D02*
X1669000D01*
X1670792Y158408D01*
Y160492D01*
G01X1671125Y161633D02*
X1671333Y161883D01*
X1671458Y162175D01*
X1671500Y162550D01*
X1671417Y162925D01*
X1671250Y163217D01*
X1670958Y163425D01*
X1670625Y163467D01*
X1670292Y163383D01*
X1670083Y163175D01*
X1669917Y162883D01*
X1669875Y162592D01*
X1669917Y162300D01*
X1670083Y161925D01*
X1669000Y162050D01*
Y163175D01*
G01X1671208Y164942D02*
X1671417Y165233D01*
X1671500Y165567D01*
X1671417Y165900D01*
X1671167Y166192D01*
X1670792Y166400D01*
X1670417Y166483D01*
X1669958D01*
X1669583Y166400D01*
X1669250Y166192D01*
X1669083Y165942D01*
X1669000Y165650D01*
X1669083Y165317D01*
X1669250Y165067D01*
X1669500Y164900D01*
X1669833Y164817D01*
X1670125Y164900D01*
X1670417Y165108D01*
X1670583Y165358D01*
X1670625Y165650D01*
X1670542Y165983D01*
X1670333Y166233D01*
X1669958Y166483D01*
G01X1669708Y189267D02*
X1669583Y189017D01*
X1669500Y188725D01*
Y188392D01*
X1669625Y188017D01*
X1669833Y187725D01*
X1670083Y187517D01*
X1670500Y187350D01*
X1670875Y187308D01*
X1671250Y187392D01*
X1671500Y187517D01*
X1671750Y187767D01*
X1671917Y188058D01*
X1672000Y188350D01*
Y188642D01*
X1671917Y188933D01*
X1671792Y189183D01*
X1671625Y189392D01*
G01X1672000Y191950D02*
X1669500D01*
X1671292Y190408D01*
Y192492D01*
G01X1670958Y193758D02*
X1670667Y194050D01*
X1670500Y194300D01*
X1670417Y194633D01*
X1670500Y194925D01*
X1670667Y195133D01*
X1670917Y195300D01*
X1671208Y195342D01*
X1671458Y195300D01*
X1671708Y195133D01*
X1671917Y194883D01*
X1672000Y194592D01*
X1671917Y194258D01*
X1671667Y193967D01*
X1671292Y193800D01*
X1670875Y193758D01*
X1670333Y193842D01*
X1670042Y193967D01*
X1669750Y194175D01*
X1669542Y194467D01*
X1669500Y194758D01*
X1669583Y195050D01*
X1669792Y195258D01*
G01X1670958Y196858D02*
X1670667Y197150D01*
X1670500Y197400D01*
X1670417Y197733D01*
X1670500Y198025D01*
X1670667Y198233D01*
X1670917Y198400D01*
X1671208Y198442D01*
X1671458Y198400D01*
X1671708Y198233D01*
X1671917Y197983D01*
X1672000Y197692D01*
X1671917Y197358D01*
X1671667Y197067D01*
X1671292Y196900D01*
X1670875Y196858D01*
X1670333Y196942D01*
X1670042Y197067D01*
X1669750Y197275D01*
X1669542Y197567D01*
X1669500Y197858D01*
X1669583Y198150D01*
X1669792Y198358D01*
G01X1678350Y106500D02*
X1678017Y106542D01*
X1677725Y106708D01*
X1677475Y106958D01*
X1677308Y107250D01*
X1677225Y107583D01*
Y107917D01*
X1677308Y108250D01*
X1677475Y108542D01*
X1677725Y108792D01*
X1678017Y108958D01*
X1678350Y109000D01*
X1678683Y108958D01*
X1678975Y108792D01*
X1679225Y108542D01*
X1679392Y108250D01*
X1679475Y107917D01*
Y107583D01*
X1679392Y107250D01*
X1679225Y106958D01*
X1678975Y106708D01*
X1678683Y106542D01*
X1678350Y106500D01*
G01X1678683Y107167D02*
X1679183Y106500D01*
G01X1681450D02*
Y109000D01*
X1680950Y108500D01*
G01Y106500D02*
X1681950D01*
G01X1684467D02*
X1684550Y107042D01*
X1684675Y107500D01*
X1684842Y107917D01*
X1685050Y108375D01*
X1685383Y109000D01*
X1683717D01*
G01X1687650Y106500D02*
Y109000D01*
X1687150Y108500D01*
G01Y106500D02*
X1688150D01*
G01X1693000Y104700D02*
X1691200Y102600D01*
X1689000Y104700D01*
G01X1698850Y145000D02*
X1698517Y145042D01*
X1698225Y145208D01*
X1697975Y145458D01*
X1697808Y145750D01*
X1697725Y146083D01*
Y146417D01*
X1697808Y146750D01*
X1697975Y147042D01*
X1698225Y147292D01*
X1698517Y147458D01*
X1698850Y147500D01*
X1699183Y147458D01*
X1699475Y147292D01*
X1699725Y147042D01*
X1699892Y146750D01*
X1699975Y146417D01*
Y146083D01*
X1699892Y145750D01*
X1699725Y145458D01*
X1699475Y145208D01*
X1699183Y145042D01*
X1698850Y145000D01*
G01X1699183Y145667D02*
X1699683Y145000D01*
G01X1701950D02*
Y147500D01*
X1701450Y147000D01*
G01Y145000D02*
X1702450D01*
G01X1704967D02*
X1705050Y145542D01*
X1705175Y146000D01*
X1705342Y146417D01*
X1705550Y146875D01*
X1705883Y147500D01*
X1704217D01*
G01X1708650Y145000D02*
Y147500D01*
X1707108Y145708D01*
X1709192D01*
G01X1687800Y132000D02*
X1689900Y130200D01*
X1687800Y128000D01*
G01X1687700Y124400D02*
X1706900D01*
Y135600D01*
X1687700D01*
Y124400D01*
X1688100D01*
G01X1672708Y156767D02*
X1672583Y156517D01*
X1672500Y156225D01*
Y155892D01*
X1672625Y155517D01*
X1672833Y155225D01*
X1673083Y155017D01*
X1673500Y154850D01*
X1673875Y154808D01*
X1674250Y154892D01*
X1674500Y155017D01*
X1674750Y155267D01*
X1674917Y155558D01*
X1675000Y155850D01*
Y156142D01*
X1674917Y156433D01*
X1674792Y156683D01*
X1674625Y156892D01*
G01X1675000Y159450D02*
X1672500D01*
X1674292Y157908D01*
Y159992D01*
G01X1673958Y161258D02*
X1673667Y161550D01*
X1673500Y161800D01*
X1673417Y162133D01*
X1673500Y162425D01*
X1673667Y162633D01*
X1673917Y162800D01*
X1674208Y162842D01*
X1674458Y162800D01*
X1674708Y162633D01*
X1674917Y162383D01*
X1675000Y162092D01*
X1674917Y161758D01*
X1674667Y161467D01*
X1674292Y161300D01*
X1673875Y161258D01*
X1673333Y161342D01*
X1673042Y161467D01*
X1672750Y161675D01*
X1672542Y161967D01*
X1672500Y162258D01*
X1672583Y162550D01*
X1672792Y162758D01*
G01X1672500Y165150D02*
X1672583Y164817D01*
X1672792Y164567D01*
X1673042Y164400D01*
X1673375Y164275D01*
X1673750Y164233D01*
X1674125Y164275D01*
X1674458Y164400D01*
X1674708Y164567D01*
X1674917Y164817D01*
X1675000Y165150D01*
X1674917Y165483D01*
X1674708Y165733D01*
X1674458Y165900D01*
X1674125Y166025D01*
X1673750Y166067D01*
X1673375Y166025D01*
X1673042Y165900D01*
X1672792Y165733D01*
X1672583Y165483D01*
X1672500Y165150D01*
G01X1677000Y136200D02*
Y141700D01*
G01X1685000Y136200D02*
X1677000D01*
G01X1685000Y141700D02*
Y136200D01*
G01Y153800D02*
Y148300D01*
G01X1677000Y153800D02*
X1685000D01*
G01X1677000Y148300D02*
Y153800D01*
G01X1672517Y118000D02*
Y120500D01*
X1673558D01*
X1673892Y120375D01*
X1674100Y120208D01*
X1674183Y119875D01*
X1674100Y119542D01*
X1673850Y119333D01*
X1673558Y119208D01*
X1672517D01*
G01X1673558D02*
X1674183Y118000D01*
G01X1676450D02*
X1676742Y118042D01*
X1677075Y118167D01*
X1677283Y118375D01*
X1677367Y118667D01*
X1677283Y118958D01*
X1677033Y119208D01*
X1676658Y119333D01*
X1676242D01*
X1675992Y119417D01*
X1675783Y119625D01*
X1675700Y119917D01*
X1675825Y120208D01*
X1676117Y120417D01*
X1676450Y120500D01*
X1676783Y120417D01*
X1677075Y120208D01*
X1677200Y119917D01*
X1677117Y119625D01*
X1676908Y119417D01*
X1676658Y119333D01*
X1676242D01*
X1675867Y119208D01*
X1675617Y118958D01*
X1675533Y118667D01*
X1675617Y118375D01*
X1675825Y118167D01*
X1676158Y118042D01*
X1676450Y118000D01*
G01X1678758Y120083D02*
X1679008Y120333D01*
X1679300Y120458D01*
X1679633Y120500D01*
X1680050Y120417D01*
X1680342Y120208D01*
X1680425Y119958D01*
X1680383Y119708D01*
X1680217Y119500D01*
X1679383Y119083D01*
X1679008Y118792D01*
X1678758Y118375D01*
X1678675Y118000D01*
X1680425D01*
G01X1682650D02*
X1682942Y118042D01*
X1683275Y118167D01*
X1683483Y118375D01*
X1683567Y118667D01*
X1683483Y118958D01*
X1683233Y119208D01*
X1682858Y119333D01*
X1682442D01*
X1682192Y119417D01*
X1681983Y119625D01*
X1681900Y119917D01*
X1682025Y120208D01*
X1682317Y120417D01*
X1682650Y120500D01*
X1682983Y120417D01*
X1683275Y120208D01*
X1683400Y119917D01*
X1683317Y119625D01*
X1683108Y119417D01*
X1682858Y119333D01*
X1682442D01*
X1682067Y119208D01*
X1681817Y118958D01*
X1681733Y118667D01*
X1681817Y118375D01*
X1682025Y118167D01*
X1682358Y118042D01*
X1682650Y118000D01*
G01X1686300Y130000D02*
Y122000D01*
X1668700D01*
Y130000D01*
X1686300D01*
G01X1684017Y165500D02*
Y168000D01*
X1685058D01*
X1685392Y167875D01*
X1685600Y167708D01*
X1685683Y167375D01*
X1685600Y167042D01*
X1685350Y166833D01*
X1685058Y166708D01*
X1684017D01*
G01X1685058D02*
X1685683Y165500D01*
G01X1687950D02*
X1688242Y165542D01*
X1688575Y165667D01*
X1688783Y165875D01*
X1688867Y166167D01*
X1688783Y166458D01*
X1688533Y166708D01*
X1688158Y166833D01*
X1687742D01*
X1687492Y166917D01*
X1687283Y167125D01*
X1687200Y167417D01*
X1687325Y167708D01*
X1687617Y167917D01*
X1687950Y168000D01*
X1688283Y167917D01*
X1688575Y167708D01*
X1688700Y167417D01*
X1688617Y167125D01*
X1688408Y166917D01*
X1688158Y166833D01*
X1687742D01*
X1687367Y166708D01*
X1687117Y166458D01*
X1687033Y166167D01*
X1687117Y165875D01*
X1687325Y165667D01*
X1687658Y165542D01*
X1687950Y165500D01*
G01X1690133Y166000D02*
X1690383Y165708D01*
X1690717Y165542D01*
X1691092Y165500D01*
X1691425Y165542D01*
X1691758Y165750D01*
X1691967Y166000D01*
X1692008Y166250D01*
X1691925Y166542D01*
X1691633Y166750D01*
X1691342Y166833D01*
X1690967D01*
G01X1691342D02*
X1691592Y166958D01*
X1691800Y167167D01*
X1691883Y167417D01*
X1691800Y167667D01*
X1691592Y167875D01*
X1691217Y168000D01*
X1690842Y167958D01*
X1690467Y167792D01*
G01X1694150Y168000D02*
X1693817Y167917D01*
X1693567Y167708D01*
X1693400Y167458D01*
X1693275Y167125D01*
X1693233Y166750D01*
X1693275Y166375D01*
X1693400Y166042D01*
X1693567Y165792D01*
X1693817Y165583D01*
X1694150Y165500D01*
X1694483Y165583D01*
X1694733Y165792D01*
X1694900Y166042D01*
X1695025Y166375D01*
X1695067Y166750D01*
X1695025Y167125D01*
X1694900Y167458D01*
X1694733Y167708D01*
X1694483Y167917D01*
X1694150Y168000D01*
G01X1693700Y164000D02*
Y156000D01*
X1676100D01*
Y164000D01*
X1693700D01*
G01X1676547Y189267D02*
X1676422Y189017D01*
X1676339Y188725D01*
Y188392D01*
X1676464Y188017D01*
X1676672Y187725D01*
X1676922Y187517D01*
X1677339Y187350D01*
X1677714Y187308D01*
X1678089Y187392D01*
X1678339Y187517D01*
X1678589Y187767D01*
X1678756Y188058D01*
X1678839Y188350D01*
Y188642D01*
X1678756Y188933D01*
X1678631Y189183D01*
X1678464Y189392D01*
G01X1678839Y191950D02*
X1676339D01*
X1678131Y190408D01*
Y192492D01*
G01X1677797Y193758D02*
X1677506Y194050D01*
X1677339Y194300D01*
X1677256Y194633D01*
X1677339Y194925D01*
X1677506Y195133D01*
X1677756Y195300D01*
X1678047Y195342D01*
X1678297Y195300D01*
X1678547Y195133D01*
X1678756Y194883D01*
X1678839Y194592D01*
X1678756Y194258D01*
X1678506Y193967D01*
X1678131Y193800D01*
X1677714Y193758D01*
X1677172Y193842D01*
X1676881Y193967D01*
X1676589Y194175D01*
X1676381Y194467D01*
X1676339Y194758D01*
X1676422Y195050D01*
X1676631Y195258D01*
G01X1678839Y198150D02*
X1676339D01*
X1678131Y196608D01*
Y198692D01*
G01X1684547Y189267D02*
X1684422Y189017D01*
X1684339Y188725D01*
Y188392D01*
X1684464Y188017D01*
X1684672Y187725D01*
X1684922Y187517D01*
X1685339Y187350D01*
X1685714Y187308D01*
X1686089Y187392D01*
X1686339Y187517D01*
X1686589Y187767D01*
X1686756Y188058D01*
X1686839Y188350D01*
Y188642D01*
X1686756Y188933D01*
X1686631Y189183D01*
X1686464Y189392D01*
G01X1686839Y191950D02*
X1684339D01*
X1686131Y190408D01*
Y192492D01*
G01X1685797Y193758D02*
X1685506Y194050D01*
X1685339Y194300D01*
X1685256Y194633D01*
X1685339Y194925D01*
X1685506Y195133D01*
X1685756Y195300D01*
X1686047Y195342D01*
X1686297Y195300D01*
X1686547Y195133D01*
X1686756Y194883D01*
X1686839Y194592D01*
X1686756Y194258D01*
X1686506Y193967D01*
X1686131Y193800D01*
X1685714Y193758D01*
X1685172Y193842D01*
X1684881Y193967D01*
X1684589Y194175D01*
X1684381Y194467D01*
X1684339Y194758D01*
X1684422Y195050D01*
X1684631Y195258D01*
G01X1686464Y196733D02*
X1686672Y196983D01*
X1686797Y197275D01*
X1686839Y197650D01*
X1686756Y198025D01*
X1686589Y198317D01*
X1686297Y198525D01*
X1685964Y198567D01*
X1685631Y198483D01*
X1685422Y198275D01*
X1685256Y197983D01*
X1685214Y197692D01*
X1685256Y197400D01*
X1685422Y197025D01*
X1684339Y197150D01*
Y198275D01*
G01X1637431Y560075D02*
X1642481D01*
Y658775D01*
X1667131D01*
Y474375D01*
X1642481D01*
Y533075D01*
X1637431D01*
Y560075D01*
G01X1717359Y473007D02*
Y477007D01*
X1709959D01*
G01X1693463Y455982D02*
Y458482D01*
X1694504D01*
X1694838Y458357D01*
X1695046Y458190D01*
X1695129Y457857D01*
X1695046Y457524D01*
X1694796Y457315D01*
X1694504Y457190D01*
X1693463D01*
G01X1694504D02*
X1695129Y455982D01*
G01X1697396D02*
Y458482D01*
X1696896Y457982D01*
G01Y455982D02*
X1697896D01*
G01X1700496D02*
Y458482D01*
X1699996Y457982D01*
G01Y455982D02*
X1700996D01*
G01X1702804Y457024D02*
X1703096Y457315D01*
X1703346Y457482D01*
X1703679Y457565D01*
X1703971Y457482D01*
X1704179Y457315D01*
X1704346Y457065D01*
X1704388Y456774D01*
X1704346Y456524D01*
X1704179Y456274D01*
X1703929Y456065D01*
X1703638Y455982D01*
X1703304Y456065D01*
X1703013Y456315D01*
X1702846Y456690D01*
X1702804Y457107D01*
X1702888Y457649D01*
X1703013Y457940D01*
X1703221Y458232D01*
X1703513Y458440D01*
X1703804Y458482D01*
X1704096Y458399D01*
X1704304Y458190D01*
G01X1705988Y456274D02*
X1706279Y456065D01*
X1706613Y455982D01*
X1706946Y456065D01*
X1707238Y456315D01*
X1707446Y456690D01*
X1707529Y457065D01*
Y457524D01*
X1707446Y457899D01*
X1707238Y458232D01*
X1706988Y458399D01*
X1706696Y458482D01*
X1706363Y458399D01*
X1706113Y458232D01*
X1705946Y457982D01*
X1705863Y457649D01*
X1705946Y457357D01*
X1706154Y457065D01*
X1706404Y456899D01*
X1706696Y456857D01*
X1707029Y456940D01*
X1707279Y457149D01*
X1707529Y457524D01*
G01X1716059Y455707D02*
Y459707D01*
X1708659D01*
G01X1707485Y462751D02*
X1704985D01*
Y463792D01*
X1705110Y464126D01*
X1705277Y464334D01*
X1705610Y464417D01*
X1705943Y464334D01*
X1706152Y464084D01*
X1706277Y463792D01*
Y462751D01*
G01Y463792D02*
X1707485Y464417D01*
G01Y466684D02*
X1704985D01*
X1705485Y466184D01*
G01X1707485D02*
Y467184D01*
G01Y469784D02*
X1704985D01*
X1705485Y469284D01*
G01X1707485D02*
Y470284D01*
G01Y472801D02*
X1706943Y472884D01*
X1706485Y473009D01*
X1706068Y473176D01*
X1705610Y473384D01*
X1704985Y473717D01*
Y472051D01*
G01Y475984D02*
X1705068Y475651D01*
X1705277Y475401D01*
X1705527Y475234D01*
X1705860Y475109D01*
X1706235Y475067D01*
X1706610Y475109D01*
X1706943Y475234D01*
X1707193Y475401D01*
X1707402Y475651D01*
X1707485Y475984D01*
X1707402Y476317D01*
X1707193Y476567D01*
X1706943Y476734D01*
X1706610Y476859D01*
X1706235Y476901D01*
X1705860Y476859D01*
X1705527Y476734D01*
X1705277Y476567D01*
X1705068Y476317D01*
X1704985Y475984D01*
G01X1720296Y465562D02*
X1724296D01*
Y472962D01*
G01X1702985Y462751D02*
X1700485D01*
Y463792D01*
X1700610Y464126D01*
X1700777Y464334D01*
X1701110Y464417D01*
X1701443Y464334D01*
X1701652Y464084D01*
X1701777Y463792D01*
Y462751D01*
G01Y463792D02*
X1702985Y464417D01*
G01Y466684D02*
X1700485D01*
X1700985Y466184D01*
G01X1702985D02*
Y467184D01*
G01Y469784D02*
X1700485D01*
X1700985Y469284D01*
G01X1702985D02*
Y470284D01*
G01Y472801D02*
X1702443Y472884D01*
X1701985Y473009D01*
X1701568Y473176D01*
X1701110Y473384D01*
X1700485Y473717D01*
Y472051D01*
G01X1700902Y475192D02*
X1700652Y475442D01*
X1700527Y475734D01*
X1700485Y476067D01*
X1700568Y476484D01*
X1700777Y476776D01*
X1701027Y476859D01*
X1701277Y476817D01*
X1701485Y476651D01*
X1701902Y475817D01*
X1702193Y475442D01*
X1702610Y475192D01*
X1702985Y475109D01*
Y476859D01*
G01X1716159Y465507D02*
X1720159D01*
Y472907D01*
G01X1694153Y448002D02*
X1693903Y448127D01*
X1693611Y448210D01*
X1693278D01*
X1692903Y448085D01*
X1692611Y447877D01*
X1692403Y447627D01*
X1692236Y447210D01*
X1692194Y446835D01*
X1692278Y446460D01*
X1692403Y446210D01*
X1692653Y445960D01*
X1692944Y445793D01*
X1693236Y445710D01*
X1693528D01*
X1693819Y445793D01*
X1694069Y445918D01*
X1694278Y446085D01*
G01X1695544Y446752D02*
X1695836Y447043D01*
X1696086Y447210D01*
X1696419Y447293D01*
X1696711Y447210D01*
X1696919Y447043D01*
X1697086Y446793D01*
X1697128Y446502D01*
X1697086Y446252D01*
X1696919Y446002D01*
X1696669Y445793D01*
X1696378Y445710D01*
X1696044Y445793D01*
X1695753Y446043D01*
X1695586Y446418D01*
X1695544Y446835D01*
X1695628Y447377D01*
X1695753Y447668D01*
X1695961Y447960D01*
X1696253Y448168D01*
X1696544Y448210D01*
X1696836Y448127D01*
X1697044Y447918D01*
G01X1699353Y445710D02*
X1699436Y446252D01*
X1699561Y446710D01*
X1699728Y447127D01*
X1699936Y447585D01*
X1700269Y448210D01*
X1698603D01*
G01X1701619Y446085D02*
X1701869Y445877D01*
X1702161Y445752D01*
X1702536Y445710D01*
X1702911Y445793D01*
X1703203Y445960D01*
X1703411Y446252D01*
X1703453Y446585D01*
X1703369Y446918D01*
X1703161Y447127D01*
X1702869Y447293D01*
X1702578Y447335D01*
X1702286Y447293D01*
X1701911Y447127D01*
X1702036Y448210D01*
X1703161D01*
G01X1694153Y440341D02*
X1693903Y440466D01*
X1693611Y440549D01*
X1693278D01*
X1692903Y440424D01*
X1692611Y440216D01*
X1692403Y439966D01*
X1692236Y439549D01*
X1692194Y439174D01*
X1692278Y438799D01*
X1692403Y438549D01*
X1692653Y438299D01*
X1692944Y438132D01*
X1693236Y438049D01*
X1693528D01*
X1693819Y438132D01*
X1694069Y438257D01*
X1694278Y438424D01*
G01X1695544Y439091D02*
X1695836Y439382D01*
X1696086Y439549D01*
X1696419Y439632D01*
X1696711Y439549D01*
X1696919Y439382D01*
X1697086Y439132D01*
X1697128Y438841D01*
X1697086Y438591D01*
X1696919Y438341D01*
X1696669Y438132D01*
X1696378Y438049D01*
X1696044Y438132D01*
X1695753Y438382D01*
X1695586Y438757D01*
X1695544Y439174D01*
X1695628Y439716D01*
X1695753Y440007D01*
X1695961Y440299D01*
X1696253Y440507D01*
X1696544Y440549D01*
X1696836Y440466D01*
X1697044Y440257D01*
G01X1699353Y438049D02*
X1699436Y438591D01*
X1699561Y439049D01*
X1699728Y439466D01*
X1699936Y439924D01*
X1700269Y440549D01*
X1698603D01*
G01X1701744Y439091D02*
X1702036Y439382D01*
X1702286Y439549D01*
X1702619Y439632D01*
X1702911Y439549D01*
X1703119Y439382D01*
X1703286Y439132D01*
X1703328Y438841D01*
X1703286Y438591D01*
X1703119Y438341D01*
X1702869Y438132D01*
X1702578Y438049D01*
X1702244Y438132D01*
X1701953Y438382D01*
X1701786Y438757D01*
X1701744Y439174D01*
X1701828Y439716D01*
X1701953Y440007D01*
X1702161Y440299D01*
X1702453Y440507D01*
X1702744Y440549D01*
X1703036Y440466D01*
X1703244Y440257D01*
G01X1669208Y537767D02*
X1669083Y537517D01*
X1669000Y537225D01*
Y536892D01*
X1669125Y536517D01*
X1669333Y536225D01*
X1669583Y536017D01*
X1670000Y535850D01*
X1670375Y535808D01*
X1670750Y535892D01*
X1671000Y536017D01*
X1671250Y536267D01*
X1671417Y536558D01*
X1671500Y536850D01*
Y537142D01*
X1671417Y537433D01*
X1671292Y537683D01*
X1671125Y537892D01*
G01X1671000Y539033D02*
X1671292Y539283D01*
X1671458Y539617D01*
X1671500Y539992D01*
X1671458Y540325D01*
X1671250Y540658D01*
X1671000Y540867D01*
X1670750Y540908D01*
X1670458Y540825D01*
X1670250Y540533D01*
X1670167Y540242D01*
Y539867D01*
G01Y540242D02*
X1670042Y540492D01*
X1669833Y540700D01*
X1669583Y540783D01*
X1669333Y540700D01*
X1669125Y540492D01*
X1669000Y540117D01*
X1669042Y539742D01*
X1669208Y539367D01*
G01X1671500Y543050D02*
X1669000D01*
X1669500Y542550D01*
G01X1671500D02*
Y543550D01*
G01Y546150D02*
X1669000D01*
X1669500Y545650D01*
G01X1671500D02*
Y546650D01*
G01X1713267Y567453D02*
X1713017Y567578D01*
X1712725Y567661D01*
X1712392D01*
X1712017Y567536D01*
X1711725Y567328D01*
X1711517Y567078D01*
X1711350Y566661D01*
X1711308Y566286D01*
X1711392Y565911D01*
X1711517Y565661D01*
X1711767Y565411D01*
X1712058Y565244D01*
X1712350Y565161D01*
X1712642D01*
X1712933Y565244D01*
X1713183Y565369D01*
X1713392Y565536D01*
G01X1714533Y565661D02*
X1714783Y565369D01*
X1715117Y565203D01*
X1715492Y565161D01*
X1715825Y565203D01*
X1716158Y565411D01*
X1716367Y565661D01*
X1716408Y565911D01*
X1716325Y566203D01*
X1716033Y566411D01*
X1715742Y566494D01*
X1715367D01*
G01X1715742D02*
X1715992Y566619D01*
X1716200Y566828D01*
X1716283Y567078D01*
X1716200Y567328D01*
X1715992Y567536D01*
X1715617Y567661D01*
X1715242Y567619D01*
X1714867Y567453D01*
G01X1718550Y565161D02*
Y567661D01*
X1718050Y567161D01*
G01Y565161D02*
X1719050D01*
G01X1720858Y567244D02*
X1721108Y567494D01*
X1721400Y567619D01*
X1721733Y567661D01*
X1722150Y567578D01*
X1722442Y567369D01*
X1722525Y567119D01*
X1722483Y566869D01*
X1722317Y566661D01*
X1721483Y566244D01*
X1721108Y565953D01*
X1720858Y565536D01*
X1720775Y565161D01*
X1722525D01*
G01X1671500Y522517D02*
X1669000D01*
Y523558D01*
X1669125Y523892D01*
X1669292Y524100D01*
X1669625Y524183D01*
X1669958Y524100D01*
X1670167Y523850D01*
X1670292Y523558D01*
Y522517D01*
G01Y523558D02*
X1671500Y524183D01*
G01X1671125Y525533D02*
X1671333Y525783D01*
X1671458Y526075D01*
X1671500Y526450D01*
X1671417Y526825D01*
X1671250Y527117D01*
X1670958Y527325D01*
X1670625Y527367D01*
X1670292Y527283D01*
X1670083Y527075D01*
X1669917Y526783D01*
X1669875Y526492D01*
X1669917Y526200D01*
X1670083Y525825D01*
X1669000Y525950D01*
Y527075D01*
G01X1670458Y528758D02*
X1670167Y529050D01*
X1670000Y529300D01*
X1669917Y529633D01*
X1670000Y529925D01*
X1670167Y530133D01*
X1670417Y530300D01*
X1670708Y530342D01*
X1670958Y530300D01*
X1671208Y530133D01*
X1671417Y529883D01*
X1671500Y529592D01*
X1671417Y529258D01*
X1671167Y528967D01*
X1670792Y528800D01*
X1670375Y528758D01*
X1669833Y528842D01*
X1669542Y528967D01*
X1669250Y529175D01*
X1669042Y529467D01*
X1669000Y529758D01*
X1669083Y530050D01*
X1669292Y530258D01*
G01X1669000Y532650D02*
X1669083Y532317D01*
X1669292Y532067D01*
X1669542Y531900D01*
X1669875Y531775D01*
X1670250Y531733D01*
X1670625Y531775D01*
X1670958Y531900D01*
X1671208Y532067D01*
X1671417Y532317D01*
X1671500Y532650D01*
X1671417Y532983D01*
X1671208Y533233D01*
X1670958Y533400D01*
X1670625Y533525D01*
X1670250Y533567D01*
X1669875Y533525D01*
X1669542Y533400D01*
X1669292Y533233D01*
X1669083Y532983D01*
X1669000Y532650D01*
G01X1674600Y532100D02*
Y528100D01*
X1682000D01*
G01X1677000Y496517D02*
X1674500D01*
Y497558D01*
X1674625Y497892D01*
X1674792Y498100D01*
X1675125Y498183D01*
X1675458Y498100D01*
X1675667Y497850D01*
X1675792Y497558D01*
Y496517D01*
G01Y497558D02*
X1677000Y498183D01*
G01X1676625Y499533D02*
X1676833Y499783D01*
X1676958Y500075D01*
X1677000Y500450D01*
X1676917Y500825D01*
X1676750Y501117D01*
X1676458Y501325D01*
X1676125Y501367D01*
X1675792Y501283D01*
X1675583Y501075D01*
X1675417Y500783D01*
X1675375Y500492D01*
X1675417Y500200D01*
X1675583Y499825D01*
X1674500Y499950D01*
Y501075D01*
G01X1675958Y502758D02*
X1675667Y503050D01*
X1675500Y503300D01*
X1675417Y503633D01*
X1675500Y503925D01*
X1675667Y504133D01*
X1675917Y504300D01*
X1676208Y504342D01*
X1676458Y504300D01*
X1676708Y504133D01*
X1676917Y503883D01*
X1677000Y503592D01*
X1676917Y503258D01*
X1676667Y502967D01*
X1676292Y502800D01*
X1675875Y502758D01*
X1675333Y502842D01*
X1675042Y502967D01*
X1674750Y503175D01*
X1674542Y503467D01*
X1674500Y503758D01*
X1674583Y504050D01*
X1674792Y504258D01*
G01X1677000Y506650D02*
X1674500D01*
X1675000Y506150D01*
G01X1677000D02*
Y507150D01*
G01X1682500Y502800D02*
X1686500D01*
Y510200D01*
G01X1702500Y500517D02*
X1700000D01*
Y501558D01*
X1700125Y501892D01*
X1700292Y502100D01*
X1700625Y502183D01*
X1700958Y502100D01*
X1701167Y501850D01*
X1701292Y501558D01*
Y500517D01*
G01Y501558D02*
X1702500Y502183D01*
G01X1702125Y503533D02*
X1702333Y503783D01*
X1702458Y504075D01*
X1702500Y504450D01*
X1702417Y504825D01*
X1702250Y505117D01*
X1701958Y505325D01*
X1701625Y505367D01*
X1701292Y505283D01*
X1701083Y505075D01*
X1700917Y504783D01*
X1700875Y504492D01*
X1700917Y504200D01*
X1701083Y503825D01*
X1700000Y503950D01*
Y505075D01*
G01X1701458Y506758D02*
X1701167Y507050D01*
X1701000Y507300D01*
X1700917Y507633D01*
X1701000Y507925D01*
X1701167Y508133D01*
X1701417Y508300D01*
X1701708Y508342D01*
X1701958Y508300D01*
X1702208Y508133D01*
X1702417Y507883D01*
X1702500Y507592D01*
X1702417Y507258D01*
X1702167Y506967D01*
X1701792Y506800D01*
X1701375Y506758D01*
X1700833Y506842D01*
X1700542Y506967D01*
X1700250Y507175D01*
X1700042Y507467D01*
X1700000Y507758D01*
X1700083Y508050D01*
X1700292Y508258D01*
G01X1702500Y511150D02*
X1700000D01*
X1701792Y509608D01*
Y511692D01*
G01X1692500Y502800D02*
X1696500D01*
Y510200D01*
G01X1673000Y496517D02*
X1670500D01*
Y497558D01*
X1670625Y497892D01*
X1670792Y498100D01*
X1671125Y498183D01*
X1671458Y498100D01*
X1671667Y497850D01*
X1671792Y497558D01*
Y496517D01*
G01Y497558D02*
X1673000Y498183D01*
G01X1672625Y499533D02*
X1672833Y499783D01*
X1672958Y500075D01*
X1673000Y500450D01*
X1672917Y500825D01*
X1672750Y501117D01*
X1672458Y501325D01*
X1672125Y501367D01*
X1671792Y501283D01*
X1671583Y501075D01*
X1671417Y500783D01*
X1671375Y500492D01*
X1671417Y500200D01*
X1671583Y499825D01*
X1670500Y499950D01*
Y501075D01*
G01X1671958Y502758D02*
X1671667Y503050D01*
X1671500Y503300D01*
X1671417Y503633D01*
X1671500Y503925D01*
X1671667Y504133D01*
X1671917Y504300D01*
X1672208Y504342D01*
X1672458Y504300D01*
X1672708Y504133D01*
X1672917Y503883D01*
X1673000Y503592D01*
X1672917Y503258D01*
X1672667Y502967D01*
X1672292Y502800D01*
X1671875Y502758D01*
X1671333Y502842D01*
X1671042Y502967D01*
X1670750Y503175D01*
X1670542Y503467D01*
X1670500Y503758D01*
X1670583Y504050D01*
X1670792Y504258D01*
G01X1672625Y505733D02*
X1672833Y505983D01*
X1672958Y506275D01*
X1673000Y506650D01*
X1672917Y507025D01*
X1672750Y507317D01*
X1672458Y507525D01*
X1672125Y507567D01*
X1671792Y507483D01*
X1671583Y507275D01*
X1671417Y506983D01*
X1671375Y506692D01*
X1671417Y506400D01*
X1671583Y506025D01*
X1670500Y506150D01*
Y507275D01*
G01X1682000Y510200D02*
X1678000D01*
Y502800D01*
G01X1711339Y510517D02*
X1708839D01*
Y511558D01*
X1708964Y511892D01*
X1709131Y512100D01*
X1709464Y512183D01*
X1709797Y512100D01*
X1710006Y511850D01*
X1710131Y511558D01*
Y510517D01*
G01Y511558D02*
X1711339Y512183D01*
G01X1710964Y513533D02*
X1711172Y513783D01*
X1711297Y514075D01*
X1711339Y514450D01*
X1711256Y514825D01*
X1711089Y515117D01*
X1710797Y515325D01*
X1710464Y515367D01*
X1710131Y515283D01*
X1709922Y515075D01*
X1709756Y514783D01*
X1709714Y514492D01*
X1709756Y514200D01*
X1709922Y513825D01*
X1708839Y513950D01*
Y515075D01*
G01X1710297Y516758D02*
X1710006Y517050D01*
X1709839Y517300D01*
X1709756Y517633D01*
X1709839Y517925D01*
X1710006Y518133D01*
X1710256Y518300D01*
X1710547Y518342D01*
X1710797Y518300D01*
X1711047Y518133D01*
X1711256Y517883D01*
X1711339Y517592D01*
X1711256Y517258D01*
X1711006Y516967D01*
X1710631Y516800D01*
X1710214Y516758D01*
X1709672Y516842D01*
X1709381Y516967D01*
X1709089Y517175D01*
X1708881Y517467D01*
X1708839Y517758D01*
X1708922Y518050D01*
X1709131Y518258D01*
G01X1711339Y520567D02*
X1710797Y520650D01*
X1710339Y520775D01*
X1709922Y520942D01*
X1709464Y521150D01*
X1708839Y521483D01*
Y519817D01*
G01X1697000Y515300D02*
X1701000D01*
Y522700D01*
G01X1711517Y561161D02*
Y563661D01*
X1712558D01*
X1712892Y563536D01*
X1713100Y563369D01*
X1713183Y563036D01*
X1713100Y562703D01*
X1712850Y562494D01*
X1712558Y562369D01*
X1711517D01*
G01X1712558D02*
X1713183Y561161D01*
G01X1714533Y561536D02*
X1714783Y561328D01*
X1715075Y561203D01*
X1715450Y561161D01*
X1715825Y561244D01*
X1716117Y561411D01*
X1716325Y561703D01*
X1716367Y562036D01*
X1716283Y562369D01*
X1716075Y562578D01*
X1715783Y562744D01*
X1715492Y562786D01*
X1715200Y562744D01*
X1714825Y562578D01*
X1714950Y563661D01*
X1716075D01*
G01X1717758Y562203D02*
X1718050Y562494D01*
X1718300Y562661D01*
X1718633Y562744D01*
X1718925Y562661D01*
X1719133Y562494D01*
X1719300Y562244D01*
X1719342Y561953D01*
X1719300Y561703D01*
X1719133Y561453D01*
X1718883Y561244D01*
X1718592Y561161D01*
X1718258Y561244D01*
X1717967Y561494D01*
X1717800Y561869D01*
X1717758Y562286D01*
X1717842Y562828D01*
X1717967Y563119D01*
X1718175Y563411D01*
X1718467Y563619D01*
X1718758Y563661D01*
X1719050Y563578D01*
X1719258Y563369D01*
G01X1721650Y561161D02*
X1721942Y561203D01*
X1722275Y561328D01*
X1722483Y561536D01*
X1722567Y561828D01*
X1722483Y562119D01*
X1722233Y562369D01*
X1721858Y562494D01*
X1721442D01*
X1721192Y562578D01*
X1720983Y562786D01*
X1720900Y563078D01*
X1721025Y563369D01*
X1721317Y563578D01*
X1721650Y563661D01*
X1721983Y563578D01*
X1722275Y563369D01*
X1722400Y563078D01*
X1722317Y562786D01*
X1722108Y562578D01*
X1721858Y562494D01*
X1721442D01*
X1721067Y562369D01*
X1720817Y562119D01*
X1720733Y561828D01*
X1720817Y561536D01*
X1721025Y561328D01*
X1721358Y561203D01*
X1721650Y561161D01*
G01X1709700Y560500D02*
Y564500D01*
X1702300D01*
G01X1712017Y532000D02*
Y534500D01*
X1713058D01*
X1713392Y534375D01*
X1713600Y534208D01*
X1713683Y533875D01*
X1713600Y533542D01*
X1713350Y533333D01*
X1713058Y533208D01*
X1712017D01*
G01X1713058D02*
X1713683Y532000D01*
G01X1715033Y532375D02*
X1715283Y532167D01*
X1715575Y532042D01*
X1715950Y532000D01*
X1716325Y532083D01*
X1716617Y532250D01*
X1716825Y532542D01*
X1716867Y532875D01*
X1716783Y533208D01*
X1716575Y533417D01*
X1716283Y533583D01*
X1715992Y533625D01*
X1715700Y533583D01*
X1715325Y533417D01*
X1715450Y534500D01*
X1716575D01*
G01X1718258Y533042D02*
X1718550Y533333D01*
X1718800Y533500D01*
X1719133Y533583D01*
X1719425Y533500D01*
X1719633Y533333D01*
X1719800Y533083D01*
X1719842Y532792D01*
X1719800Y532542D01*
X1719633Y532292D01*
X1719383Y532083D01*
X1719092Y532000D01*
X1718758Y532083D01*
X1718467Y532333D01*
X1718300Y532708D01*
X1718258Y533125D01*
X1718342Y533667D01*
X1718467Y533958D01*
X1718675Y534250D01*
X1718967Y534458D01*
X1719258Y534500D01*
X1719550Y534417D01*
X1719758Y534208D01*
G01X1721442Y532292D02*
X1721733Y532083D01*
X1722067Y532000D01*
X1722400Y532083D01*
X1722692Y532333D01*
X1722900Y532708D01*
X1722983Y533083D01*
Y533542D01*
X1722900Y533917D01*
X1722692Y534250D01*
X1722442Y534417D01*
X1722150Y534500D01*
X1721817Y534417D01*
X1721567Y534250D01*
X1721400Y534000D01*
X1721317Y533667D01*
X1721400Y533375D01*
X1721608Y533083D01*
X1721858Y532917D01*
X1722150Y532875D01*
X1722483Y532958D01*
X1722733Y533167D01*
X1722983Y533542D01*
G01X1699800Y535500D02*
Y531500D01*
X1707200D01*
G01X1706839Y510517D02*
X1704339D01*
Y511558D01*
X1704464Y511892D01*
X1704631Y512100D01*
X1704964Y512183D01*
X1705297Y512100D01*
X1705506Y511850D01*
X1705631Y511558D01*
Y510517D01*
G01Y511558D02*
X1706839Y512183D01*
G01X1706464Y513533D02*
X1706672Y513783D01*
X1706797Y514075D01*
X1706839Y514450D01*
X1706756Y514825D01*
X1706589Y515117D01*
X1706297Y515325D01*
X1705964Y515367D01*
X1705631Y515283D01*
X1705422Y515075D01*
X1705256Y514783D01*
X1705214Y514492D01*
X1705256Y514200D01*
X1705422Y513825D01*
X1704339Y513950D01*
Y515075D01*
G01X1706839Y517467D02*
X1706297Y517550D01*
X1705839Y517675D01*
X1705422Y517842D01*
X1704964Y518050D01*
X1704339Y518383D01*
Y516717D01*
G01Y520650D02*
X1704422Y520317D01*
X1704631Y520067D01*
X1704881Y519900D01*
X1705214Y519775D01*
X1705589Y519733D01*
X1705964Y519775D01*
X1706297Y519900D01*
X1706547Y520067D01*
X1706756Y520317D01*
X1706839Y520650D01*
X1706756Y520983D01*
X1706547Y521233D01*
X1706297Y521400D01*
X1705964Y521525D01*
X1705589Y521567D01*
X1705214Y521525D01*
X1704881Y521400D01*
X1704631Y521233D01*
X1704422Y520983D01*
X1704339Y520650D01*
G01X1692500Y515300D02*
X1696500D01*
Y522700D01*
G01X1708242Y484245D02*
Y486745D01*
X1709283D01*
X1709617Y486620D01*
X1709825Y486453D01*
X1709908Y486120D01*
X1709825Y485787D01*
X1709575Y485578D01*
X1709283Y485453D01*
X1708242D01*
G01X1709283D02*
X1709908Y484245D01*
G01X1712175D02*
Y486745D01*
X1711675Y486245D01*
G01Y484245D02*
X1712675D01*
G01X1715275D02*
Y486745D01*
X1714775Y486245D01*
G01Y484245D02*
X1715775D01*
G01X1717583Y485287D02*
X1717875Y485578D01*
X1718125Y485745D01*
X1718458Y485828D01*
X1718750Y485745D01*
X1718958Y485578D01*
X1719125Y485328D01*
X1719167Y485037D01*
X1719125Y484787D01*
X1718958Y484537D01*
X1718708Y484328D01*
X1718417Y484245D01*
X1718083Y484328D01*
X1717792Y484578D01*
X1717625Y484953D01*
X1717583Y485370D01*
X1717667Y485912D01*
X1717792Y486203D01*
X1718000Y486495D01*
X1718292Y486703D01*
X1718583Y486745D01*
X1718875Y486662D01*
X1719083Y486453D01*
G01X1721975Y484245D02*
Y486745D01*
X1720433Y484953D01*
X1722517D01*
G01X1708240Y488311D02*
Y490811D01*
X1709281D01*
X1709615Y490686D01*
X1709823Y490519D01*
X1709906Y490186D01*
X1709823Y489853D01*
X1709573Y489644D01*
X1709281Y489519D01*
X1708240D01*
G01X1709281D02*
X1709906Y488311D01*
G01X1712173D02*
Y490811D01*
X1711673Y490311D01*
G01Y488311D02*
X1712673D01*
G01X1715273D02*
Y490811D01*
X1714773Y490311D01*
G01Y488311D02*
X1715773D01*
G01X1717581Y489353D02*
X1717873Y489644D01*
X1718123Y489811D01*
X1718456Y489894D01*
X1718748Y489811D01*
X1718956Y489644D01*
X1719123Y489394D01*
X1719165Y489103D01*
X1719123Y488853D01*
X1718956Y488603D01*
X1718706Y488394D01*
X1718415Y488311D01*
X1718081Y488394D01*
X1717790Y488644D01*
X1717623Y489019D01*
X1717581Y489436D01*
X1717665Y489978D01*
X1717790Y490269D01*
X1717998Y490561D01*
X1718290Y490769D01*
X1718581Y490811D01*
X1718873Y490728D01*
X1719081Y490519D01*
G01X1720556Y488686D02*
X1720806Y488478D01*
X1721098Y488353D01*
X1721473Y488311D01*
X1721848Y488394D01*
X1722140Y488561D01*
X1722348Y488853D01*
X1722390Y489186D01*
X1722306Y489519D01*
X1722098Y489728D01*
X1721806Y489894D01*
X1721515Y489936D01*
X1721223Y489894D01*
X1720848Y489728D01*
X1720973Y490811D01*
X1722098D01*
G01X1690172Y479817D02*
Y482317D01*
X1691213D01*
X1691547Y482192D01*
X1691755Y482025D01*
X1691838Y481692D01*
X1691755Y481359D01*
X1691505Y481150D01*
X1691213Y481025D01*
X1690172D01*
G01X1691213D02*
X1691838Y479817D01*
G01X1694105D02*
Y482317D01*
X1693605Y481817D01*
G01Y479817D02*
X1694605D01*
G01X1697205D02*
Y482317D01*
X1696705Y481817D01*
G01Y479817D02*
X1697705D01*
G01X1699513Y480859D02*
X1699805Y481150D01*
X1700055Y481317D01*
X1700388Y481400D01*
X1700680Y481317D01*
X1700888Y481150D01*
X1701055Y480900D01*
X1701097Y480609D01*
X1701055Y480359D01*
X1700888Y480109D01*
X1700638Y479900D01*
X1700347Y479817D01*
X1700013Y479900D01*
X1699722Y480150D01*
X1699555Y480525D01*
X1699513Y480942D01*
X1699597Y481484D01*
X1699722Y481775D01*
X1699930Y482067D01*
X1700222Y482275D01*
X1700513Y482317D01*
X1700805Y482234D01*
X1701013Y482025D01*
G01X1703405Y479817D02*
X1703697Y479859D01*
X1704030Y479984D01*
X1704238Y480192D01*
X1704322Y480484D01*
X1704238Y480775D01*
X1703988Y481025D01*
X1703613Y481150D01*
X1703197D01*
X1702947Y481234D01*
X1702738Y481442D01*
X1702655Y481734D01*
X1702780Y482025D01*
X1703072Y482234D01*
X1703405Y482317D01*
X1703738Y482234D01*
X1704030Y482025D01*
X1704155Y481734D01*
X1704072Y481442D01*
X1703863Y481234D01*
X1703613Y481150D01*
X1703197D01*
X1702822Y481025D01*
X1702572Y480775D01*
X1702488Y480484D01*
X1702572Y480192D01*
X1702780Y479984D01*
X1703113Y479859D01*
X1703405Y479817D01*
G01X1677350Y559000D02*
X1677017Y559042D01*
X1676725Y559208D01*
X1676475Y559458D01*
X1676308Y559750D01*
X1676225Y560083D01*
Y560417D01*
X1676308Y560750D01*
X1676475Y561042D01*
X1676725Y561292D01*
X1677017Y561458D01*
X1677350Y561500D01*
X1677683Y561458D01*
X1677975Y561292D01*
X1678225Y561042D01*
X1678392Y560750D01*
X1678475Y560417D01*
Y560083D01*
X1678392Y559750D01*
X1678225Y559458D01*
X1677975Y559208D01*
X1677683Y559042D01*
X1677350Y559000D01*
G01X1677683Y559667D02*
X1678183Y559000D01*
G01X1680450D02*
Y561500D01*
X1679950Y561000D01*
G01Y559000D02*
X1680950D01*
G01X1683550Y561500D02*
X1683217Y561417D01*
X1682967Y561208D01*
X1682800Y560958D01*
X1682675Y560625D01*
X1682633Y560250D01*
X1682675Y559875D01*
X1682800Y559542D01*
X1682967Y559292D01*
X1683217Y559083D01*
X1683550Y559000D01*
X1683883Y559083D01*
X1684133Y559292D01*
X1684300Y559542D01*
X1684425Y559875D01*
X1684467Y560250D01*
X1684425Y560625D01*
X1684300Y560958D01*
X1684133Y561208D01*
X1683883Y561417D01*
X1683550Y561500D01*
G01X1686650D02*
X1686317Y561417D01*
X1686067Y561208D01*
X1685900Y560958D01*
X1685775Y560625D01*
X1685733Y560250D01*
X1685775Y559875D01*
X1685900Y559542D01*
X1686067Y559292D01*
X1686317Y559083D01*
X1686650Y559000D01*
X1686983Y559083D01*
X1687233Y559292D01*
X1687400Y559542D01*
X1687525Y559875D01*
X1687567Y560250D01*
X1687525Y560625D01*
X1687400Y560958D01*
X1687233Y561208D01*
X1686983Y561417D01*
X1686650Y561500D01*
G01X1693000Y557700D02*
X1691200Y555600D01*
X1689000Y557700D01*
G01X1685400Y557800D02*
Y538600D01*
X1696600D01*
Y557800D01*
X1685400D01*
Y557400D01*
G01X1710983Y525500D02*
Y528000D01*
X1711817D01*
X1712150Y527875D01*
X1712400Y527708D01*
X1712608Y527458D01*
X1712775Y527167D01*
X1712817Y526750D01*
X1712775Y526333D01*
X1712608Y526042D01*
X1712400Y525792D01*
X1712150Y525625D01*
X1711817Y525500D01*
X1710983D01*
G01X1714208Y527583D02*
X1714458Y527833D01*
X1714750Y527958D01*
X1715083Y528000D01*
X1715500Y527917D01*
X1715792Y527708D01*
X1715875Y527458D01*
X1715833Y527208D01*
X1715667Y527000D01*
X1714833Y526583D01*
X1714458Y526292D01*
X1714208Y525875D01*
X1714125Y525500D01*
X1715875D01*
G01X1718100D02*
Y528000D01*
X1717600Y527500D01*
G01Y525500D02*
X1718600D01*
G01X1709000Y523500D02*
X1692900D01*
G01X1709000Y530500D02*
Y523500D01*
G01X1692900Y530500D02*
X1709000D01*
G01X1692900Y523500D02*
Y530500D01*
G01X1671500Y510350D02*
X1671458Y510017D01*
X1671292Y509725D01*
X1671042Y509475D01*
X1670750Y509308D01*
X1670417Y509225D01*
X1670083D01*
X1669750Y509308D01*
X1669458Y509475D01*
X1669208Y509725D01*
X1669042Y510017D01*
X1669000Y510350D01*
X1669042Y510683D01*
X1669208Y510975D01*
X1669458Y511225D01*
X1669750Y511392D01*
X1670083Y511475D01*
X1670417D01*
X1670750Y511392D01*
X1671042Y511225D01*
X1671292Y510975D01*
X1671458Y510683D01*
X1671500Y510350D01*
G01X1670833Y510683D02*
X1671500Y511183D01*
G01Y513450D02*
X1669000D01*
X1669500Y512950D01*
G01X1671500D02*
Y513950D01*
G01X1669000Y516550D02*
X1669083Y516217D01*
X1669292Y515967D01*
X1669542Y515800D01*
X1669875Y515675D01*
X1670250Y515633D01*
X1670625Y515675D01*
X1670958Y515800D01*
X1671208Y515967D01*
X1671417Y516217D01*
X1671500Y516550D01*
X1671417Y516883D01*
X1671208Y517133D01*
X1670958Y517300D01*
X1670625Y517425D01*
X1670250Y517467D01*
X1669875Y517425D01*
X1669542Y517300D01*
X1669292Y517133D01*
X1669083Y516883D01*
X1669000Y516550D01*
G01X1671500Y519650D02*
X1669000D01*
X1669500Y519150D01*
G01X1671500D02*
Y520150D01*
G01X1673300Y522700D02*
Y511300D01*
G01X1686700Y522700D02*
X1673300D01*
G01X1686700Y511300D02*
Y522700D01*
G01X1673300Y511300D02*
X1686700D01*
G01X1674017Y570500D02*
Y573000D01*
X1675058D01*
X1675392Y572875D01*
X1675600Y572708D01*
X1675683Y572375D01*
X1675600Y572042D01*
X1675350Y571833D01*
X1675058Y571708D01*
X1674017D01*
G01X1675058D02*
X1675683Y570500D01*
G01X1677033Y570875D02*
X1677283Y570667D01*
X1677575Y570542D01*
X1677950Y570500D01*
X1678325Y570583D01*
X1678617Y570750D01*
X1678825Y571042D01*
X1678867Y571375D01*
X1678783Y571708D01*
X1678575Y571917D01*
X1678283Y572083D01*
X1677992Y572125D01*
X1677700Y572083D01*
X1677325Y571917D01*
X1677450Y573000D01*
X1678575D01*
G01X1680133Y570875D02*
X1680383Y570667D01*
X1680675Y570542D01*
X1681050Y570500D01*
X1681425Y570583D01*
X1681717Y570750D01*
X1681925Y571042D01*
X1681967Y571375D01*
X1681883Y571708D01*
X1681675Y571917D01*
X1681383Y572083D01*
X1681092Y572125D01*
X1680800Y572083D01*
X1680425Y571917D01*
X1680550Y573000D01*
X1681675D01*
G01X1683358Y572583D02*
X1683608Y572833D01*
X1683900Y572958D01*
X1684233Y573000D01*
X1684650Y572917D01*
X1684942Y572708D01*
X1685025Y572458D01*
X1684983Y572208D01*
X1684817Y572000D01*
X1683983Y571583D01*
X1683608Y571292D01*
X1683358Y570875D01*
X1683275Y570500D01*
X1685025D01*
G01X1642275Y662000D02*
Y664500D01*
G01X1644025D02*
Y662000D01*
G01Y663250D02*
X1642275D01*
G01X1645333Y662000D02*
Y664500D01*
X1646167D01*
X1646500Y664375D01*
X1646750Y664208D01*
X1646958Y663958D01*
X1647125Y663667D01*
X1647167Y663250D01*
X1647125Y662833D01*
X1646958Y662542D01*
X1646750Y662292D01*
X1646500Y662125D01*
X1646167Y662000D01*
X1645333D01*
G01X1648433D02*
Y664500D01*
X1649267D01*
X1649600Y664375D01*
X1649850Y664208D01*
X1650058Y663958D01*
X1650225Y663667D01*
X1650267Y663250D01*
X1650225Y662833D01*
X1650058Y662542D01*
X1649850Y662292D01*
X1649600Y662125D01*
X1649267Y662000D01*
X1648433D01*
G01X1651575Y662333D02*
X1651908Y662125D01*
X1652283Y662000D01*
X1652617D01*
X1652950Y662125D01*
X1653200Y662333D01*
X1653325Y662625D01*
X1653242Y662917D01*
X1653033Y663167D01*
X1652658Y663333D01*
X1652158Y663417D01*
X1651867Y663583D01*
X1651742Y663875D01*
X1651825Y664167D01*
X1652033Y664375D01*
X1652325Y664500D01*
X1652617D01*
X1652908Y664417D01*
X1653158Y664208D01*
G01X1654508Y662000D02*
X1655550Y664500D01*
X1656592Y662000D01*
G01X1656217Y662875D02*
X1654883D01*
G01X1657775Y662333D02*
X1658108Y662125D01*
X1658483Y662000D01*
X1658817D01*
X1659150Y662125D01*
X1659400Y662333D01*
X1659525Y662625D01*
X1659442Y662917D01*
X1659233Y663167D01*
X1658858Y663333D01*
X1658358Y663417D01*
X1658067Y663583D01*
X1657942Y663875D01*
X1658025Y664167D01*
X1658233Y664375D01*
X1658525Y664500D01*
X1658817D01*
X1659108Y664417D01*
X1659358Y664208D01*
G01X1660958Y664083D02*
X1661208Y664333D01*
X1661500Y664458D01*
X1661833Y664500D01*
X1662250Y664417D01*
X1662542Y664208D01*
X1662625Y663958D01*
X1662583Y663708D01*
X1662417Y663500D01*
X1661583Y663083D01*
X1661208Y662792D01*
X1660958Y662375D01*
X1660875Y662000D01*
X1662625D01*
G01X1664850D02*
Y664500D01*
X1664350Y664000D01*
G01Y662000D02*
X1665350D01*
G01X1637247Y584567D02*
X1637122Y584317D01*
X1637039Y584025D01*
Y583692D01*
X1637164Y583317D01*
X1637372Y583025D01*
X1637622Y582817D01*
X1638039Y582650D01*
X1638414Y582608D01*
X1638789Y582692D01*
X1639039Y582817D01*
X1639289Y583067D01*
X1639456Y583358D01*
X1639539Y583650D01*
Y583942D01*
X1639456Y584233D01*
X1639331Y584483D01*
X1639164Y584692D01*
G01X1639039Y585833D02*
X1639331Y586083D01*
X1639497Y586417D01*
X1639539Y586792D01*
X1639497Y587125D01*
X1639289Y587458D01*
X1639039Y587667D01*
X1638789Y587708D01*
X1638497Y587625D01*
X1638289Y587333D01*
X1638206Y587042D01*
Y586667D01*
G01Y587042D02*
X1638081Y587292D01*
X1637872Y587500D01*
X1637622Y587583D01*
X1637372Y587500D01*
X1637164Y587292D01*
X1637039Y586917D01*
X1637081Y586542D01*
X1637247Y586167D01*
G01X1639539Y589850D02*
X1637039D01*
X1637539Y589350D01*
G01X1639539D02*
Y590350D01*
G01X1637039Y592950D02*
X1637122Y592617D01*
X1637331Y592367D01*
X1637581Y592200D01*
X1637914Y592075D01*
X1638289Y592033D01*
X1638664Y592075D01*
X1638997Y592200D01*
X1639247Y592367D01*
X1639456Y592617D01*
X1639539Y592950D01*
X1639456Y593283D01*
X1639247Y593533D01*
X1638997Y593700D01*
X1638664Y593825D01*
X1638289Y593867D01*
X1637914Y593825D01*
X1637581Y593700D01*
X1637331Y593533D01*
X1637122Y593283D01*
X1637039Y592950D01*
G01X1635539Y582817D02*
X1633039D01*
Y583858D01*
X1633164Y584192D01*
X1633331Y584400D01*
X1633664Y584483D01*
X1633997Y584400D01*
X1634206Y584150D01*
X1634331Y583858D01*
Y582817D01*
G01Y583858D02*
X1635539Y584483D01*
G01X1635164Y585833D02*
X1635372Y586083D01*
X1635497Y586375D01*
X1635539Y586750D01*
X1635456Y587125D01*
X1635289Y587417D01*
X1634997Y587625D01*
X1634664Y587667D01*
X1634331Y587583D01*
X1634122Y587375D01*
X1633956Y587083D01*
X1633914Y586792D01*
X1633956Y586500D01*
X1634122Y586125D01*
X1633039Y586250D01*
Y587375D01*
G01X1635164Y588933D02*
X1635372Y589183D01*
X1635497Y589475D01*
X1635539Y589850D01*
X1635456Y590225D01*
X1635289Y590517D01*
X1634997Y590725D01*
X1634664Y590767D01*
X1634331Y590683D01*
X1634122Y590475D01*
X1633956Y590183D01*
X1633914Y589892D01*
X1633956Y589600D01*
X1634122Y589225D01*
X1633039Y589350D01*
Y590475D01*
G01X1635039Y592033D02*
X1635331Y592283D01*
X1635497Y592617D01*
X1635539Y592992D01*
X1635497Y593325D01*
X1635289Y593658D01*
X1635039Y593867D01*
X1634789Y593908D01*
X1634497Y593825D01*
X1634289Y593533D01*
X1634206Y593242D01*
Y592867D01*
G01Y593242D02*
X1634081Y593492D01*
X1633872Y593700D01*
X1633622Y593783D01*
X1633372Y593700D01*
X1633164Y593492D01*
X1633039Y593117D01*
X1633081Y592742D01*
X1633247Y592367D01*
G01X1632200Y573600D02*
X1636200D01*
Y581000D01*
G01X1669703Y610576D02*
X1669578Y610326D01*
X1669495Y610034D01*
Y609701D01*
X1669620Y609326D01*
X1669828Y609034D01*
X1670078Y608826D01*
X1670495Y608659D01*
X1670870Y608617D01*
X1671245Y608701D01*
X1671495Y608826D01*
X1671745Y609076D01*
X1671912Y609367D01*
X1671995Y609659D01*
Y609951D01*
X1671912Y610242D01*
X1671787Y610492D01*
X1671620Y610701D01*
G01X1671495Y611842D02*
X1671787Y612092D01*
X1671953Y612426D01*
X1671995Y612801D01*
X1671953Y613134D01*
X1671745Y613467D01*
X1671495Y613676D01*
X1671245Y613717D01*
X1670953Y613634D01*
X1670745Y613342D01*
X1670662Y613051D01*
Y612676D01*
G01Y613051D02*
X1670537Y613301D01*
X1670328Y613509D01*
X1670078Y613592D01*
X1669828Y613509D01*
X1669620Y613301D01*
X1669495Y612926D01*
X1669537Y612551D01*
X1669703Y612176D01*
G01X1669495Y615859D02*
X1669578Y615526D01*
X1669787Y615276D01*
X1670037Y615109D01*
X1670370Y614984D01*
X1670745Y614942D01*
X1671120Y614984D01*
X1671453Y615109D01*
X1671703Y615276D01*
X1671912Y615526D01*
X1671995Y615859D01*
X1671912Y616192D01*
X1671703Y616442D01*
X1671453Y616609D01*
X1671120Y616734D01*
X1670745Y616776D01*
X1670370Y616734D01*
X1670037Y616609D01*
X1669787Y616442D01*
X1669578Y616192D01*
X1669495Y615859D01*
G01X1671495Y618042D02*
X1671787Y618292D01*
X1671953Y618626D01*
X1671995Y619001D01*
X1671953Y619334D01*
X1671745Y619667D01*
X1671495Y619876D01*
X1671245Y619917D01*
X1670953Y619834D01*
X1670745Y619542D01*
X1670662Y619251D01*
Y618876D01*
G01Y619251D02*
X1670537Y619501D01*
X1670328Y619709D01*
X1670078Y619792D01*
X1669828Y619709D01*
X1669620Y619501D01*
X1669495Y619126D01*
X1669537Y618751D01*
X1669703Y618376D01*
G01X1669708Y643267D02*
X1669583Y643017D01*
X1669500Y642725D01*
Y642392D01*
X1669625Y642017D01*
X1669833Y641725D01*
X1670083Y641517D01*
X1670500Y641350D01*
X1670875Y641308D01*
X1671250Y641392D01*
X1671500Y641517D01*
X1671750Y641767D01*
X1671917Y642058D01*
X1672000Y642350D01*
Y642642D01*
X1671917Y642933D01*
X1671792Y643183D01*
X1671625Y643392D01*
G01X1671500Y644533D02*
X1671792Y644783D01*
X1671958Y645117D01*
X1672000Y645492D01*
X1671958Y645825D01*
X1671750Y646158D01*
X1671500Y646367D01*
X1671250Y646408D01*
X1670958Y646325D01*
X1670750Y646033D01*
X1670667Y645742D01*
Y645367D01*
G01Y645742D02*
X1670542Y645992D01*
X1670333Y646200D01*
X1670083Y646283D01*
X1669833Y646200D01*
X1669625Y645992D01*
X1669500Y645617D01*
X1669542Y645242D01*
X1669708Y644867D01*
G01X1669500Y648550D02*
X1669583Y648217D01*
X1669792Y647967D01*
X1670042Y647800D01*
X1670375Y647675D01*
X1670750Y647633D01*
X1671125Y647675D01*
X1671458Y647800D01*
X1671708Y647967D01*
X1671917Y648217D01*
X1672000Y648550D01*
X1671917Y648883D01*
X1671708Y649133D01*
X1671458Y649300D01*
X1671125Y649425D01*
X1670750Y649467D01*
X1670375Y649425D01*
X1670042Y649300D01*
X1669792Y649133D01*
X1669583Y648883D01*
X1669500Y648550D01*
G01X1671708Y650942D02*
X1671917Y651233D01*
X1672000Y651567D01*
X1671917Y651900D01*
X1671667Y652192D01*
X1671292Y652400D01*
X1670917Y652483D01*
X1670458D01*
X1670083Y652400D01*
X1669750Y652192D01*
X1669583Y651942D01*
X1669500Y651650D01*
X1669583Y651317D01*
X1669750Y651067D01*
X1670000Y650900D01*
X1670333Y650817D01*
X1670625Y650900D01*
X1670917Y651108D01*
X1671083Y651358D01*
X1671125Y651650D01*
X1671042Y651983D01*
X1670833Y652233D01*
X1670458Y652483D01*
G01X1697850Y599000D02*
X1697517Y599042D01*
X1697225Y599208D01*
X1696975Y599458D01*
X1696808Y599750D01*
X1696725Y600083D01*
Y600417D01*
X1696808Y600750D01*
X1696975Y601042D01*
X1697225Y601292D01*
X1697517Y601458D01*
X1697850Y601500D01*
X1698183Y601458D01*
X1698475Y601292D01*
X1698725Y601042D01*
X1698892Y600750D01*
X1698975Y600417D01*
Y600083D01*
X1698892Y599750D01*
X1698725Y599458D01*
X1698475Y599208D01*
X1698183Y599042D01*
X1697850Y599000D01*
G01X1698183Y599667D02*
X1698683Y599000D01*
G01X1700950D02*
Y601500D01*
X1700450Y601000D01*
G01Y599000D02*
X1701450D01*
G01X1704050Y601500D02*
X1703717Y601417D01*
X1703467Y601208D01*
X1703300Y600958D01*
X1703175Y600625D01*
X1703133Y600250D01*
X1703175Y599875D01*
X1703300Y599542D01*
X1703467Y599292D01*
X1703717Y599083D01*
X1704050Y599000D01*
X1704383Y599083D01*
X1704633Y599292D01*
X1704800Y599542D01*
X1704925Y599875D01*
X1704967Y600250D01*
X1704925Y600625D01*
X1704800Y600958D01*
X1704633Y601208D01*
X1704383Y601417D01*
X1704050Y601500D01*
G01X1706358Y601083D02*
X1706608Y601333D01*
X1706900Y601458D01*
X1707233Y601500D01*
X1707650Y601417D01*
X1707942Y601208D01*
X1708025Y600958D01*
X1707983Y600708D01*
X1707817Y600500D01*
X1706983Y600083D01*
X1706608Y599792D01*
X1706358Y599375D01*
X1706275Y599000D01*
X1708025D01*
G01X1687800Y585000D02*
X1689900Y583200D01*
X1687800Y581000D01*
G01X1687700Y577400D02*
X1706900D01*
Y588600D01*
X1687700D01*
Y577400D01*
X1688100D01*
G01X1673703Y609576D02*
X1673578Y609326D01*
X1673495Y609034D01*
Y608701D01*
X1673620Y608326D01*
X1673828Y608034D01*
X1674078Y607826D01*
X1674495Y607659D01*
X1674870Y607617D01*
X1675245Y607701D01*
X1675495Y607826D01*
X1675745Y608076D01*
X1675912Y608367D01*
X1675995Y608659D01*
Y608951D01*
X1675912Y609242D01*
X1675787Y609492D01*
X1675620Y609701D01*
G01X1675495Y610842D02*
X1675787Y611092D01*
X1675953Y611426D01*
X1675995Y611801D01*
X1675953Y612134D01*
X1675745Y612467D01*
X1675495Y612676D01*
X1675245Y612717D01*
X1674953Y612634D01*
X1674745Y612342D01*
X1674662Y612051D01*
Y611676D01*
G01Y612051D02*
X1674537Y612301D01*
X1674328Y612509D01*
X1674078Y612592D01*
X1673828Y612509D01*
X1673620Y612301D01*
X1673495Y611926D01*
X1673537Y611551D01*
X1673703Y611176D01*
G01X1673495Y614859D02*
X1673578Y614526D01*
X1673787Y614276D01*
X1674037Y614109D01*
X1674370Y613984D01*
X1674745Y613942D01*
X1675120Y613984D01*
X1675453Y614109D01*
X1675703Y614276D01*
X1675912Y614526D01*
X1675995Y614859D01*
X1675912Y615192D01*
X1675703Y615442D01*
X1675453Y615609D01*
X1675120Y615734D01*
X1674745Y615776D01*
X1674370Y615734D01*
X1674037Y615609D01*
X1673787Y615442D01*
X1673578Y615192D01*
X1673495Y614859D01*
G01X1675995Y618459D02*
X1673495D01*
X1675287Y616917D01*
Y619001D01*
G01X1677000Y589200D02*
Y594700D01*
G01X1685000Y589200D02*
X1677000D01*
G01X1685000Y594700D02*
Y589200D01*
G01Y606800D02*
Y601300D01*
G01X1677000Y606800D02*
X1685000D01*
G01X1677000Y601300D02*
Y606800D01*
G01X1686300Y583000D02*
Y575000D01*
X1668700D01*
Y583000D01*
X1686300D01*
G01X1683617Y618000D02*
Y620500D01*
X1684658D01*
X1684992Y620375D01*
X1685200Y620208D01*
X1685283Y619875D01*
X1685200Y619542D01*
X1684950Y619333D01*
X1684658Y619208D01*
X1683617D01*
G01X1684658D02*
X1685283Y618000D01*
G01X1686633Y618375D02*
X1686883Y618167D01*
X1687175Y618042D01*
X1687550Y618000D01*
X1687925Y618083D01*
X1688217Y618250D01*
X1688425Y618542D01*
X1688467Y618875D01*
X1688383Y619208D01*
X1688175Y619417D01*
X1687883Y619583D01*
X1687592Y619625D01*
X1687300Y619583D01*
X1686925Y619417D01*
X1687050Y620500D01*
X1688175D01*
G01X1689733Y618375D02*
X1689983Y618167D01*
X1690275Y618042D01*
X1690650Y618000D01*
X1691025Y618083D01*
X1691317Y618250D01*
X1691525Y618542D01*
X1691567Y618875D01*
X1691483Y619208D01*
X1691275Y619417D01*
X1690983Y619583D01*
X1690692Y619625D01*
X1690400Y619583D01*
X1690025Y619417D01*
X1690150Y620500D01*
X1691275D01*
G01X1694250Y618000D02*
Y620500D01*
X1692708Y618708D01*
X1694792D01*
G01X1694900Y616500D02*
Y608500D01*
X1677300D01*
Y616500D01*
X1694900D01*
G01X1676047Y643267D02*
X1675922Y643017D01*
X1675839Y642725D01*
Y642392D01*
X1675964Y642017D01*
X1676172Y641725D01*
X1676422Y641517D01*
X1676839Y641350D01*
X1677214Y641308D01*
X1677589Y641392D01*
X1677839Y641517D01*
X1678089Y641767D01*
X1678256Y642058D01*
X1678339Y642350D01*
Y642642D01*
X1678256Y642933D01*
X1678131Y643183D01*
X1677964Y643392D01*
G01X1677839Y644533D02*
X1678131Y644783D01*
X1678297Y645117D01*
X1678339Y645492D01*
X1678297Y645825D01*
X1678089Y646158D01*
X1677839Y646367D01*
X1677589Y646408D01*
X1677297Y646325D01*
X1677089Y646033D01*
X1677006Y645742D01*
Y645367D01*
G01Y645742D02*
X1676881Y645992D01*
X1676672Y646200D01*
X1676422Y646283D01*
X1676172Y646200D01*
X1675964Y645992D01*
X1675839Y645617D01*
X1675881Y645242D01*
X1676047Y644867D01*
G01X1675839Y648550D02*
X1675922Y648217D01*
X1676131Y647967D01*
X1676381Y647800D01*
X1676714Y647675D01*
X1677089Y647633D01*
X1677464Y647675D01*
X1677797Y647800D01*
X1678047Y647967D01*
X1678256Y648217D01*
X1678339Y648550D01*
X1678256Y648883D01*
X1678047Y649133D01*
X1677797Y649300D01*
X1677464Y649425D01*
X1677089Y649467D01*
X1676714Y649425D01*
X1676381Y649300D01*
X1676131Y649133D01*
X1675922Y648883D01*
X1675839Y648550D01*
G01X1678339Y651567D02*
X1677797Y651650D01*
X1677339Y651775D01*
X1676922Y651942D01*
X1676464Y652150D01*
X1675839Y652483D01*
Y650817D01*
G01X1684047Y643267D02*
X1683922Y643017D01*
X1683839Y642725D01*
Y642392D01*
X1683964Y642017D01*
X1684172Y641725D01*
X1684422Y641517D01*
X1684839Y641350D01*
X1685214Y641308D01*
X1685589Y641392D01*
X1685839Y641517D01*
X1686089Y641767D01*
X1686256Y642058D01*
X1686339Y642350D01*
Y642642D01*
X1686256Y642933D01*
X1686131Y643183D01*
X1685964Y643392D01*
G01X1685839Y644533D02*
X1686131Y644783D01*
X1686297Y645117D01*
X1686339Y645492D01*
X1686297Y645825D01*
X1686089Y646158D01*
X1685839Y646367D01*
X1685589Y646408D01*
X1685297Y646325D01*
X1685089Y646033D01*
X1685006Y645742D01*
Y645367D01*
G01Y645742D02*
X1684881Y645992D01*
X1684672Y646200D01*
X1684422Y646283D01*
X1684172Y646200D01*
X1683964Y645992D01*
X1683839Y645617D01*
X1683881Y645242D01*
X1684047Y644867D01*
G01X1683839Y648550D02*
X1683922Y648217D01*
X1684131Y647967D01*
X1684381Y647800D01*
X1684714Y647675D01*
X1685089Y647633D01*
X1685464Y647675D01*
X1685797Y647800D01*
X1686047Y647967D01*
X1686256Y648217D01*
X1686339Y648550D01*
X1686256Y648883D01*
X1686047Y649133D01*
X1685797Y649300D01*
X1685464Y649425D01*
X1685089Y649467D01*
X1684714Y649425D01*
X1684381Y649300D01*
X1684131Y649133D01*
X1683922Y648883D01*
X1683839Y648550D01*
G01X1686339Y651650D02*
X1686297Y651942D01*
X1686172Y652275D01*
X1685964Y652483D01*
X1685672Y652567D01*
X1685381Y652483D01*
X1685131Y652233D01*
X1685006Y651858D01*
Y651442D01*
X1684922Y651192D01*
X1684714Y650983D01*
X1684422Y650900D01*
X1684131Y651025D01*
X1683922Y651317D01*
X1683839Y651650D01*
X1683922Y651983D01*
X1684131Y652275D01*
X1684422Y652400D01*
X1684714Y652317D01*
X1684922Y652108D01*
X1685006Y651858D01*
Y651442D01*
X1685131Y651067D01*
X1685381Y650817D01*
X1685672Y650733D01*
X1685964Y650817D01*
X1686172Y651025D01*
X1686297Y651358D01*
X1686339Y651650D01*
G01X1696517Y835000D02*
Y837500D01*
X1697558D01*
X1697892Y837375D01*
X1698100Y837208D01*
X1698183Y836875D01*
X1698100Y836542D01*
X1697850Y836333D01*
X1697558Y836208D01*
X1696517D01*
G01X1697558D02*
X1698183Y835000D01*
G01X1699533Y835500D02*
X1699783Y835208D01*
X1700117Y835042D01*
X1700492Y835000D01*
X1700825Y835042D01*
X1701158Y835250D01*
X1701367Y835500D01*
X1701408Y835750D01*
X1701325Y836042D01*
X1701033Y836250D01*
X1700742Y836333D01*
X1700367D01*
G01X1700742D02*
X1700992Y836458D01*
X1701200Y836667D01*
X1701283Y836917D01*
X1701200Y837167D01*
X1700992Y837375D01*
X1700617Y837500D01*
X1700242Y837458D01*
X1699867Y837292D01*
G01X1703550Y837500D02*
X1703217Y837417D01*
X1702967Y837208D01*
X1702800Y836958D01*
X1702675Y836625D01*
X1702633Y836250D01*
X1702675Y835875D01*
X1702800Y835542D01*
X1702967Y835292D01*
X1703217Y835083D01*
X1703550Y835000D01*
X1703883Y835083D01*
X1704133Y835292D01*
X1704300Y835542D01*
X1704425Y835875D01*
X1704467Y836250D01*
X1704425Y836625D01*
X1704300Y836958D01*
X1704133Y837208D01*
X1703883Y837417D01*
X1703550Y837500D01*
G01X1705942Y835292D02*
X1706233Y835083D01*
X1706567Y835000D01*
X1706900Y835083D01*
X1707192Y835333D01*
X1707400Y835708D01*
X1707483Y836083D01*
Y836542D01*
X1707400Y836917D01*
X1707192Y837250D01*
X1706942Y837417D01*
X1706650Y837500D01*
X1706317Y837417D01*
X1706067Y837250D01*
X1705900Y837000D01*
X1705817Y836667D01*
X1705900Y836375D01*
X1706108Y836083D01*
X1706358Y835917D01*
X1706650Y835875D01*
X1706983Y835958D01*
X1707233Y836167D01*
X1707483Y836542D01*
G01X1715911Y834182D02*
Y838182D01*
X1708511D01*
G01X1722350Y834500D02*
X1722017Y834542D01*
X1721725Y834708D01*
X1721475Y834958D01*
X1721308Y835250D01*
X1721225Y835583D01*
Y835917D01*
X1721308Y836250D01*
X1721475Y836542D01*
X1721725Y836792D01*
X1722017Y836958D01*
X1722350Y837000D01*
X1722683Y836958D01*
X1722975Y836792D01*
X1723225Y836542D01*
X1723392Y836250D01*
X1723475Y835917D01*
Y835583D01*
X1723392Y835250D01*
X1723225Y834958D01*
X1722975Y834708D01*
X1722683Y834542D01*
X1722350Y834500D01*
G01X1722683Y835167D02*
X1723183Y834500D01*
G01X1724658Y836583D02*
X1724908Y836833D01*
X1725200Y836958D01*
X1725533Y837000D01*
X1725950Y836917D01*
X1726242Y836708D01*
X1726325Y836458D01*
X1726283Y836208D01*
X1726117Y836000D01*
X1725283Y835583D01*
X1724908Y835292D01*
X1724658Y834875D01*
X1724575Y834500D01*
X1726325D01*
G01X1727758Y836583D02*
X1728008Y836833D01*
X1728300Y836958D01*
X1728633Y837000D01*
X1729050Y836917D01*
X1729342Y836708D01*
X1729425Y836458D01*
X1729383Y836208D01*
X1729217Y836000D01*
X1728383Y835583D01*
X1728008Y835292D01*
X1727758Y834875D01*
X1727675Y834500D01*
X1729425D01*
G01X1730942Y834792D02*
X1731233Y834583D01*
X1731567Y834500D01*
X1731900Y834583D01*
X1732192Y834833D01*
X1732400Y835208D01*
X1732483Y835583D01*
Y836042D01*
X1732400Y836417D01*
X1732192Y836750D01*
X1731942Y836917D01*
X1731650Y837000D01*
X1731317Y836917D01*
X1731067Y836750D01*
X1730900Y836500D01*
X1730817Y836167D01*
X1730900Y835875D01*
X1731108Y835583D01*
X1731358Y835417D01*
X1731650Y835375D01*
X1731983Y835458D01*
X1732233Y835667D01*
X1732483Y836042D01*
G01X1718319Y838500D02*
X1731319D01*
G01X1718319Y852500D02*
Y838500D01*
G01X1731319Y852500D02*
X1718319D01*
G01X1705550Y856000D02*
X1705217Y856042D01*
X1704925Y856208D01*
X1704675Y856458D01*
X1704508Y856750D01*
X1704425Y857083D01*
Y857417D01*
X1704508Y857750D01*
X1704675Y858042D01*
X1704925Y858292D01*
X1705217Y858458D01*
X1705550Y858500D01*
X1705883Y858458D01*
X1706175Y858292D01*
X1706425Y858042D01*
X1706592Y857750D01*
X1706675Y857417D01*
Y857083D01*
X1706592Y856750D01*
X1706425Y856458D01*
X1706175Y856208D01*
X1705883Y856042D01*
X1705550Y856000D01*
G01X1705883Y856667D02*
X1706383Y856000D01*
G01X1707858Y858083D02*
X1708108Y858333D01*
X1708400Y858458D01*
X1708733Y858500D01*
X1709150Y858417D01*
X1709442Y858208D01*
X1709525Y857958D01*
X1709483Y857708D01*
X1709317Y857500D01*
X1708483Y857083D01*
X1708108Y856792D01*
X1707858Y856375D01*
X1707775Y856000D01*
X1709525D01*
G01X1710833Y856375D02*
X1711083Y856167D01*
X1711375Y856042D01*
X1711750Y856000D01*
X1712125Y856083D01*
X1712417Y856250D01*
X1712625Y856542D01*
X1712667Y856875D01*
X1712583Y857208D01*
X1712375Y857417D01*
X1712083Y857583D01*
X1711792Y857625D01*
X1711500Y857583D01*
X1711125Y857417D01*
X1711250Y858500D01*
X1712375D01*
G01X1713933Y856500D02*
X1714183Y856208D01*
X1714517Y856042D01*
X1714892Y856000D01*
X1715225Y856042D01*
X1715558Y856250D01*
X1715767Y856500D01*
X1715808Y856750D01*
X1715725Y857042D01*
X1715433Y857250D01*
X1715142Y857333D01*
X1714767D01*
G01X1715142D02*
X1715392Y857458D01*
X1715600Y857667D01*
X1715683Y857917D01*
X1715600Y858167D01*
X1715392Y858375D01*
X1715017Y858500D01*
X1714642Y858458D01*
X1714267Y858292D01*
G01X1703211Y839407D02*
X1717211D01*
G01X1703211Y852407D02*
Y839407D01*
G01X1717211Y852407D02*
X1703211D01*
G01X1717211Y839407D02*
Y852407D01*
G01X1637431Y1012831D02*
X1642481D01*
Y1111531D01*
X1667131D01*
Y927131D01*
X1642481D01*
Y985831D01*
X1637431D01*
Y1012831D01*
G01X1630767Y950292D02*
X1630517Y950417D01*
X1630225Y950500D01*
X1629892D01*
X1629517Y950375D01*
X1629225Y950167D01*
X1629017Y949917D01*
X1628850Y949500D01*
X1628808Y949125D01*
X1628892Y948750D01*
X1629017Y948500D01*
X1629267Y948250D01*
X1629558Y948083D01*
X1629850Y948000D01*
X1630142D01*
X1630433Y948083D01*
X1630683Y948208D01*
X1630892Y948375D01*
G01X1632950Y948000D02*
Y950500D01*
X1632450Y950000D01*
G01Y948000D02*
X1633450D01*
G01X1636550D02*
Y950500D01*
X1635008Y948708D01*
X1637092D01*
G01X1638358Y949042D02*
X1638650Y949333D01*
X1638900Y949500D01*
X1639233Y949583D01*
X1639525Y949500D01*
X1639733Y949333D01*
X1639900Y949083D01*
X1639942Y948792D01*
X1639900Y948542D01*
X1639733Y948292D01*
X1639483Y948083D01*
X1639192Y948000D01*
X1638858Y948083D01*
X1638567Y948333D01*
X1638400Y948708D01*
X1638358Y949125D01*
X1638442Y949667D01*
X1638567Y949958D01*
X1638775Y950250D01*
X1639067Y950458D01*
X1639358Y950500D01*
X1639650Y950417D01*
X1639858Y950208D01*
G01X1630767Y954292D02*
X1630517Y954417D01*
X1630225Y954500D01*
X1629892D01*
X1629517Y954375D01*
X1629225Y954167D01*
X1629017Y953917D01*
X1628850Y953500D01*
X1628808Y953125D01*
X1628892Y952750D01*
X1629017Y952500D01*
X1629267Y952250D01*
X1629558Y952083D01*
X1629850Y952000D01*
X1630142D01*
X1630433Y952083D01*
X1630683Y952208D01*
X1630892Y952375D01*
G01X1632950Y952000D02*
Y954500D01*
X1632450Y954000D01*
G01Y952000D02*
X1633450D01*
G01X1636550D02*
Y954500D01*
X1635008Y952708D01*
X1637092D01*
G01X1638233Y952375D02*
X1638483Y952167D01*
X1638775Y952042D01*
X1639150Y952000D01*
X1639525Y952083D01*
X1639817Y952250D01*
X1640025Y952542D01*
X1640067Y952875D01*
X1639983Y953208D01*
X1639775Y953417D01*
X1639483Y953583D01*
X1639192Y953625D01*
X1638900Y953583D01*
X1638525Y953417D01*
X1638650Y954500D01*
X1639775D01*
G01X1677000Y951517D02*
X1674500D01*
Y952558D01*
X1674625Y952892D01*
X1674792Y953100D01*
X1675125Y953183D01*
X1675458Y953100D01*
X1675667Y952850D01*
X1675792Y952558D01*
Y951517D01*
G01Y952558D02*
X1677000Y953183D01*
G01X1676500Y954533D02*
X1676792Y954783D01*
X1676958Y955117D01*
X1677000Y955492D01*
X1676958Y955825D01*
X1676750Y956158D01*
X1676500Y956367D01*
X1676250Y956408D01*
X1675958Y956325D01*
X1675750Y956033D01*
X1675667Y955742D01*
Y955367D01*
G01Y955742D02*
X1675542Y955992D01*
X1675333Y956200D01*
X1675083Y956283D01*
X1674833Y956200D01*
X1674625Y955992D01*
X1674500Y955617D01*
X1674542Y955242D01*
X1674708Y954867D01*
G01X1674500Y958550D02*
X1674583Y958217D01*
X1674792Y957967D01*
X1675042Y957800D01*
X1675375Y957675D01*
X1675750Y957633D01*
X1676125Y957675D01*
X1676458Y957800D01*
X1676708Y957967D01*
X1676917Y958217D01*
X1677000Y958550D01*
X1676917Y958883D01*
X1676708Y959133D01*
X1676458Y959300D01*
X1676125Y959425D01*
X1675750Y959467D01*
X1675375Y959425D01*
X1675042Y959300D01*
X1674792Y959133D01*
X1674583Y958883D01*
X1674500Y958550D01*
G01X1677000Y961650D02*
X1676958Y961942D01*
X1676833Y962275D01*
X1676625Y962483D01*
X1676333Y962567D01*
X1676042Y962483D01*
X1675792Y962233D01*
X1675667Y961858D01*
Y961442D01*
X1675583Y961192D01*
X1675375Y960983D01*
X1675083Y960900D01*
X1674792Y961025D01*
X1674583Y961317D01*
X1674500Y961650D01*
X1674583Y961983D01*
X1674792Y962275D01*
X1675083Y962400D01*
X1675375Y962317D01*
X1675583Y962108D01*
X1675667Y961858D01*
Y961442D01*
X1675792Y961067D01*
X1676042Y960817D01*
X1676333Y960733D01*
X1676625Y960817D01*
X1676833Y961025D01*
X1676958Y961358D01*
X1677000Y961650D01*
G01X1702500Y951017D02*
X1700000D01*
Y952058D01*
X1700125Y952392D01*
X1700292Y952600D01*
X1700625Y952683D01*
X1700958Y952600D01*
X1701167Y952350D01*
X1701292Y952058D01*
Y951017D01*
G01Y952058D02*
X1702500Y952683D01*
G01X1702000Y954033D02*
X1702292Y954283D01*
X1702458Y954617D01*
X1702500Y954992D01*
X1702458Y955325D01*
X1702250Y955658D01*
X1702000Y955867D01*
X1701750Y955908D01*
X1701458Y955825D01*
X1701250Y955533D01*
X1701167Y955242D01*
Y954867D01*
G01Y955242D02*
X1701042Y955492D01*
X1700833Y955700D01*
X1700583Y955783D01*
X1700333Y955700D01*
X1700125Y955492D01*
X1700000Y955117D01*
X1700042Y954742D01*
X1700208Y954367D01*
G01X1702500Y958050D02*
X1700000D01*
X1700500Y957550D01*
G01X1702500D02*
Y958550D01*
G01X1700000Y961150D02*
X1700083Y960817D01*
X1700292Y960567D01*
X1700542Y960400D01*
X1700875Y960275D01*
X1701250Y960233D01*
X1701625Y960275D01*
X1701958Y960400D01*
X1702208Y960567D01*
X1702417Y960817D01*
X1702500Y961150D01*
X1702417Y961483D01*
X1702208Y961733D01*
X1701958Y961900D01*
X1701625Y962025D01*
X1701250Y962067D01*
X1700875Y962025D01*
X1700542Y961900D01*
X1700292Y961733D01*
X1700083Y961483D01*
X1700000Y961150D01*
G01X1673000Y951517D02*
X1670500D01*
Y952558D01*
X1670625Y952892D01*
X1670792Y953100D01*
X1671125Y953183D01*
X1671458Y953100D01*
X1671667Y952850D01*
X1671792Y952558D01*
Y951517D01*
G01Y952558D02*
X1673000Y953183D01*
G01X1672500Y954533D02*
X1672792Y954783D01*
X1672958Y955117D01*
X1673000Y955492D01*
X1672958Y955825D01*
X1672750Y956158D01*
X1672500Y956367D01*
X1672250Y956408D01*
X1671958Y956325D01*
X1671750Y956033D01*
X1671667Y955742D01*
Y955367D01*
G01Y955742D02*
X1671542Y955992D01*
X1671333Y956200D01*
X1671083Y956283D01*
X1670833Y956200D01*
X1670625Y955992D01*
X1670500Y955617D01*
X1670542Y955242D01*
X1670708Y954867D01*
G01X1673000Y958550D02*
X1670500D01*
X1671000Y958050D01*
G01X1673000D02*
Y959050D01*
G01Y961650D02*
X1670500D01*
X1671000Y961150D01*
G01X1673000D02*
Y962150D01*
G01X1721017Y859000D02*
Y861500D01*
X1722058D01*
X1722392Y861375D01*
X1722600Y861208D01*
X1722683Y860875D01*
X1722600Y860542D01*
X1722350Y860333D01*
X1722058Y860208D01*
X1721017D01*
G01X1722058D02*
X1722683Y859000D01*
G01X1724033Y859500D02*
X1724283Y859208D01*
X1724617Y859042D01*
X1724992Y859000D01*
X1725325Y859042D01*
X1725658Y859250D01*
X1725867Y859500D01*
X1725908Y859750D01*
X1725825Y860042D01*
X1725533Y860250D01*
X1725242Y860333D01*
X1724867D01*
G01X1725242D02*
X1725492Y860458D01*
X1725700Y860667D01*
X1725783Y860917D01*
X1725700Y861167D01*
X1725492Y861375D01*
X1725117Y861500D01*
X1724742Y861458D01*
X1724367Y861292D01*
G01X1728050Y861500D02*
X1727717Y861417D01*
X1727467Y861208D01*
X1727300Y860958D01*
X1727175Y860625D01*
X1727133Y860250D01*
X1727175Y859875D01*
X1727300Y859542D01*
X1727467Y859292D01*
X1727717Y859083D01*
X1728050Y859000D01*
X1728383Y859083D01*
X1728633Y859292D01*
X1728800Y859542D01*
X1728925Y859875D01*
X1728967Y860250D01*
X1728925Y860625D01*
X1728800Y860958D01*
X1728633Y861208D01*
X1728383Y861417D01*
X1728050Y861500D01*
G01X1730358Y860042D02*
X1730650Y860333D01*
X1730900Y860500D01*
X1731233Y860583D01*
X1731525Y860500D01*
X1731733Y860333D01*
X1731900Y860083D01*
X1731942Y859792D01*
X1731900Y859542D01*
X1731733Y859292D01*
X1731483Y859083D01*
X1731192Y859000D01*
X1730858Y859083D01*
X1730567Y859333D01*
X1730400Y859708D01*
X1730358Y860125D01*
X1730442Y860667D01*
X1730567Y860958D01*
X1730775Y861250D01*
X1731067Y861458D01*
X1731358Y861500D01*
X1731650Y861417D01*
X1731858Y861208D01*
G01X1637708Y1037267D02*
X1637583Y1037017D01*
X1637500Y1036725D01*
Y1036392D01*
X1637625Y1036017D01*
X1637833Y1035725D01*
X1638083Y1035517D01*
X1638500Y1035350D01*
X1638875Y1035308D01*
X1639250Y1035392D01*
X1639500Y1035517D01*
X1639750Y1035767D01*
X1639917Y1036058D01*
X1640000Y1036350D01*
Y1036642D01*
X1639917Y1036933D01*
X1639792Y1037183D01*
X1639625Y1037392D01*
G01X1640000Y1039450D02*
X1637500D01*
X1638000Y1038950D01*
G01X1640000D02*
Y1039950D01*
G01X1639625Y1041633D02*
X1639833Y1041883D01*
X1639958Y1042175D01*
X1640000Y1042550D01*
X1639917Y1042925D01*
X1639750Y1043217D01*
X1639458Y1043425D01*
X1639125Y1043467D01*
X1638792Y1043383D01*
X1638583Y1043175D01*
X1638417Y1042883D01*
X1638375Y1042592D01*
X1638417Y1042300D01*
X1638583Y1041925D01*
X1637500Y1042050D01*
Y1043175D01*
G01X1640000Y1046150D02*
X1637500D01*
X1639292Y1044608D01*
Y1046692D01*
G01X1669208Y992767D02*
X1669083Y992517D01*
X1669000Y992225D01*
Y991892D01*
X1669125Y991517D01*
X1669333Y991225D01*
X1669583Y991017D01*
X1670000Y990850D01*
X1670375Y990808D01*
X1670750Y990892D01*
X1671000Y991017D01*
X1671250Y991267D01*
X1671417Y991558D01*
X1671500Y991850D01*
Y992142D01*
X1671417Y992433D01*
X1671292Y992683D01*
X1671125Y992892D01*
G01X1671500Y994950D02*
X1669000D01*
X1669500Y994450D01*
G01X1671500D02*
Y995450D01*
G01X1671125Y997133D02*
X1671333Y997383D01*
X1671458Y997675D01*
X1671500Y998050D01*
X1671417Y998425D01*
X1671250Y998717D01*
X1670958Y998925D01*
X1670625Y998967D01*
X1670292Y998883D01*
X1670083Y998675D01*
X1669917Y998383D01*
X1669875Y998092D01*
X1669917Y997800D01*
X1670083Y997425D01*
X1669000Y997550D01*
Y998675D01*
G01X1671125Y1000233D02*
X1671333Y1000483D01*
X1671458Y1000775D01*
X1671500Y1001150D01*
X1671417Y1001525D01*
X1671250Y1001817D01*
X1670958Y1002025D01*
X1670625Y1002067D01*
X1670292Y1001983D01*
X1670083Y1001775D01*
X1669917Y1001483D01*
X1669875Y1001192D01*
X1669917Y1000900D01*
X1670083Y1000525D01*
X1669000Y1000650D01*
Y1001775D01*
G01X1713767Y1020792D02*
X1713517Y1020917D01*
X1713225Y1021000D01*
X1712892D01*
X1712517Y1020875D01*
X1712225Y1020667D01*
X1712017Y1020417D01*
X1711850Y1020000D01*
X1711808Y1019625D01*
X1711892Y1019250D01*
X1712017Y1019000D01*
X1712267Y1018750D01*
X1712558Y1018583D01*
X1712850Y1018500D01*
X1713142D01*
X1713433Y1018583D01*
X1713683Y1018708D01*
X1713892Y1018875D01*
G01X1715950Y1018500D02*
Y1021000D01*
X1715450Y1020500D01*
G01Y1018500D02*
X1716450D01*
G01X1718133Y1018875D02*
X1718383Y1018667D01*
X1718675Y1018542D01*
X1719050Y1018500D01*
X1719425Y1018583D01*
X1719717Y1018750D01*
X1719925Y1019042D01*
X1719967Y1019375D01*
X1719883Y1019708D01*
X1719675Y1019917D01*
X1719383Y1020083D01*
X1719092Y1020125D01*
X1718800Y1020083D01*
X1718425Y1019917D01*
X1718550Y1021000D01*
X1719675D01*
G01X1721358Y1019542D02*
X1721650Y1019833D01*
X1721900Y1020000D01*
X1722233Y1020083D01*
X1722525Y1020000D01*
X1722733Y1019833D01*
X1722900Y1019583D01*
X1722942Y1019292D01*
X1722900Y1019042D01*
X1722733Y1018792D01*
X1722483Y1018583D01*
X1722192Y1018500D01*
X1721858Y1018583D01*
X1721567Y1018833D01*
X1721400Y1019208D01*
X1721358Y1019625D01*
X1721442Y1020167D01*
X1721567Y1020458D01*
X1721775Y1020750D01*
X1722067Y1020958D01*
X1722358Y1021000D01*
X1722650Y1020917D01*
X1722858Y1020708D01*
G01X1636000Y1035517D02*
X1633500D01*
Y1036558D01*
X1633625Y1036892D01*
X1633792Y1037100D01*
X1634125Y1037183D01*
X1634458Y1037100D01*
X1634667Y1036850D01*
X1634792Y1036558D01*
Y1035517D01*
G01Y1036558D02*
X1636000Y1037183D01*
G01X1635500Y1038533D02*
X1635792Y1038783D01*
X1635958Y1039117D01*
X1636000Y1039492D01*
X1635958Y1039825D01*
X1635750Y1040158D01*
X1635500Y1040367D01*
X1635250Y1040408D01*
X1634958Y1040325D01*
X1634750Y1040033D01*
X1634667Y1039742D01*
Y1039367D01*
G01Y1039742D02*
X1634542Y1039992D01*
X1634333Y1040200D01*
X1634083Y1040283D01*
X1633833Y1040200D01*
X1633625Y1039992D01*
X1633500Y1039617D01*
X1633542Y1039242D01*
X1633708Y1038867D01*
G01X1633500Y1042550D02*
X1633583Y1042217D01*
X1633792Y1041967D01*
X1634042Y1041800D01*
X1634375Y1041675D01*
X1634750Y1041633D01*
X1635125Y1041675D01*
X1635458Y1041800D01*
X1635708Y1041967D01*
X1635917Y1042217D01*
X1636000Y1042550D01*
X1635917Y1042883D01*
X1635708Y1043133D01*
X1635458Y1043300D01*
X1635125Y1043425D01*
X1634750Y1043467D01*
X1634375Y1043425D01*
X1634042Y1043300D01*
X1633792Y1043133D01*
X1633583Y1042883D01*
X1633500Y1042550D01*
G01X1635500Y1044733D02*
X1635792Y1044983D01*
X1635958Y1045317D01*
X1636000Y1045692D01*
X1635958Y1046025D01*
X1635750Y1046358D01*
X1635500Y1046567D01*
X1635250Y1046608D01*
X1634958Y1046525D01*
X1634750Y1046233D01*
X1634667Y1045942D01*
Y1045567D01*
G01Y1045942D02*
X1634542Y1046192D01*
X1634333Y1046400D01*
X1634083Y1046483D01*
X1633833Y1046400D01*
X1633625Y1046192D01*
X1633500Y1045817D01*
X1633542Y1045442D01*
X1633708Y1045067D01*
G01X1633100Y1026400D02*
X1637100D01*
Y1033800D01*
G01X1671300Y978317D02*
X1668800D01*
Y979358D01*
X1668925Y979692D01*
X1669092Y979900D01*
X1669425Y979983D01*
X1669758Y979900D01*
X1669967Y979650D01*
X1670092Y979358D01*
Y978317D01*
G01Y979358D02*
X1671300Y979983D01*
G01X1670800Y981333D02*
X1671092Y981583D01*
X1671258Y981917D01*
X1671300Y982292D01*
X1671258Y982625D01*
X1671050Y982958D01*
X1670800Y983167D01*
X1670550Y983208D01*
X1670258Y983125D01*
X1670050Y982833D01*
X1669967Y982542D01*
Y982167D01*
G01Y982542D02*
X1669842Y982792D01*
X1669633Y983000D01*
X1669383Y983083D01*
X1669133Y983000D01*
X1668925Y982792D01*
X1668800Y982417D01*
X1668842Y982042D01*
X1669008Y981667D01*
G01X1668800Y985350D02*
X1668883Y985017D01*
X1669092Y984767D01*
X1669342Y984600D01*
X1669675Y984475D01*
X1670050Y984433D01*
X1670425Y984475D01*
X1670758Y984600D01*
X1671008Y984767D01*
X1671217Y985017D01*
X1671300Y985350D01*
X1671217Y985683D01*
X1671008Y985933D01*
X1670758Y986100D01*
X1670425Y986225D01*
X1670050Y986267D01*
X1669675Y986225D01*
X1669342Y986100D01*
X1669092Y985933D01*
X1668883Y985683D01*
X1668800Y985350D01*
G01X1671300Y988367D02*
X1670758Y988450D01*
X1670300Y988575D01*
X1669883Y988742D01*
X1669425Y988950D01*
X1668800Y989283D01*
Y987617D01*
G01X1674200Y984300D02*
Y980300D01*
X1681600D01*
G01X1682500Y955300D02*
X1686500D01*
Y962700D01*
G01X1692500Y955300D02*
X1696500D01*
Y962700D01*
G01X1682000D02*
X1678000D01*
Y955300D01*
G01X1709339Y963517D02*
X1706839D01*
Y964558D01*
X1706964Y964892D01*
X1707131Y965100D01*
X1707464Y965183D01*
X1707797Y965100D01*
X1708006Y964850D01*
X1708131Y964558D01*
Y963517D01*
G01Y964558D02*
X1709339Y965183D01*
G01X1708839Y966533D02*
X1709131Y966783D01*
X1709297Y967117D01*
X1709339Y967492D01*
X1709297Y967825D01*
X1709089Y968158D01*
X1708839Y968367D01*
X1708589Y968408D01*
X1708297Y968325D01*
X1708089Y968033D01*
X1708006Y967742D01*
Y967367D01*
G01Y967742D02*
X1707881Y967992D01*
X1707672Y968200D01*
X1707422Y968283D01*
X1707172Y968200D01*
X1706964Y967992D01*
X1706839Y967617D01*
X1706881Y967242D01*
X1707047Y966867D01*
G01X1709339Y970550D02*
X1706839D01*
X1707339Y970050D01*
G01X1709339D02*
Y971050D01*
G01X1707256Y972858D02*
X1707006Y973108D01*
X1706881Y973400D01*
X1706839Y973733D01*
X1706922Y974150D01*
X1707131Y974442D01*
X1707381Y974525D01*
X1707631Y974483D01*
X1707839Y974317D01*
X1708256Y973483D01*
X1708547Y973108D01*
X1708964Y972858D01*
X1709339Y972775D01*
Y974525D01*
G01X1697000Y967800D02*
X1701000D01*
Y975200D01*
G01X1712017Y1014000D02*
Y1016500D01*
X1713058D01*
X1713392Y1016375D01*
X1713600Y1016208D01*
X1713683Y1015875D01*
X1713600Y1015542D01*
X1713350Y1015333D01*
X1713058Y1015208D01*
X1712017D01*
G01X1713058D02*
X1713683Y1014000D01*
G01X1715033Y1014500D02*
X1715283Y1014208D01*
X1715617Y1014042D01*
X1715992Y1014000D01*
X1716325Y1014042D01*
X1716658Y1014250D01*
X1716867Y1014500D01*
X1716908Y1014750D01*
X1716825Y1015042D01*
X1716533Y1015250D01*
X1716242Y1015333D01*
X1715867D01*
G01X1716242D02*
X1716492Y1015458D01*
X1716700Y1015667D01*
X1716783Y1015917D01*
X1716700Y1016167D01*
X1716492Y1016375D01*
X1716117Y1016500D01*
X1715742Y1016458D01*
X1715367Y1016292D01*
G01X1719050Y1014000D02*
Y1016500D01*
X1718550Y1016000D01*
G01Y1014000D02*
X1719550D01*
G01X1721233Y1014500D02*
X1721483Y1014208D01*
X1721817Y1014042D01*
X1722192Y1014000D01*
X1722525Y1014042D01*
X1722858Y1014250D01*
X1723067Y1014500D01*
X1723108Y1014750D01*
X1723025Y1015042D01*
X1722733Y1015250D01*
X1722442Y1015333D01*
X1722067D01*
G01X1722442D02*
X1722692Y1015458D01*
X1722900Y1015667D01*
X1722983Y1015917D01*
X1722900Y1016167D01*
X1722692Y1016375D01*
X1722317Y1016500D01*
X1721942Y1016458D01*
X1721567Y1016292D01*
G01X1709700Y1013000D02*
Y1017000D01*
X1702300D01*
G01X1712517Y985000D02*
Y987500D01*
X1713558D01*
X1713892Y987375D01*
X1714100Y987208D01*
X1714183Y986875D01*
X1714100Y986542D01*
X1713850Y986333D01*
X1713558Y986208D01*
X1712517D01*
G01X1713558D02*
X1714183Y985000D01*
G01X1715533Y985500D02*
X1715783Y985208D01*
X1716117Y985042D01*
X1716492Y985000D01*
X1716825Y985042D01*
X1717158Y985250D01*
X1717367Y985500D01*
X1717408Y985750D01*
X1717325Y986042D01*
X1717033Y986250D01*
X1716742Y986333D01*
X1716367D01*
G01X1716742D02*
X1716992Y986458D01*
X1717200Y986667D01*
X1717283Y986917D01*
X1717200Y987167D01*
X1716992Y987375D01*
X1716617Y987500D01*
X1716242Y987458D01*
X1715867Y987292D01*
G01X1719550Y985000D02*
Y987500D01*
X1719050Y987000D01*
G01Y985000D02*
X1720050D01*
G01X1723150D02*
Y987500D01*
X1721608Y985708D01*
X1723692D01*
G01X1699800Y988000D02*
Y984000D01*
X1707200D01*
G01X1704839Y963517D02*
X1702339D01*
Y964558D01*
X1702464Y964892D01*
X1702631Y965100D01*
X1702964Y965183D01*
X1703297Y965100D01*
X1703506Y964850D01*
X1703631Y964558D01*
Y963517D01*
G01Y964558D02*
X1704839Y965183D01*
G01X1704339Y966533D02*
X1704631Y966783D01*
X1704797Y967117D01*
X1704839Y967492D01*
X1704797Y967825D01*
X1704589Y968158D01*
X1704339Y968367D01*
X1704089Y968408D01*
X1703797Y968325D01*
X1703589Y968033D01*
X1703506Y967742D01*
Y967367D01*
G01Y967742D02*
X1703381Y967992D01*
X1703172Y968200D01*
X1702922Y968283D01*
X1702672Y968200D01*
X1702464Y967992D01*
X1702339Y967617D01*
X1702381Y967242D01*
X1702547Y966867D01*
G01X1704839Y970550D02*
X1702339D01*
X1702839Y970050D01*
G01X1704839D02*
Y971050D01*
G01X1704464Y972733D02*
X1704672Y972983D01*
X1704797Y973275D01*
X1704839Y973650D01*
X1704756Y974025D01*
X1704589Y974317D01*
X1704297Y974525D01*
X1703964Y974567D01*
X1703631Y974483D01*
X1703422Y974275D01*
X1703256Y973983D01*
X1703214Y973692D01*
X1703256Y973400D01*
X1703422Y973025D01*
X1702339Y973150D01*
Y974275D01*
G01X1692500Y967800D02*
X1696500D01*
Y975200D01*
G01X1677900Y1012500D02*
X1677567Y1012542D01*
X1677275Y1012708D01*
X1677025Y1012958D01*
X1676858Y1013250D01*
X1676775Y1013583D01*
Y1013917D01*
X1676858Y1014250D01*
X1677025Y1014542D01*
X1677275Y1014792D01*
X1677567Y1014958D01*
X1677900Y1015000D01*
X1678233Y1014958D01*
X1678525Y1014792D01*
X1678775Y1014542D01*
X1678942Y1014250D01*
X1679025Y1013917D01*
Y1013583D01*
X1678942Y1013250D01*
X1678775Y1012958D01*
X1678525Y1012708D01*
X1678233Y1012542D01*
X1677900Y1012500D01*
G01X1678233Y1013167D02*
X1678733Y1012500D01*
G01X1680083Y1013000D02*
X1680333Y1012708D01*
X1680667Y1012542D01*
X1681042Y1012500D01*
X1681375Y1012542D01*
X1681708Y1012750D01*
X1681917Y1013000D01*
X1681958Y1013250D01*
X1681875Y1013542D01*
X1681583Y1013750D01*
X1681292Y1013833D01*
X1680917D01*
G01X1681292D02*
X1681542Y1013958D01*
X1681750Y1014167D01*
X1681833Y1014417D01*
X1681750Y1014667D01*
X1681542Y1014875D01*
X1681167Y1015000D01*
X1680792Y1014958D01*
X1680417Y1014792D01*
G01X1684600Y1012500D02*
Y1015000D01*
X1683058Y1013208D01*
X1685142D01*
G01X1693000Y1010200D02*
X1691200Y1008100D01*
X1689000Y1010200D01*
G01X1685400Y1010300D02*
Y991100D01*
X1696600D01*
Y1010300D01*
X1685400D01*
Y1009900D01*
G01X1687800Y1037500D02*
X1689900Y1035700D01*
X1687800Y1033500D01*
G01X1687700Y1029900D02*
X1706900D01*
Y1041100D01*
X1687700D01*
Y1029900D01*
X1688100D01*
G01X1677000Y1041700D02*
Y1047200D01*
G01X1685000Y1041700D02*
X1677000D01*
G01X1685000Y1047200D02*
Y1041700D01*
G01X1711033Y978000D02*
Y980500D01*
X1711867D01*
X1712200Y980375D01*
X1712450Y980208D01*
X1712658Y979958D01*
X1712825Y979667D01*
X1712867Y979250D01*
X1712825Y978833D01*
X1712658Y978542D01*
X1712450Y978292D01*
X1712200Y978125D01*
X1711867Y978000D01*
X1711033D01*
G01X1714342Y978292D02*
X1714633Y978083D01*
X1714967Y978000D01*
X1715300Y978083D01*
X1715592Y978333D01*
X1715800Y978708D01*
X1715883Y979083D01*
Y979542D01*
X1715800Y979917D01*
X1715592Y980250D01*
X1715342Y980417D01*
X1715050Y980500D01*
X1714717Y980417D01*
X1714467Y980250D01*
X1714300Y980000D01*
X1714217Y979667D01*
X1714300Y979375D01*
X1714508Y979083D01*
X1714758Y978917D01*
X1715050Y978875D01*
X1715383Y978958D01*
X1715633Y979167D01*
X1715883Y979542D01*
G01X1709000Y976000D02*
X1692900D01*
G01X1709000Y983000D02*
Y976000D01*
G01X1692900Y983000D02*
X1709000D01*
G01X1692900Y976000D02*
Y983000D01*
G01X1671500Y967400D02*
X1671458Y967067D01*
X1671292Y966775D01*
X1671042Y966525D01*
X1670750Y966358D01*
X1670417Y966275D01*
X1670083D01*
X1669750Y966358D01*
X1669458Y966525D01*
X1669208Y966775D01*
X1669042Y967067D01*
X1669000Y967400D01*
X1669042Y967733D01*
X1669208Y968025D01*
X1669458Y968275D01*
X1669750Y968442D01*
X1670083Y968525D01*
X1670417D01*
X1670750Y968442D01*
X1671042Y968275D01*
X1671292Y968025D01*
X1671458Y967733D01*
X1671500Y967400D01*
G01X1670833Y967733D02*
X1671500Y968233D01*
G01X1671000Y969583D02*
X1671292Y969833D01*
X1671458Y970167D01*
X1671500Y970542D01*
X1671458Y970875D01*
X1671250Y971208D01*
X1671000Y971417D01*
X1670750Y971458D01*
X1670458Y971375D01*
X1670250Y971083D01*
X1670167Y970792D01*
Y970417D01*
G01Y970792D02*
X1670042Y971042D01*
X1669833Y971250D01*
X1669583Y971333D01*
X1669333Y971250D01*
X1669125Y971042D01*
X1669000Y970667D01*
X1669042Y970292D01*
X1669208Y969917D01*
G01X1671125Y972683D02*
X1671333Y972933D01*
X1671458Y973225D01*
X1671500Y973600D01*
X1671417Y973975D01*
X1671250Y974267D01*
X1670958Y974475D01*
X1670625Y974517D01*
X1670292Y974433D01*
X1670083Y974225D01*
X1669917Y973933D01*
X1669875Y973642D01*
X1669917Y973350D01*
X1670083Y972975D01*
X1669000Y973100D01*
Y974225D01*
G01X1673300Y975200D02*
Y963800D01*
G01X1686700Y975200D02*
X1673300D01*
G01X1686700Y963800D02*
Y975200D01*
G01X1673300Y963800D02*
X1686700D01*
G01X1672517Y1023500D02*
Y1026000D01*
X1673558D01*
X1673892Y1025875D01*
X1674100Y1025708D01*
X1674183Y1025375D01*
X1674100Y1025042D01*
X1673850Y1024833D01*
X1673558Y1024708D01*
X1672517D01*
G01X1673558D02*
X1674183Y1023500D01*
G01X1675533Y1024000D02*
X1675783Y1023708D01*
X1676117Y1023542D01*
X1676492Y1023500D01*
X1676825Y1023542D01*
X1677158Y1023750D01*
X1677367Y1024000D01*
X1677408Y1024250D01*
X1677325Y1024542D01*
X1677033Y1024750D01*
X1676742Y1024833D01*
X1676367D01*
G01X1676742D02*
X1676992Y1024958D01*
X1677200Y1025167D01*
X1677283Y1025417D01*
X1677200Y1025667D01*
X1676992Y1025875D01*
X1676617Y1026000D01*
X1676242Y1025958D01*
X1675867Y1025792D01*
G01X1679550Y1026000D02*
X1679217Y1025917D01*
X1678967Y1025708D01*
X1678800Y1025458D01*
X1678675Y1025125D01*
X1678633Y1024750D01*
X1678675Y1024375D01*
X1678800Y1024042D01*
X1678967Y1023792D01*
X1679217Y1023583D01*
X1679550Y1023500D01*
X1679883Y1023583D01*
X1680133Y1023792D01*
X1680300Y1024042D01*
X1680425Y1024375D01*
X1680467Y1024750D01*
X1680425Y1025125D01*
X1680300Y1025458D01*
X1680133Y1025708D01*
X1679883Y1025917D01*
X1679550Y1026000D01*
G01X1681858Y1025583D02*
X1682108Y1025833D01*
X1682400Y1025958D01*
X1682733Y1026000D01*
X1683150Y1025917D01*
X1683442Y1025708D01*
X1683525Y1025458D01*
X1683483Y1025208D01*
X1683317Y1025000D01*
X1682483Y1024583D01*
X1682108Y1024292D01*
X1681858Y1023875D01*
X1681775Y1023500D01*
X1683525D01*
G01X1686300Y1035500D02*
Y1027500D01*
X1668700D01*
Y1035500D01*
X1686300D01*
G01X1643325Y1114000D02*
Y1116500D01*
G01X1645075D02*
Y1114000D01*
G01Y1115250D02*
X1643325D01*
G01X1646383Y1114000D02*
Y1116500D01*
X1647217D01*
X1647550Y1116375D01*
X1647800Y1116208D01*
X1648008Y1115958D01*
X1648175Y1115667D01*
X1648217Y1115250D01*
X1648175Y1114833D01*
X1648008Y1114542D01*
X1647800Y1114292D01*
X1647550Y1114125D01*
X1647217Y1114000D01*
X1646383D01*
G01X1649483D02*
Y1116500D01*
X1650317D01*
X1650650Y1116375D01*
X1650900Y1116208D01*
X1651108Y1115958D01*
X1651275Y1115667D01*
X1651317Y1115250D01*
X1651275Y1114833D01*
X1651108Y1114542D01*
X1650900Y1114292D01*
X1650650Y1114125D01*
X1650317Y1114000D01*
X1649483D01*
G01X1652625Y1114333D02*
X1652958Y1114125D01*
X1653333Y1114000D01*
X1653667D01*
X1654000Y1114125D01*
X1654250Y1114333D01*
X1654375Y1114625D01*
X1654292Y1114917D01*
X1654083Y1115167D01*
X1653708Y1115333D01*
X1653208Y1115417D01*
X1652917Y1115583D01*
X1652792Y1115875D01*
X1652875Y1116167D01*
X1653083Y1116375D01*
X1653375Y1116500D01*
X1653667D01*
X1653958Y1116417D01*
X1654208Y1116208D01*
G01X1655558Y1114000D02*
X1656600Y1116500D01*
X1657642Y1114000D01*
G01X1657267Y1114875D02*
X1655933D01*
G01X1658825Y1114333D02*
X1659158Y1114125D01*
X1659533Y1114000D01*
X1659867D01*
X1660200Y1114125D01*
X1660450Y1114333D01*
X1660575Y1114625D01*
X1660492Y1114917D01*
X1660283Y1115167D01*
X1659908Y1115333D01*
X1659408Y1115417D01*
X1659117Y1115583D01*
X1658992Y1115875D01*
X1659075Y1116167D01*
X1659283Y1116375D01*
X1659575Y1116500D01*
X1659867D01*
X1660158Y1116417D01*
X1660408Y1116208D01*
G01X1662092Y1114292D02*
X1662383Y1114083D01*
X1662717Y1114000D01*
X1663050Y1114083D01*
X1663342Y1114333D01*
X1663550Y1114708D01*
X1663633Y1115083D01*
Y1115542D01*
X1663550Y1115917D01*
X1663342Y1116250D01*
X1663092Y1116417D01*
X1662800Y1116500D01*
X1662467Y1116417D01*
X1662217Y1116250D01*
X1662050Y1116000D01*
X1661967Y1115667D01*
X1662050Y1115375D01*
X1662258Y1115083D01*
X1662508Y1114917D01*
X1662800Y1114875D01*
X1663133Y1114958D01*
X1663383Y1115167D01*
X1663633Y1115542D01*
G01X1669708Y1063767D02*
X1669583Y1063517D01*
X1669500Y1063225D01*
Y1062892D01*
X1669625Y1062517D01*
X1669833Y1062225D01*
X1670083Y1062017D01*
X1670500Y1061850D01*
X1670875Y1061808D01*
X1671250Y1061892D01*
X1671500Y1062017D01*
X1671750Y1062267D01*
X1671917Y1062558D01*
X1672000Y1062850D01*
Y1063142D01*
X1671917Y1063433D01*
X1671792Y1063683D01*
X1671625Y1063892D01*
G01X1672000Y1065950D02*
X1669500D01*
X1670000Y1065450D01*
G01X1672000D02*
Y1066450D01*
G01Y1069550D02*
X1669500D01*
X1671292Y1068008D01*
Y1070092D01*
G01X1672000Y1072067D02*
X1671458Y1072150D01*
X1671000Y1072275D01*
X1670583Y1072442D01*
X1670125Y1072650D01*
X1669500Y1072983D01*
Y1071317D01*
G01X1669208Y1095767D02*
X1669083Y1095517D01*
X1669000Y1095225D01*
Y1094892D01*
X1669125Y1094517D01*
X1669333Y1094225D01*
X1669583Y1094017D01*
X1670000Y1093850D01*
X1670375Y1093808D01*
X1670750Y1093892D01*
X1671000Y1094017D01*
X1671250Y1094267D01*
X1671417Y1094558D01*
X1671500Y1094850D01*
Y1095142D01*
X1671417Y1095433D01*
X1671292Y1095683D01*
X1671125Y1095892D01*
G01X1671500Y1097950D02*
X1669000D01*
X1669500Y1097450D01*
G01X1671500D02*
Y1098450D01*
G01X1671125Y1100133D02*
X1671333Y1100383D01*
X1671458Y1100675D01*
X1671500Y1101050D01*
X1671417Y1101425D01*
X1671250Y1101717D01*
X1670958Y1101925D01*
X1670625Y1101967D01*
X1670292Y1101883D01*
X1670083Y1101675D01*
X1669917Y1101383D01*
X1669875Y1101092D01*
X1669917Y1100800D01*
X1670083Y1100425D01*
X1669000Y1100550D01*
Y1101675D01*
G01X1671000Y1103233D02*
X1671292Y1103483D01*
X1671458Y1103817D01*
X1671500Y1104192D01*
X1671458Y1104525D01*
X1671250Y1104858D01*
X1671000Y1105067D01*
X1670750Y1105108D01*
X1670458Y1105025D01*
X1670250Y1104733D01*
X1670167Y1104442D01*
Y1104067D01*
G01Y1104442D02*
X1670042Y1104692D01*
X1669833Y1104900D01*
X1669583Y1104983D01*
X1669333Y1104900D01*
X1669125Y1104692D01*
X1669000Y1104317D01*
X1669042Y1103942D01*
X1669208Y1103567D01*
G01X1691900Y1051000D02*
X1691567Y1051042D01*
X1691275Y1051208D01*
X1691025Y1051458D01*
X1690858Y1051750D01*
X1690775Y1052083D01*
Y1052417D01*
X1690858Y1052750D01*
X1691025Y1053042D01*
X1691275Y1053292D01*
X1691567Y1053458D01*
X1691900Y1053500D01*
X1692233Y1053458D01*
X1692525Y1053292D01*
X1692775Y1053042D01*
X1692942Y1052750D01*
X1693025Y1052417D01*
Y1052083D01*
X1692942Y1051750D01*
X1692775Y1051458D01*
X1692525Y1051208D01*
X1692233Y1051042D01*
X1691900Y1051000D01*
G01X1692233Y1051667D02*
X1692733Y1051000D01*
G01X1694083Y1051500D02*
X1694333Y1051208D01*
X1694667Y1051042D01*
X1695042Y1051000D01*
X1695375Y1051042D01*
X1695708Y1051250D01*
X1695917Y1051500D01*
X1695958Y1051750D01*
X1695875Y1052042D01*
X1695583Y1052250D01*
X1695292Y1052333D01*
X1694917D01*
G01X1695292D02*
X1695542Y1052458D01*
X1695750Y1052667D01*
X1695833Y1052917D01*
X1695750Y1053167D01*
X1695542Y1053375D01*
X1695167Y1053500D01*
X1694792Y1053458D01*
X1694417Y1053292D01*
G01X1697308Y1052042D02*
X1697600Y1052333D01*
X1697850Y1052500D01*
X1698183Y1052583D01*
X1698475Y1052500D01*
X1698683Y1052333D01*
X1698850Y1052083D01*
X1698892Y1051792D01*
X1698850Y1051542D01*
X1698683Y1051292D01*
X1698433Y1051083D01*
X1698142Y1051000D01*
X1697808Y1051083D01*
X1697517Y1051333D01*
X1697350Y1051708D01*
X1697308Y1052125D01*
X1697392Y1052667D01*
X1697517Y1052958D01*
X1697725Y1053250D01*
X1698017Y1053458D01*
X1698308Y1053500D01*
X1698600Y1053417D01*
X1698808Y1053208D01*
G01X1673708Y1061267D02*
X1673583Y1061017D01*
X1673500Y1060725D01*
Y1060392D01*
X1673625Y1060017D01*
X1673833Y1059725D01*
X1674083Y1059517D01*
X1674500Y1059350D01*
X1674875Y1059308D01*
X1675250Y1059392D01*
X1675500Y1059517D01*
X1675750Y1059767D01*
X1675917Y1060058D01*
X1676000Y1060350D01*
Y1060642D01*
X1675917Y1060933D01*
X1675792Y1061183D01*
X1675625Y1061392D01*
G01X1676000Y1063450D02*
X1673500D01*
X1674000Y1062950D01*
G01X1676000D02*
Y1063950D01*
G01Y1067050D02*
X1673500D01*
X1675292Y1065508D01*
Y1067592D01*
G01X1676000Y1069650D02*
X1675958Y1069942D01*
X1675833Y1070275D01*
X1675625Y1070483D01*
X1675333Y1070567D01*
X1675042Y1070483D01*
X1674792Y1070233D01*
X1674667Y1069858D01*
Y1069442D01*
X1674583Y1069192D01*
X1674375Y1068983D01*
X1674083Y1068900D01*
X1673792Y1069025D01*
X1673583Y1069317D01*
X1673500Y1069650D01*
X1673583Y1069983D01*
X1673792Y1070275D01*
X1674083Y1070400D01*
X1674375Y1070317D01*
X1674583Y1070108D01*
X1674667Y1069858D01*
Y1069442D01*
X1674792Y1069067D01*
X1675042Y1068817D01*
X1675333Y1068733D01*
X1675625Y1068817D01*
X1675833Y1069025D01*
X1675958Y1069358D01*
X1676000Y1069650D01*
G01X1685000Y1059300D02*
Y1053800D01*
G01X1677000Y1059300D02*
X1685000D01*
G01X1677000Y1053800D02*
Y1059300D01*
G01X1684417Y1070800D02*
Y1073300D01*
X1685458D01*
X1685792Y1073175D01*
X1686000Y1073008D01*
X1686083Y1072675D01*
X1686000Y1072342D01*
X1685750Y1072133D01*
X1685458Y1072008D01*
X1684417D01*
G01X1685458D02*
X1686083Y1070800D01*
G01X1687433Y1071300D02*
X1687683Y1071008D01*
X1688017Y1070842D01*
X1688392Y1070800D01*
X1688725Y1070842D01*
X1689058Y1071050D01*
X1689267Y1071300D01*
X1689308Y1071550D01*
X1689225Y1071842D01*
X1688933Y1072050D01*
X1688642Y1072133D01*
X1688267D01*
G01X1688642D02*
X1688892Y1072258D01*
X1689100Y1072467D01*
X1689183Y1072717D01*
X1689100Y1072967D01*
X1688892Y1073175D01*
X1688517Y1073300D01*
X1688142Y1073258D01*
X1687767Y1073092D01*
G01X1691450Y1073300D02*
X1691117Y1073217D01*
X1690867Y1073008D01*
X1690700Y1072758D01*
X1690575Y1072425D01*
X1690533Y1072050D01*
X1690575Y1071675D01*
X1690700Y1071342D01*
X1690867Y1071092D01*
X1691117Y1070883D01*
X1691450Y1070800D01*
X1691783Y1070883D01*
X1692033Y1071092D01*
X1692200Y1071342D01*
X1692325Y1071675D01*
X1692367Y1072050D01*
X1692325Y1072425D01*
X1692200Y1072758D01*
X1692033Y1073008D01*
X1691783Y1073217D01*
X1691450Y1073300D01*
G01X1695050Y1070800D02*
Y1073300D01*
X1693508Y1071508D01*
X1695592D01*
G01X1694700Y1069300D02*
Y1061300D01*
X1677100D01*
Y1069300D01*
X1694700D01*
G01X1676047Y1095767D02*
X1675922Y1095517D01*
X1675839Y1095225D01*
Y1094892D01*
X1675964Y1094517D01*
X1676172Y1094225D01*
X1676422Y1094017D01*
X1676839Y1093850D01*
X1677214Y1093808D01*
X1677589Y1093892D01*
X1677839Y1094017D01*
X1678089Y1094267D01*
X1678256Y1094558D01*
X1678339Y1094850D01*
Y1095142D01*
X1678256Y1095433D01*
X1678131Y1095683D01*
X1677964Y1095892D01*
G01X1678339Y1097950D02*
X1675839D01*
X1676339Y1097450D01*
G01X1678339D02*
Y1098450D01*
G01X1677964Y1100133D02*
X1678172Y1100383D01*
X1678297Y1100675D01*
X1678339Y1101050D01*
X1678256Y1101425D01*
X1678089Y1101717D01*
X1677797Y1101925D01*
X1677464Y1101967D01*
X1677131Y1101883D01*
X1676922Y1101675D01*
X1676756Y1101383D01*
X1676714Y1101092D01*
X1676756Y1100800D01*
X1676922Y1100425D01*
X1675839Y1100550D01*
Y1101675D01*
G01X1678339Y1104150D02*
X1675839D01*
X1676339Y1103650D01*
G01X1678339D02*
Y1104650D01*
G01X1684047Y1095767D02*
X1683922Y1095517D01*
X1683839Y1095225D01*
Y1094892D01*
X1683964Y1094517D01*
X1684172Y1094225D01*
X1684422Y1094017D01*
X1684839Y1093850D01*
X1685214Y1093808D01*
X1685589Y1093892D01*
X1685839Y1094017D01*
X1686089Y1094267D01*
X1686256Y1094558D01*
X1686339Y1094850D01*
Y1095142D01*
X1686256Y1095433D01*
X1686131Y1095683D01*
X1685964Y1095892D01*
G01X1686339Y1097950D02*
X1683839D01*
X1684339Y1097450D01*
G01X1686339D02*
Y1098450D01*
G01X1685964Y1100133D02*
X1686172Y1100383D01*
X1686297Y1100675D01*
X1686339Y1101050D01*
X1686256Y1101425D01*
X1686089Y1101717D01*
X1685797Y1101925D01*
X1685464Y1101967D01*
X1685131Y1101883D01*
X1684922Y1101675D01*
X1684756Y1101383D01*
X1684714Y1101092D01*
X1684756Y1100800D01*
X1684922Y1100425D01*
X1683839Y1100550D01*
Y1101675D01*
G01X1684256Y1103358D02*
X1684006Y1103608D01*
X1683881Y1103900D01*
X1683839Y1104233D01*
X1683922Y1104650D01*
X1684131Y1104942D01*
X1684381Y1105025D01*
X1684631Y1104983D01*
X1684839Y1104817D01*
X1685256Y1103983D01*
X1685547Y1103608D01*
X1685964Y1103358D01*
X1686339Y1103275D01*
Y1105025D01*
G01X1679173Y1420267D02*
X1679048Y1420017D01*
X1678965Y1419725D01*
Y1419392D01*
X1679090Y1419017D01*
X1679298Y1418725D01*
X1679548Y1418517D01*
X1679965Y1418350D01*
X1680340Y1418308D01*
X1680715Y1418392D01*
X1680965Y1418517D01*
X1681215Y1418767D01*
X1681382Y1419058D01*
X1681465Y1419350D01*
Y1419642D01*
X1681382Y1419933D01*
X1681257Y1420183D01*
X1681090Y1420392D01*
G01Y1421533D02*
X1681298Y1421783D01*
X1681423Y1422075D01*
X1681465Y1422450D01*
X1681382Y1422825D01*
X1681215Y1423117D01*
X1680923Y1423325D01*
X1680590Y1423367D01*
X1680257Y1423283D01*
X1680048Y1423075D01*
X1679882Y1422783D01*
X1679840Y1422492D01*
X1679882Y1422200D01*
X1680048Y1421825D01*
X1678965Y1421950D01*
Y1423075D01*
G01X1680965Y1424633D02*
X1681257Y1424883D01*
X1681423Y1425217D01*
X1681465Y1425592D01*
X1681423Y1425925D01*
X1681215Y1426258D01*
X1680965Y1426467D01*
X1680715Y1426508D01*
X1680423Y1426425D01*
X1680215Y1426133D01*
X1680132Y1425842D01*
Y1425467D01*
G01Y1425842D02*
X1680007Y1426092D01*
X1679798Y1426300D01*
X1679548Y1426383D01*
X1679298Y1426300D01*
X1679090Y1426092D01*
X1678965Y1425717D01*
X1679007Y1425342D01*
X1679173Y1424967D01*
G01X1681465Y1428650D02*
X1681423Y1428942D01*
X1681298Y1429275D01*
X1681090Y1429483D01*
X1680798Y1429567D01*
X1680507Y1429483D01*
X1680257Y1429233D01*
X1680132Y1428858D01*
Y1428442D01*
X1680048Y1428192D01*
X1679840Y1427983D01*
X1679548Y1427900D01*
X1679257Y1428025D01*
X1679048Y1428317D01*
X1678965Y1428650D01*
X1679048Y1428983D01*
X1679257Y1429275D01*
X1679548Y1429400D01*
X1679840Y1429317D01*
X1680048Y1429108D01*
X1680132Y1428858D01*
Y1428442D01*
X1680257Y1428067D01*
X1680507Y1427817D01*
X1680798Y1427733D01*
X1681090Y1427817D01*
X1681298Y1428025D01*
X1681423Y1428358D01*
X1681465Y1428650D01*
G01X1710834Y1396267D02*
X1710709Y1396017D01*
X1710626Y1395725D01*
Y1395392D01*
X1710751Y1395017D01*
X1710959Y1394725D01*
X1711209Y1394517D01*
X1711626Y1394350D01*
X1712001Y1394308D01*
X1712376Y1394392D01*
X1712626Y1394517D01*
X1712876Y1394767D01*
X1713043Y1395058D01*
X1713126Y1395350D01*
Y1395642D01*
X1713043Y1395933D01*
X1712918Y1396183D01*
X1712751Y1396392D01*
G01X1713126Y1398950D02*
X1710626D01*
X1712418Y1397408D01*
Y1399492D01*
G01X1710626Y1401550D02*
X1710709Y1401217D01*
X1710918Y1400967D01*
X1711168Y1400800D01*
X1711501Y1400675D01*
X1711876Y1400633D01*
X1712251Y1400675D01*
X1712584Y1400800D01*
X1712834Y1400967D01*
X1713043Y1401217D01*
X1713126Y1401550D01*
X1713043Y1401883D01*
X1712834Y1402133D01*
X1712584Y1402300D01*
X1712251Y1402425D01*
X1711876Y1402467D01*
X1711501Y1402425D01*
X1711168Y1402300D01*
X1710918Y1402133D01*
X1710709Y1401883D01*
X1710626Y1401550D01*
G01X1713126Y1405150D02*
X1710626D01*
X1712418Y1403608D01*
Y1405692D01*
G01X1677465Y1418517D02*
X1674965D01*
Y1419558D01*
X1675090Y1419892D01*
X1675257Y1420100D01*
X1675590Y1420183D01*
X1675923Y1420100D01*
X1676132Y1419850D01*
X1676257Y1419558D01*
Y1418517D01*
G01Y1419558D02*
X1677465Y1420183D01*
G01X1677173Y1421742D02*
X1677382Y1422033D01*
X1677465Y1422367D01*
X1677382Y1422700D01*
X1677132Y1422992D01*
X1676757Y1423200D01*
X1676382Y1423283D01*
X1675923D01*
X1675548Y1423200D01*
X1675215Y1422992D01*
X1675048Y1422742D01*
X1674965Y1422450D01*
X1675048Y1422117D01*
X1675215Y1421867D01*
X1675465Y1421700D01*
X1675798Y1421617D01*
X1676090Y1421700D01*
X1676382Y1421908D01*
X1676548Y1422158D01*
X1676590Y1422450D01*
X1676507Y1422783D01*
X1676298Y1423033D01*
X1675923Y1423283D01*
G01X1677090Y1424633D02*
X1677298Y1424883D01*
X1677423Y1425175D01*
X1677465Y1425550D01*
X1677382Y1425925D01*
X1677215Y1426217D01*
X1676923Y1426425D01*
X1676590Y1426467D01*
X1676257Y1426383D01*
X1676048Y1426175D01*
X1675882Y1425883D01*
X1675840Y1425592D01*
X1675882Y1425300D01*
X1676048Y1424925D01*
X1674965Y1425050D01*
Y1426175D01*
G01X1677465Y1428650D02*
X1677423Y1428942D01*
X1677298Y1429275D01*
X1677090Y1429483D01*
X1676798Y1429567D01*
X1676507Y1429483D01*
X1676257Y1429233D01*
X1676132Y1428858D01*
Y1428442D01*
X1676048Y1428192D01*
X1675840Y1427983D01*
X1675548Y1427900D01*
X1675257Y1428025D01*
X1675048Y1428317D01*
X1674965Y1428650D01*
X1675048Y1428983D01*
X1675257Y1429275D01*
X1675548Y1429400D01*
X1675840Y1429317D01*
X1676048Y1429108D01*
X1676132Y1428858D01*
Y1428442D01*
X1676257Y1428067D01*
X1676507Y1427817D01*
X1676798Y1427733D01*
X1677090Y1427817D01*
X1677298Y1428025D01*
X1677423Y1428358D01*
X1677465Y1428650D01*
G01X1660643Y1419500D02*
Y1422000D01*
X1661684D01*
X1662018Y1421875D01*
X1662226Y1421708D01*
X1662309Y1421375D01*
X1662226Y1421042D01*
X1661976Y1420833D01*
X1661684Y1420708D01*
X1660643D01*
G01X1661684D02*
X1662309Y1419500D01*
G01X1663868Y1419792D02*
X1664159Y1419583D01*
X1664493Y1419500D01*
X1664826Y1419583D01*
X1665118Y1419833D01*
X1665326Y1420208D01*
X1665409Y1420583D01*
Y1421042D01*
X1665326Y1421417D01*
X1665118Y1421750D01*
X1664868Y1421917D01*
X1664576Y1422000D01*
X1664243Y1421917D01*
X1663993Y1421750D01*
X1663826Y1421500D01*
X1663743Y1421167D01*
X1663826Y1420875D01*
X1664034Y1420583D01*
X1664284Y1420417D01*
X1664576Y1420375D01*
X1664909Y1420458D01*
X1665159Y1420667D01*
X1665409Y1421042D01*
G01X1666884Y1420542D02*
X1667176Y1420833D01*
X1667426Y1421000D01*
X1667759Y1421083D01*
X1668051Y1421000D01*
X1668259Y1420833D01*
X1668426Y1420583D01*
X1668468Y1420292D01*
X1668426Y1420042D01*
X1668259Y1419792D01*
X1668009Y1419583D01*
X1667718Y1419500D01*
X1667384Y1419583D01*
X1667093Y1419833D01*
X1666926Y1420208D01*
X1666884Y1420625D01*
X1666968Y1421167D01*
X1667093Y1421458D01*
X1667301Y1421750D01*
X1667593Y1421958D01*
X1667884Y1422000D01*
X1668176Y1421917D01*
X1668384Y1421708D01*
G01X1670776Y1419500D02*
Y1422000D01*
X1670276Y1421500D01*
G01Y1419500D02*
X1671276D01*
G01X1709126Y1394517D02*
X1706626D01*
Y1395558D01*
X1706751Y1395892D01*
X1706918Y1396100D01*
X1707251Y1396183D01*
X1707584Y1396100D01*
X1707793Y1395850D01*
X1707918Y1395558D01*
Y1394517D01*
G01Y1395558D02*
X1709126Y1396183D01*
G01X1708834Y1397742D02*
X1709043Y1398033D01*
X1709126Y1398367D01*
X1709043Y1398700D01*
X1708793Y1398992D01*
X1708418Y1399200D01*
X1708043Y1399283D01*
X1707584D01*
X1707209Y1399200D01*
X1706876Y1398992D01*
X1706709Y1398742D01*
X1706626Y1398450D01*
X1706709Y1398117D01*
X1706876Y1397867D01*
X1707126Y1397700D01*
X1707459Y1397617D01*
X1707751Y1397700D01*
X1708043Y1397908D01*
X1708209Y1398158D01*
X1708251Y1398450D01*
X1708168Y1398783D01*
X1707959Y1399033D01*
X1707584Y1399283D01*
G01X1709126Y1401467D02*
X1708584Y1401550D01*
X1708126Y1401675D01*
X1707709Y1401842D01*
X1707251Y1402050D01*
X1706626Y1402383D01*
Y1400717D01*
G01X1709126Y1404650D02*
X1706626D01*
X1707126Y1404150D01*
G01X1709126D02*
Y1405150D01*
G01X1709626Y1422200D02*
X1705626D01*
Y1414800D01*
G01X1709126Y1381017D02*
X1706626D01*
Y1382058D01*
X1706751Y1382392D01*
X1706918Y1382600D01*
X1707251Y1382683D01*
X1707584Y1382600D01*
X1707793Y1382350D01*
X1707918Y1382058D01*
Y1381017D01*
G01Y1382058D02*
X1709126Y1382683D01*
G01Y1384950D02*
X1706626D01*
X1707126Y1384450D01*
G01X1709126D02*
Y1385450D01*
G01Y1388550D02*
X1706626D01*
X1708418Y1387008D01*
Y1389092D01*
G01X1708084Y1390358D02*
X1707793Y1390650D01*
X1707626Y1390900D01*
X1707543Y1391233D01*
X1707626Y1391525D01*
X1707793Y1391733D01*
X1708043Y1391900D01*
X1708334Y1391942D01*
X1708584Y1391900D01*
X1708834Y1391733D01*
X1709043Y1391483D01*
X1709126Y1391192D01*
X1709043Y1390858D01*
X1708793Y1390567D01*
X1708418Y1390400D01*
X1708001Y1390358D01*
X1707459Y1390442D01*
X1707168Y1390567D01*
X1706876Y1390775D01*
X1706668Y1391067D01*
X1706626Y1391358D01*
X1706709Y1391650D01*
X1706918Y1391858D01*
G01X1709626Y1414550D02*
X1705626D01*
Y1407150D01*
G01X1713626Y1381017D02*
X1711126D01*
Y1382058D01*
X1711251Y1382392D01*
X1711418Y1382600D01*
X1711751Y1382683D01*
X1712084Y1382600D01*
X1712293Y1382350D01*
X1712418Y1382058D01*
Y1381017D01*
G01Y1382058D02*
X1713626Y1382683D01*
G01Y1384950D02*
X1711126D01*
X1711626Y1384450D01*
G01X1713626D02*
Y1385450D01*
G01Y1388550D02*
X1711126D01*
X1712918Y1387008D01*
Y1389092D01*
G01X1713334Y1390442D02*
X1713543Y1390733D01*
X1713626Y1391067D01*
X1713543Y1391400D01*
X1713293Y1391692D01*
X1712918Y1391900D01*
X1712543Y1391983D01*
X1712084D01*
X1711709Y1391900D01*
X1711376Y1391692D01*
X1711209Y1391442D01*
X1711126Y1391150D01*
X1711209Y1390817D01*
X1711376Y1390567D01*
X1711626Y1390400D01*
X1711959Y1390317D01*
X1712251Y1390400D01*
X1712543Y1390608D01*
X1712709Y1390858D01*
X1712751Y1391150D01*
X1712668Y1391483D01*
X1712459Y1391733D01*
X1712084Y1391983D01*
G01X1710176Y1410700D02*
Y1406700D01*
X1717576D01*
G01X1718126Y1422600D02*
X1720226Y1420800D01*
X1718126Y1418600D01*
G01X1718026Y1415000D02*
X1737226D01*
Y1426200D01*
X1718026D01*
Y1415000D01*
X1718426D01*
G01X1660643Y1423661D02*
Y1426161D01*
X1661684D01*
X1662018Y1426036D01*
X1662226Y1425869D01*
X1662309Y1425536D01*
X1662226Y1425203D01*
X1661976Y1424994D01*
X1661684Y1424869D01*
X1660643D01*
G01X1661684D02*
X1662309Y1423661D01*
G01X1663868Y1423953D02*
X1664159Y1423744D01*
X1664493Y1423661D01*
X1664826Y1423744D01*
X1665118Y1423994D01*
X1665326Y1424369D01*
X1665409Y1424744D01*
Y1425203D01*
X1665326Y1425578D01*
X1665118Y1425911D01*
X1664868Y1426078D01*
X1664576Y1426161D01*
X1664243Y1426078D01*
X1663993Y1425911D01*
X1663826Y1425661D01*
X1663743Y1425328D01*
X1663826Y1425036D01*
X1664034Y1424744D01*
X1664284Y1424578D01*
X1664576Y1424536D01*
X1664909Y1424619D01*
X1665159Y1424828D01*
X1665409Y1425203D01*
G01X1666884Y1424703D02*
X1667176Y1424994D01*
X1667426Y1425161D01*
X1667759Y1425244D01*
X1668051Y1425161D01*
X1668259Y1424994D01*
X1668426Y1424744D01*
X1668468Y1424453D01*
X1668426Y1424203D01*
X1668259Y1423953D01*
X1668009Y1423744D01*
X1667718Y1423661D01*
X1667384Y1423744D01*
X1667093Y1423994D01*
X1666926Y1424369D01*
X1666884Y1424786D01*
X1666968Y1425328D01*
X1667093Y1425619D01*
X1667301Y1425911D01*
X1667593Y1426119D01*
X1667884Y1426161D01*
X1668176Y1426078D01*
X1668384Y1425869D01*
G01X1670776Y1426161D02*
X1670443Y1426078D01*
X1670193Y1425869D01*
X1670026Y1425619D01*
X1669901Y1425286D01*
X1669859Y1424911D01*
X1669901Y1424536D01*
X1670026Y1424203D01*
X1670193Y1423953D01*
X1670443Y1423744D01*
X1670776Y1423661D01*
X1671109Y1423744D01*
X1671359Y1423953D01*
X1671526Y1424203D01*
X1671651Y1424536D01*
X1671693Y1424911D01*
X1671651Y1425286D01*
X1671526Y1425619D01*
X1671359Y1425869D01*
X1671109Y1426078D01*
X1670776Y1426161D01*
G01X1696126Y1398983D02*
X1693626D01*
Y1399817D01*
X1693751Y1400150D01*
X1693918Y1400400D01*
X1694168Y1400608D01*
X1694459Y1400775D01*
X1694876Y1400817D01*
X1695293Y1400775D01*
X1695584Y1400608D01*
X1695834Y1400400D01*
X1696001Y1400150D01*
X1696126Y1399817D01*
Y1398983D01*
G01Y1403500D02*
X1693626D01*
X1695418Y1401958D01*
Y1404042D01*
G01X1696126Y1406100D02*
X1696084Y1406392D01*
X1695959Y1406725D01*
X1695751Y1406933D01*
X1695459Y1407017D01*
X1695168Y1406933D01*
X1694918Y1406683D01*
X1694793Y1406308D01*
Y1405892D01*
X1694709Y1405642D01*
X1694501Y1405433D01*
X1694209Y1405350D01*
X1693918Y1405475D01*
X1693709Y1405767D01*
X1693626Y1406100D01*
X1693709Y1406433D01*
X1693918Y1406725D01*
X1694209Y1406850D01*
X1694501Y1406767D01*
X1694709Y1406558D01*
X1694793Y1406308D01*
Y1405892D01*
X1694918Y1405517D01*
X1695168Y1405267D01*
X1695459Y1405183D01*
X1695751Y1405267D01*
X1695959Y1405475D01*
X1696084Y1405808D01*
X1696126Y1406100D01*
G01X1698126Y1397900D02*
Y1414000D01*
G01X1705126Y1397900D02*
X1698126D01*
G01X1705126Y1414000D02*
Y1397900D01*
G01X1698126Y1414000D02*
X1705126D01*
G01X1690026Y1420550D02*
X1689984Y1420217D01*
X1689818Y1419925D01*
X1689568Y1419675D01*
X1689276Y1419508D01*
X1688943Y1419425D01*
X1688609D01*
X1688276Y1419508D01*
X1687984Y1419675D01*
X1687734Y1419925D01*
X1687568Y1420217D01*
X1687526Y1420550D01*
X1687568Y1420883D01*
X1687734Y1421175D01*
X1687984Y1421425D01*
X1688276Y1421592D01*
X1688609Y1421675D01*
X1688943D01*
X1689276Y1421592D01*
X1689568Y1421425D01*
X1689818Y1421175D01*
X1689984Y1420883D01*
X1690026Y1420550D01*
G01X1689359Y1420883D02*
X1690026Y1421383D01*
G01X1687943Y1422858D02*
X1687693Y1423108D01*
X1687568Y1423400D01*
X1687526Y1423733D01*
X1687609Y1424150D01*
X1687818Y1424442D01*
X1688068Y1424525D01*
X1688318Y1424483D01*
X1688526Y1424317D01*
X1688943Y1423483D01*
X1689234Y1423108D01*
X1689651Y1422858D01*
X1690026Y1422775D01*
Y1424525D01*
G01Y1426750D02*
X1687526D01*
X1688026Y1426250D01*
G01X1690026D02*
Y1427250D01*
G01Y1430350D02*
X1687526D01*
X1689318Y1428808D01*
Y1430892D01*
G01X1705126Y1418500D02*
Y1432500D01*
G01X1692126Y1418500D02*
X1705126D01*
G01X1692126Y1432500D02*
Y1418500D01*
G01X1659184Y1498000D02*
Y1500500D01*
X1660768D01*
G01X1660184Y1499292D02*
X1659184D01*
G01X1662034Y1498000D02*
X1663076Y1500500D01*
X1664118Y1498000D01*
G01X1663743Y1498875D02*
X1662409D01*
G01X1665218Y1498000D02*
Y1500500D01*
X1667134Y1498000D01*
Y1500500D01*
G01X1669776Y1498000D02*
Y1500500D01*
X1668234Y1498708D01*
X1670318D01*
G01X1783646Y1527769D02*
Y1470269D01*
X1767446D01*
Y1439269D01*
X1689246D01*
Y1470269D01*
X1673046D01*
Y1527769D01*
X1783646D01*
G01X1646173Y1450767D02*
X1646048Y1450517D01*
X1645965Y1450225D01*
Y1449892D01*
X1646090Y1449517D01*
X1646298Y1449225D01*
X1646548Y1449017D01*
X1646965Y1448850D01*
X1647340Y1448808D01*
X1647715Y1448892D01*
X1647965Y1449017D01*
X1648215Y1449267D01*
X1648382Y1449558D01*
X1648465Y1449850D01*
Y1450142D01*
X1648382Y1450433D01*
X1648257Y1450683D01*
X1648090Y1450892D01*
G01Y1452033D02*
X1648298Y1452283D01*
X1648423Y1452575D01*
X1648465Y1452950D01*
X1648382Y1453325D01*
X1648215Y1453617D01*
X1647923Y1453825D01*
X1647590Y1453867D01*
X1647257Y1453783D01*
X1647048Y1453575D01*
X1646882Y1453283D01*
X1646840Y1452992D01*
X1646882Y1452700D01*
X1647048Y1452325D01*
X1645965Y1452450D01*
Y1453575D01*
G01X1647965Y1455133D02*
X1648257Y1455383D01*
X1648423Y1455717D01*
X1648465Y1456092D01*
X1648423Y1456425D01*
X1648215Y1456758D01*
X1647965Y1456967D01*
X1647715Y1457008D01*
X1647423Y1456925D01*
X1647215Y1456633D01*
X1647132Y1456342D01*
Y1455967D01*
G01Y1456342D02*
X1647007Y1456592D01*
X1646798Y1456800D01*
X1646548Y1456883D01*
X1646298Y1456800D01*
X1646090Y1456592D01*
X1645965Y1456217D01*
X1646007Y1455842D01*
X1646173Y1455467D01*
G01X1648465Y1459650D02*
X1645965D01*
X1647757Y1458108D01*
Y1460192D01*
G01X1644465Y1449017D02*
X1641965D01*
Y1450058D01*
X1642090Y1450392D01*
X1642257Y1450600D01*
X1642590Y1450683D01*
X1642923Y1450600D01*
X1643132Y1450350D01*
X1643257Y1450058D01*
Y1449017D01*
G01Y1450058D02*
X1644465Y1450683D01*
G01X1644173Y1452242D02*
X1644382Y1452533D01*
X1644465Y1452867D01*
X1644382Y1453200D01*
X1644132Y1453492D01*
X1643757Y1453700D01*
X1643382Y1453783D01*
X1642923D01*
X1642548Y1453700D01*
X1642215Y1453492D01*
X1642048Y1453242D01*
X1641965Y1452950D01*
X1642048Y1452617D01*
X1642215Y1452367D01*
X1642465Y1452200D01*
X1642798Y1452117D01*
X1643090Y1452200D01*
X1643382Y1452408D01*
X1643548Y1452658D01*
X1643590Y1452950D01*
X1643507Y1453283D01*
X1643298Y1453533D01*
X1642923Y1453783D01*
G01X1644090Y1455133D02*
X1644298Y1455383D01*
X1644423Y1455675D01*
X1644465Y1456050D01*
X1644382Y1456425D01*
X1644215Y1456717D01*
X1643923Y1456925D01*
X1643590Y1456967D01*
X1643257Y1456883D01*
X1643048Y1456675D01*
X1642882Y1456383D01*
X1642840Y1456092D01*
X1642882Y1455800D01*
X1643048Y1455425D01*
X1641965Y1455550D01*
Y1456675D01*
G01X1643965Y1458233D02*
X1644257Y1458483D01*
X1644423Y1458817D01*
X1644465Y1459192D01*
X1644423Y1459525D01*
X1644215Y1459858D01*
X1643965Y1460067D01*
X1643715Y1460108D01*
X1643423Y1460025D01*
X1643215Y1459733D01*
X1643132Y1459442D01*
Y1459067D01*
G01Y1459442D02*
X1643007Y1459692D01*
X1642798Y1459900D01*
X1642548Y1459983D01*
X1642298Y1459900D01*
X1642090Y1459692D01*
X1641965Y1459317D01*
X1642007Y1458942D01*
X1642173Y1458567D01*
G01X1674626Y1451800D02*
X1678626D01*
Y1459200D01*
G01X1637517Y1463500D02*
Y1466000D01*
X1638558D01*
X1638892Y1465875D01*
X1639100Y1465708D01*
X1639183Y1465375D01*
X1639100Y1465042D01*
X1638850Y1464833D01*
X1638558Y1464708D01*
X1637517D01*
G01X1638558D02*
X1639183Y1463500D01*
G01X1640742Y1463792D02*
X1641033Y1463583D01*
X1641367Y1463500D01*
X1641700Y1463583D01*
X1641992Y1463833D01*
X1642200Y1464208D01*
X1642283Y1464583D01*
Y1465042D01*
X1642200Y1465417D01*
X1641992Y1465750D01*
X1641742Y1465917D01*
X1641450Y1466000D01*
X1641117Y1465917D01*
X1640867Y1465750D01*
X1640700Y1465500D01*
X1640617Y1465167D01*
X1640700Y1464875D01*
X1640908Y1464583D01*
X1641158Y1464417D01*
X1641450Y1464375D01*
X1641783Y1464458D01*
X1642033Y1464667D01*
X1642283Y1465042D01*
G01X1643633Y1463875D02*
X1643883Y1463667D01*
X1644175Y1463542D01*
X1644550Y1463500D01*
X1644925Y1463583D01*
X1645217Y1463750D01*
X1645425Y1464042D01*
X1645467Y1464375D01*
X1645383Y1464708D01*
X1645175Y1464917D01*
X1644883Y1465083D01*
X1644592Y1465125D01*
X1644300Y1465083D01*
X1643925Y1464917D01*
X1644050Y1466000D01*
X1645175D01*
G01X1648150Y1463500D02*
Y1466000D01*
X1646608Y1464208D01*
X1648692D01*
G01X1650800Y1467000D02*
Y1463000D01*
X1658200D01*
G01X1654510Y1458700D02*
X1650510D01*
Y1451300D01*
G01X1629143Y1451000D02*
Y1453500D01*
X1630184D01*
X1630518Y1453375D01*
X1630726Y1453208D01*
X1630809Y1452875D01*
X1630726Y1452542D01*
X1630476Y1452333D01*
X1630184Y1452208D01*
X1629143D01*
G01X1630184D02*
X1630809Y1451000D01*
G01X1632368Y1451292D02*
X1632659Y1451083D01*
X1632993Y1451000D01*
X1633326Y1451083D01*
X1633618Y1451333D01*
X1633826Y1451708D01*
X1633909Y1452083D01*
Y1452542D01*
X1633826Y1452917D01*
X1633618Y1453250D01*
X1633368Y1453417D01*
X1633076Y1453500D01*
X1632743Y1453417D01*
X1632493Y1453250D01*
X1632326Y1453000D01*
X1632243Y1452667D01*
X1632326Y1452375D01*
X1632534Y1452083D01*
X1632784Y1451917D01*
X1633076Y1451875D01*
X1633409Y1451958D01*
X1633659Y1452167D01*
X1633909Y1452542D01*
G01X1635259Y1451375D02*
X1635509Y1451167D01*
X1635801Y1451042D01*
X1636176Y1451000D01*
X1636551Y1451083D01*
X1636843Y1451250D01*
X1637051Y1451542D01*
X1637093Y1451875D01*
X1637009Y1452208D01*
X1636801Y1452417D01*
X1636509Y1452583D01*
X1636218Y1452625D01*
X1635926Y1452583D01*
X1635551Y1452417D01*
X1635676Y1453500D01*
X1636801D01*
G01X1639193Y1451000D02*
X1639276Y1451542D01*
X1639401Y1452000D01*
X1639568Y1452417D01*
X1639776Y1452875D01*
X1640109Y1453500D01*
X1638443D01*
G01X1671326Y1450500D02*
Y1454500D01*
X1663926D01*
G01X1674626Y1433300D02*
X1678626D01*
Y1440700D01*
G01X1671326Y1432000D02*
Y1436000D01*
X1663926D01*
G01X1629143Y1455161D02*
Y1457661D01*
X1630184D01*
X1630518Y1457536D01*
X1630726Y1457369D01*
X1630809Y1457036D01*
X1630726Y1456703D01*
X1630476Y1456494D01*
X1630184Y1456369D01*
X1629143D01*
G01X1630184D02*
X1630809Y1455161D01*
G01X1632368Y1455453D02*
X1632659Y1455244D01*
X1632993Y1455161D01*
X1633326Y1455244D01*
X1633618Y1455494D01*
X1633826Y1455869D01*
X1633909Y1456244D01*
Y1456703D01*
X1633826Y1457078D01*
X1633618Y1457411D01*
X1633368Y1457578D01*
X1633076Y1457661D01*
X1632743Y1457578D01*
X1632493Y1457411D01*
X1632326Y1457161D01*
X1632243Y1456828D01*
X1632326Y1456536D01*
X1632534Y1456244D01*
X1632784Y1456078D01*
X1633076Y1456036D01*
X1633409Y1456119D01*
X1633659Y1456328D01*
X1633909Y1456703D01*
G01X1635259Y1455536D02*
X1635509Y1455328D01*
X1635801Y1455203D01*
X1636176Y1455161D01*
X1636551Y1455244D01*
X1636843Y1455411D01*
X1637051Y1455703D01*
X1637093Y1456036D01*
X1637009Y1456369D01*
X1636801Y1456578D01*
X1636509Y1456744D01*
X1636218Y1456786D01*
X1635926Y1456744D01*
X1635551Y1456578D01*
X1635676Y1457661D01*
X1636801D01*
G01X1638484Y1456203D02*
X1638776Y1456494D01*
X1639026Y1456661D01*
X1639359Y1456744D01*
X1639651Y1456661D01*
X1639859Y1456494D01*
X1640026Y1456244D01*
X1640068Y1455953D01*
X1640026Y1455703D01*
X1639859Y1455453D01*
X1639609Y1455244D01*
X1639318Y1455161D01*
X1638984Y1455244D01*
X1638693Y1455494D01*
X1638526Y1455869D01*
X1638484Y1456286D01*
X1638568Y1456828D01*
X1638693Y1457119D01*
X1638901Y1457411D01*
X1639193Y1457619D01*
X1639484Y1457661D01*
X1639776Y1457578D01*
X1639984Y1457369D01*
G01X1661983Y1470500D02*
Y1473000D01*
X1662817D01*
X1663150Y1472875D01*
X1663400Y1472708D01*
X1663608Y1472458D01*
X1663775Y1472167D01*
X1663817Y1471750D01*
X1663775Y1471333D01*
X1663608Y1471042D01*
X1663400Y1470792D01*
X1663150Y1470625D01*
X1662817Y1470500D01*
X1661983D01*
G01X1666500D02*
Y1473000D01*
X1664958Y1471208D01*
X1667042D01*
G01X1668183Y1471000D02*
X1668433Y1470708D01*
X1668767Y1470542D01*
X1669142Y1470500D01*
X1669475Y1470542D01*
X1669808Y1470750D01*
X1670017Y1471000D01*
X1670058Y1471250D01*
X1669975Y1471542D01*
X1669683Y1471750D01*
X1669392Y1471833D01*
X1669017D01*
G01X1669392D02*
X1669642Y1471958D01*
X1669850Y1472167D01*
X1669933Y1472417D01*
X1669850Y1472667D01*
X1669642Y1472875D01*
X1669267Y1473000D01*
X1668892Y1472958D01*
X1668517Y1472792D01*
G01X1663626Y1460000D02*
X1684626D01*
G01D02*
Y1468000D01*
G01D02*
X1663626D01*
G01D02*
Y1460000D01*
G01X1650483Y1442000D02*
Y1444500D01*
X1651317D01*
X1651650Y1444375D01*
X1651900Y1444208D01*
X1652108Y1443958D01*
X1652275Y1443667D01*
X1652317Y1443250D01*
X1652275Y1442833D01*
X1652108Y1442542D01*
X1651900Y1442292D01*
X1651650Y1442125D01*
X1651317Y1442000D01*
X1650483D01*
G01X1655000D02*
Y1444500D01*
X1653458Y1442708D01*
X1655542D01*
G01X1658100Y1442000D02*
Y1444500D01*
X1656558Y1442708D01*
X1658642D01*
G01X1663626Y1441500D02*
X1684626D01*
G01D02*
Y1449500D01*
G01D02*
X1663626D01*
G01D02*
Y1441500D01*
G01X1705126Y1432500D02*
X1692126D01*
G01X1761643Y107319D02*
X1766693D01*
Y206019D01*
X1791343D01*
Y21619D01*
X1766693D01*
Y80319D01*
X1761643D01*
Y107319D01*
G01X1750395Y63672D02*
X1750145Y63797D01*
X1749853Y63880D01*
X1749520D01*
X1749145Y63755D01*
X1748853Y63547D01*
X1748645Y63297D01*
X1748478Y62880D01*
X1748436Y62505D01*
X1748520Y62130D01*
X1748645Y61880D01*
X1748895Y61630D01*
X1749186Y61463D01*
X1749478Y61380D01*
X1749770D01*
X1750061Y61463D01*
X1750311Y61588D01*
X1750520Y61755D01*
G01X1753078Y61380D02*
Y63880D01*
X1751536Y62088D01*
X1753620D01*
G01X1755595Y61380D02*
X1755678Y61922D01*
X1755803Y62380D01*
X1755970Y62797D01*
X1756178Y63255D01*
X1756511Y63880D01*
X1754845D01*
G01X1758778Y61380D02*
Y63880D01*
X1758278Y63380D01*
G01Y61380D02*
X1759278D01*
G01X1750267Y67792D02*
X1750017Y67917D01*
X1749725Y68000D01*
X1749392D01*
X1749017Y67875D01*
X1748725Y67667D01*
X1748517Y67417D01*
X1748350Y67000D01*
X1748308Y66625D01*
X1748392Y66250D01*
X1748517Y66000D01*
X1748767Y65750D01*
X1749058Y65583D01*
X1749350Y65500D01*
X1749642D01*
X1749933Y65583D01*
X1750183Y65708D01*
X1750392Y65875D01*
G01X1752950Y65500D02*
Y68000D01*
X1751408Y66208D01*
X1753492D01*
G01X1755467Y65500D02*
X1755550Y66042D01*
X1755675Y66500D01*
X1755842Y66917D01*
X1756050Y67375D01*
X1756383Y68000D01*
X1754717D01*
G01X1758650D02*
X1758317Y67917D01*
X1758067Y67708D01*
X1757900Y67458D01*
X1757775Y67125D01*
X1757733Y66750D01*
X1757775Y66375D01*
X1757900Y66042D01*
X1758067Y65792D01*
X1758317Y65583D01*
X1758650Y65500D01*
X1758983Y65583D01*
X1759233Y65792D01*
X1759400Y66042D01*
X1759525Y66375D01*
X1759567Y66750D01*
X1759525Y67125D01*
X1759400Y67458D01*
X1759233Y67708D01*
X1758983Y67917D01*
X1758650Y68000D01*
G01X1795067Y68492D02*
X1794817Y68617D01*
X1794525Y68700D01*
X1794192D01*
X1793817Y68575D01*
X1793525Y68367D01*
X1793317Y68117D01*
X1793150Y67700D01*
X1793108Y67325D01*
X1793192Y66950D01*
X1793317Y66700D01*
X1793567Y66450D01*
X1793858Y66283D01*
X1794150Y66200D01*
X1794442D01*
X1794733Y66283D01*
X1794983Y66408D01*
X1795192Y66575D01*
G01X1797750Y66200D02*
Y68700D01*
X1796208Y66908D01*
X1798292D01*
G01X1800350Y66200D02*
X1800642Y66242D01*
X1800975Y66367D01*
X1801183Y66575D01*
X1801267Y66867D01*
X1801183Y67158D01*
X1800933Y67408D01*
X1800558Y67533D01*
X1800142D01*
X1799892Y67617D01*
X1799683Y67825D01*
X1799600Y68117D01*
X1799725Y68408D01*
X1800017Y68617D01*
X1800350Y68700D01*
X1800683Y68617D01*
X1800975Y68408D01*
X1801100Y68117D01*
X1801017Y67825D01*
X1800808Y67617D01*
X1800558Y67533D01*
X1800142D01*
X1799767Y67408D01*
X1799517Y67158D01*
X1799433Y66867D01*
X1799517Y66575D01*
X1799725Y66367D01*
X1800058Y66242D01*
X1800350Y66200D01*
G01X1803450Y68700D02*
X1803117Y68617D01*
X1802867Y68408D01*
X1802700Y68158D01*
X1802575Y67825D01*
X1802533Y67450D01*
X1802575Y67075D01*
X1802700Y66742D01*
X1802867Y66492D01*
X1803117Y66283D01*
X1803450Y66200D01*
X1803783Y66283D01*
X1804033Y66492D01*
X1804200Y66742D01*
X1804325Y67075D01*
X1804367Y67450D01*
X1804325Y67825D01*
X1804200Y68158D01*
X1804033Y68408D01*
X1803783Y68617D01*
X1803450Y68700D01*
G01X1810017Y10792D02*
X1809767Y10917D01*
X1809475Y11000D01*
X1809142D01*
X1808767Y10875D01*
X1808475Y10667D01*
X1808267Y10417D01*
X1808100Y10000D01*
X1808058Y9625D01*
X1808142Y9250D01*
X1808267Y9000D01*
X1808517Y8750D01*
X1808808Y8583D01*
X1809100Y8500D01*
X1809392D01*
X1809683Y8583D01*
X1809933Y8708D01*
X1810142Y8875D01*
G01X1811283Y9000D02*
X1811533Y8708D01*
X1811867Y8542D01*
X1812242Y8500D01*
X1812575Y8542D01*
X1812908Y8750D01*
X1813117Y9000D01*
X1813158Y9250D01*
X1813075Y9542D01*
X1812783Y9750D01*
X1812492Y9833D01*
X1812117D01*
G01X1812492D02*
X1812742Y9958D01*
X1812950Y10167D01*
X1813033Y10417D01*
X1812950Y10667D01*
X1812742Y10875D01*
X1812367Y11000D01*
X1811992Y10958D01*
X1811617Y10792D01*
G01X1814508Y10583D02*
X1814758Y10833D01*
X1815050Y10958D01*
X1815383Y11000D01*
X1815800Y10917D01*
X1816092Y10708D01*
X1816175Y10458D01*
X1816133Y10208D01*
X1815967Y10000D01*
X1815133Y9583D01*
X1814758Y9292D01*
X1814508Y8875D01*
X1814425Y8500D01*
X1816175D01*
G01X1795500Y73517D02*
X1793000D01*
Y74558D01*
X1793125Y74892D01*
X1793292Y75100D01*
X1793625Y75183D01*
X1793958Y75100D01*
X1794167Y74850D01*
X1794292Y74558D01*
Y73517D01*
G01Y74558D02*
X1795500Y75183D01*
G01Y77450D02*
X1795458Y77742D01*
X1795333Y78075D01*
X1795125Y78283D01*
X1794833Y78367D01*
X1794542Y78283D01*
X1794292Y78033D01*
X1794167Y77658D01*
Y77242D01*
X1794083Y76992D01*
X1793875Y76783D01*
X1793583Y76700D01*
X1793292Y76825D01*
X1793083Y77117D01*
X1793000Y77450D01*
X1793083Y77783D01*
X1793292Y78075D01*
X1793583Y78200D01*
X1793875Y78117D01*
X1794083Y77908D01*
X1794167Y77658D01*
Y77242D01*
X1794292Y76867D01*
X1794542Y76617D01*
X1794833Y76533D01*
X1795125Y76617D01*
X1795333Y76825D01*
X1795458Y77158D01*
X1795500Y77450D01*
G01X1795125Y79633D02*
X1795333Y79883D01*
X1795458Y80175D01*
X1795500Y80550D01*
X1795417Y80925D01*
X1795250Y81217D01*
X1794958Y81425D01*
X1794625Y81467D01*
X1794292Y81383D01*
X1794083Y81175D01*
X1793917Y80883D01*
X1793875Y80592D01*
X1793917Y80300D01*
X1794083Y79925D01*
X1793000Y80050D01*
Y81175D01*
G01X1795208Y82942D02*
X1795417Y83233D01*
X1795500Y83567D01*
X1795417Y83900D01*
X1795167Y84192D01*
X1794792Y84400D01*
X1794417Y84483D01*
X1793958D01*
X1793583Y84400D01*
X1793250Y84192D01*
X1793083Y83942D01*
X1793000Y83650D01*
X1793083Y83317D01*
X1793250Y83067D01*
X1793500Y82900D01*
X1793833Y82817D01*
X1794125Y82900D01*
X1794417Y83108D01*
X1794583Y83358D01*
X1794625Y83650D01*
X1794542Y83983D01*
X1794333Y84233D01*
X1793958Y84483D01*
G01X1801100Y80500D02*
X1797100D01*
Y73100D01*
G01X1792917Y57600D02*
Y60100D01*
X1793958D01*
X1794292Y59975D01*
X1794500Y59808D01*
X1794583Y59475D01*
X1794500Y59142D01*
X1794250Y58933D01*
X1793958Y58808D01*
X1792917D01*
G01X1793958D02*
X1794583Y57600D01*
G01X1796850D02*
X1797142Y57642D01*
X1797475Y57767D01*
X1797683Y57975D01*
X1797767Y58267D01*
X1797683Y58558D01*
X1797433Y58808D01*
X1797058Y58933D01*
X1796642D01*
X1796392Y59017D01*
X1796183Y59225D01*
X1796100Y59517D01*
X1796225Y59808D01*
X1796517Y60017D01*
X1796850Y60100D01*
X1797183Y60017D01*
X1797475Y59808D01*
X1797600Y59517D01*
X1797517Y59225D01*
X1797308Y59017D01*
X1797058Y58933D01*
X1796642D01*
X1796267Y58808D01*
X1796017Y58558D01*
X1795933Y58267D01*
X1796017Y57975D01*
X1796225Y57767D01*
X1796558Y57642D01*
X1796850Y57600D01*
G01X1799158Y58642D02*
X1799450Y58933D01*
X1799700Y59100D01*
X1800033Y59183D01*
X1800325Y59100D01*
X1800533Y58933D01*
X1800700Y58683D01*
X1800742Y58392D01*
X1800700Y58142D01*
X1800533Y57892D01*
X1800283Y57683D01*
X1799992Y57600D01*
X1799658Y57683D01*
X1799367Y57933D01*
X1799200Y58308D01*
X1799158Y58725D01*
X1799242Y59267D01*
X1799367Y59558D01*
X1799575Y59850D01*
X1799867Y60058D01*
X1800158Y60100D01*
X1800450Y60017D01*
X1800658Y59808D01*
G01X1803050Y60100D02*
X1802717Y60017D01*
X1802467Y59808D01*
X1802300Y59558D01*
X1802175Y59225D01*
X1802133Y58850D01*
X1802175Y58475D01*
X1802300Y58142D01*
X1802467Y57892D01*
X1802717Y57683D01*
X1803050Y57600D01*
X1803383Y57683D01*
X1803633Y57892D01*
X1803800Y58142D01*
X1803925Y58475D01*
X1803967Y58850D01*
X1803925Y59225D01*
X1803800Y59558D01*
X1803633Y59808D01*
X1803383Y60017D01*
X1803050Y60100D01*
G01X1795700Y65200D02*
Y61200D01*
X1803100D01*
G01X1818200Y48917D02*
X1815700D01*
Y49958D01*
X1815825Y50292D01*
X1815992Y50500D01*
X1816325Y50583D01*
X1816658Y50500D01*
X1816867Y50250D01*
X1816992Y49958D01*
Y48917D01*
G01Y49958D02*
X1818200Y50583D01*
G01Y52850D02*
X1818158Y53142D01*
X1818033Y53475D01*
X1817825Y53683D01*
X1817533Y53767D01*
X1817242Y53683D01*
X1816992Y53433D01*
X1816867Y53058D01*
Y52642D01*
X1816783Y52392D01*
X1816575Y52183D01*
X1816283Y52100D01*
X1815992Y52225D01*
X1815783Y52517D01*
X1815700Y52850D01*
X1815783Y53183D01*
X1815992Y53475D01*
X1816283Y53600D01*
X1816575Y53517D01*
X1816783Y53308D01*
X1816867Y53058D01*
Y52642D01*
X1816992Y52267D01*
X1817242Y52017D01*
X1817533Y51933D01*
X1817825Y52017D01*
X1818033Y52225D01*
X1818158Y52558D01*
X1818200Y52850D01*
G01X1817158Y55158D02*
X1816867Y55450D01*
X1816700Y55700D01*
X1816617Y56033D01*
X1816700Y56325D01*
X1816867Y56533D01*
X1817117Y56700D01*
X1817408Y56742D01*
X1817658Y56700D01*
X1817908Y56533D01*
X1818117Y56283D01*
X1818200Y55992D01*
X1818117Y55658D01*
X1817867Y55367D01*
X1817492Y55200D01*
X1817075Y55158D01*
X1816533Y55242D01*
X1816242Y55367D01*
X1815950Y55575D01*
X1815742Y55867D01*
X1815700Y56158D01*
X1815783Y56450D01*
X1815992Y56658D01*
G01X1816117Y58258D02*
X1815867Y58508D01*
X1815742Y58800D01*
X1815700Y59133D01*
X1815783Y59550D01*
X1815992Y59842D01*
X1816242Y59925D01*
X1816492Y59883D01*
X1816700Y59717D01*
X1817117Y58883D01*
X1817408Y58508D01*
X1817825Y58258D01*
X1818200Y58175D01*
Y59925D01*
G01Y62400D02*
Y66400D01*
X1810800D01*
G01X1813900Y46117D02*
X1811400D01*
Y47158D01*
X1811525Y47492D01*
X1811692Y47700D01*
X1812025Y47783D01*
X1812358Y47700D01*
X1812567Y47450D01*
X1812692Y47158D01*
Y46117D01*
G01Y47158D02*
X1813900Y47783D01*
G01Y50050D02*
X1813858Y50342D01*
X1813733Y50675D01*
X1813525Y50883D01*
X1813233Y50967D01*
X1812942Y50883D01*
X1812692Y50633D01*
X1812567Y50258D01*
Y49842D01*
X1812483Y49592D01*
X1812275Y49383D01*
X1811983Y49300D01*
X1811692Y49425D01*
X1811483Y49717D01*
X1811400Y50050D01*
X1811483Y50383D01*
X1811692Y50675D01*
X1811983Y50800D01*
X1812275Y50717D01*
X1812483Y50508D01*
X1812567Y50258D01*
Y49842D01*
X1812692Y49467D01*
X1812942Y49217D01*
X1813233Y49133D01*
X1813525Y49217D01*
X1813733Y49425D01*
X1813858Y49758D01*
X1813900Y50050D01*
G01X1812858Y52358D02*
X1812567Y52650D01*
X1812400Y52900D01*
X1812317Y53233D01*
X1812400Y53525D01*
X1812567Y53733D01*
X1812817Y53900D01*
X1813108Y53942D01*
X1813358Y53900D01*
X1813608Y53733D01*
X1813817Y53483D01*
X1813900Y53192D01*
X1813817Y52858D01*
X1813567Y52567D01*
X1813192Y52400D01*
X1812775Y52358D01*
X1812233Y52442D01*
X1811942Y52567D01*
X1811650Y52775D01*
X1811442Y53067D01*
X1811400Y53358D01*
X1811483Y53650D01*
X1811692Y53858D01*
G01X1813900Y56750D02*
X1811400D01*
X1813192Y55208D01*
Y57292D01*
G01X1810500Y66400D02*
X1806500D01*
Y59000D01*
G01X1816317Y35300D02*
Y37800D01*
X1817358D01*
X1817692Y37675D01*
X1817900Y37508D01*
X1817983Y37175D01*
X1817900Y36842D01*
X1817650Y36633D01*
X1817358Y36508D01*
X1816317D01*
G01X1817358D02*
X1817983Y35300D01*
G01X1820250D02*
Y37800D01*
X1819750Y37300D01*
G01Y35300D02*
X1820750D01*
G01X1823850D02*
Y37800D01*
X1822308Y36008D01*
X1824392D01*
G01X1826450Y35300D02*
Y37800D01*
X1825950Y37300D01*
G01Y35300D02*
X1826950D01*
G01X1796700Y44917D02*
X1794200D01*
Y45958D01*
X1794325Y46292D01*
X1794492Y46500D01*
X1794825Y46583D01*
X1795158Y46500D01*
X1795367Y46250D01*
X1795492Y45958D01*
Y44917D01*
G01Y45958D02*
X1796700Y46583D01*
G01Y48850D02*
X1794200D01*
X1794700Y48350D01*
G01X1796700D02*
Y49350D01*
G01X1796200Y51033D02*
X1796492Y51283D01*
X1796658Y51617D01*
X1796700Y51992D01*
X1796658Y52325D01*
X1796450Y52658D01*
X1796200Y52867D01*
X1795950Y52908D01*
X1795658Y52825D01*
X1795450Y52533D01*
X1795367Y52242D01*
Y51867D01*
G01Y52242D02*
X1795242Y52492D01*
X1795033Y52700D01*
X1794783Y52783D01*
X1794533Y52700D01*
X1794325Y52492D01*
X1794200Y52117D01*
X1794242Y51742D01*
X1794408Y51367D01*
G01X1796700Y54967D02*
X1796158Y55050D01*
X1795700Y55175D01*
X1795283Y55342D01*
X1794825Y55550D01*
X1794200Y55883D01*
Y54217D01*
G01X1805400Y55800D02*
X1801400D01*
Y48400D01*
G01X1800500Y44917D02*
X1798000D01*
Y45958D01*
X1798125Y46292D01*
X1798292Y46500D01*
X1798625Y46583D01*
X1798958Y46500D01*
X1799167Y46250D01*
X1799292Y45958D01*
Y44917D01*
G01Y45958D02*
X1800500Y46583D01*
G01Y48850D02*
X1798000D01*
X1798500Y48350D01*
G01X1800500D02*
Y49350D01*
G01X1800000Y51033D02*
X1800292Y51283D01*
X1800458Y51617D01*
X1800500Y51992D01*
X1800458Y52325D01*
X1800250Y52658D01*
X1800000Y52867D01*
X1799750Y52908D01*
X1799458Y52825D01*
X1799250Y52533D01*
X1799167Y52242D01*
Y51867D01*
G01Y52242D02*
X1799042Y52492D01*
X1798833Y52700D01*
X1798583Y52783D01*
X1798333Y52700D01*
X1798125Y52492D01*
X1798000Y52117D01*
X1798042Y51742D01*
X1798208Y51367D01*
G01X1800500Y55050D02*
X1800458Y55342D01*
X1800333Y55675D01*
X1800125Y55883D01*
X1799833Y55967D01*
X1799542Y55883D01*
X1799292Y55633D01*
X1799167Y55258D01*
Y54842D01*
X1799083Y54592D01*
X1798875Y54383D01*
X1798583Y54300D01*
X1798292Y54425D01*
X1798083Y54717D01*
X1798000Y55050D01*
X1798083Y55383D01*
X1798292Y55675D01*
X1798583Y55800D01*
X1798875Y55717D01*
X1799083Y55508D01*
X1799167Y55258D01*
Y54842D01*
X1799292Y54467D01*
X1799542Y54217D01*
X1799833Y54133D01*
X1800125Y54217D01*
X1800333Y54425D01*
X1800458Y54758D01*
X1800500Y55050D01*
G01X1810300Y55900D02*
X1806300D01*
Y48500D01*
G01X1810017Y14792D02*
X1809767Y14917D01*
X1809475Y15000D01*
X1809142D01*
X1808767Y14875D01*
X1808475Y14667D01*
X1808267Y14417D01*
X1808100Y14000D01*
X1808058Y13625D01*
X1808142Y13250D01*
X1808267Y13000D01*
X1808517Y12750D01*
X1808808Y12583D01*
X1809100Y12500D01*
X1809392D01*
X1809683Y12583D01*
X1809933Y12708D01*
X1810142Y12875D01*
G01X1811283Y13000D02*
X1811533Y12708D01*
X1811867Y12542D01*
X1812242Y12500D01*
X1812575Y12542D01*
X1812908Y12750D01*
X1813117Y13000D01*
X1813158Y13250D01*
X1813075Y13542D01*
X1812783Y13750D01*
X1812492Y13833D01*
X1812117D01*
G01X1812492D02*
X1812742Y13958D01*
X1812950Y14167D01*
X1813033Y14417D01*
X1812950Y14667D01*
X1812742Y14875D01*
X1812367Y15000D01*
X1811992Y14958D01*
X1811617Y14792D01*
G01X1815300Y12500D02*
Y15000D01*
X1814800Y14500D01*
G01Y12500D02*
X1815800D01*
G01X1815900Y41500D02*
Y39000D01*
G01X1814942Y41500D02*
X1816858D01*
G01X1818167Y39000D02*
Y41500D01*
X1819167D01*
X1819500Y41375D01*
X1819750Y41083D01*
X1819833Y40750D01*
X1819750Y40417D01*
X1819542Y40167D01*
X1819167Y40042D01*
X1818167D01*
G01X1821183Y39500D02*
X1821433Y39208D01*
X1821767Y39042D01*
X1822142Y39000D01*
X1822475Y39042D01*
X1822808Y39250D01*
X1823017Y39500D01*
X1823058Y39750D01*
X1822975Y40042D01*
X1822683Y40250D01*
X1822392Y40333D01*
X1822017D01*
G01X1822392D02*
X1822642Y40458D01*
X1822850Y40667D01*
X1822933Y40917D01*
X1822850Y41167D01*
X1822642Y41375D01*
X1822267Y41500D01*
X1821892Y41458D01*
X1821517Y41292D01*
G01X1831900Y90900D02*
X1815800D01*
G01D02*
Y97900D01*
G01X1806350Y80000D02*
X1806017Y80042D01*
X1805725Y80208D01*
X1805475Y80458D01*
X1805308Y80750D01*
X1805225Y81083D01*
Y81417D01*
X1805308Y81750D01*
X1805475Y82042D01*
X1805725Y82292D01*
X1806017Y82458D01*
X1806350Y82500D01*
X1806683Y82458D01*
X1806975Y82292D01*
X1807225Y82042D01*
X1807392Y81750D01*
X1807475Y81417D01*
Y81083D01*
X1807392Y80750D01*
X1807225Y80458D01*
X1806975Y80208D01*
X1806683Y80042D01*
X1806350Y80000D01*
G01X1806683Y80667D02*
X1807183Y80000D01*
G01X1809450D02*
Y82500D01*
X1808950Y82000D01*
G01Y80000D02*
X1809950D01*
G01X1812467D02*
X1812550Y80542D01*
X1812675Y81000D01*
X1812842Y81417D01*
X1813050Y81875D01*
X1813383Y82500D01*
X1811717D01*
G01X1814942Y80292D02*
X1815233Y80083D01*
X1815567Y80000D01*
X1815900Y80083D01*
X1816192Y80333D01*
X1816400Y80708D01*
X1816483Y81083D01*
Y81542D01*
X1816400Y81917D01*
X1816192Y82250D01*
X1815942Y82417D01*
X1815650Y82500D01*
X1815317Y82417D01*
X1815067Y82250D01*
X1814900Y82000D01*
X1814817Y81667D01*
X1814900Y81375D01*
X1815108Y81083D01*
X1815358Y80917D01*
X1815650Y80875D01*
X1815983Y80958D01*
X1816233Y81167D01*
X1816483Y81542D01*
G01X1805600Y78400D02*
Y67000D01*
G01X1819000Y78400D02*
X1805600D01*
G01Y67000D02*
X1819000D01*
G01X1793983Y17500D02*
Y15708D01*
X1794150Y15333D01*
X1794483Y15083D01*
X1794900Y15000D01*
X1795317Y15083D01*
X1795650Y15333D01*
X1795817Y15708D01*
Y17500D01*
G01X1798000Y15000D02*
Y17500D01*
X1797500Y17000D01*
G01Y15000D02*
X1798500D01*
G01X1800308Y16042D02*
X1800600Y16333D01*
X1800850Y16500D01*
X1801183Y16583D01*
X1801475Y16500D01*
X1801683Y16333D01*
X1801850Y16083D01*
X1801892Y15792D01*
X1801850Y15542D01*
X1801683Y15292D01*
X1801433Y15083D01*
X1801142Y15000D01*
X1800808Y15083D01*
X1800517Y15333D01*
X1800350Y15708D01*
X1800308Y16125D01*
X1800392Y16667D01*
X1800517Y16958D01*
X1800725Y17250D01*
X1801017Y17458D01*
X1801308Y17500D01*
X1801600Y17417D01*
X1801808Y17208D01*
G01X1796931Y35496D02*
Y27496D01*
X1808881D01*
Y35496D01*
X1796931D01*
G01X1808881Y29346D02*
X1806881Y31346D01*
X1808881Y33346D01*
G01X1762647Y131867D02*
X1762522Y131617D01*
X1762439Y131325D01*
Y130992D01*
X1762564Y130617D01*
X1762772Y130325D01*
X1763022Y130117D01*
X1763439Y129950D01*
X1763814Y129908D01*
X1764189Y129992D01*
X1764439Y130117D01*
X1764689Y130367D01*
X1764856Y130658D01*
X1764939Y130950D01*
Y131242D01*
X1764856Y131533D01*
X1764731Y131783D01*
X1764564Y131992D01*
G01X1764939Y134550D02*
X1762439D01*
X1764231Y133008D01*
Y135092D01*
G01X1764939Y137067D02*
X1764397Y137150D01*
X1763939Y137275D01*
X1763522Y137442D01*
X1763064Y137650D01*
X1762439Y137983D01*
Y136317D01*
G01X1764939Y140750D02*
X1762439D01*
X1764231Y139208D01*
Y141292D01*
G01X1760939Y130117D02*
X1758439D01*
Y131158D01*
X1758564Y131492D01*
X1758731Y131700D01*
X1759064Y131783D01*
X1759397Y131700D01*
X1759606Y131450D01*
X1759731Y131158D01*
Y130117D01*
G01Y131158D02*
X1760939Y131783D01*
G01Y134050D02*
X1760897Y134342D01*
X1760772Y134675D01*
X1760564Y134883D01*
X1760272Y134967D01*
X1759981Y134883D01*
X1759731Y134633D01*
X1759606Y134258D01*
Y133842D01*
X1759522Y133592D01*
X1759314Y133383D01*
X1759022Y133300D01*
X1758731Y133425D01*
X1758522Y133717D01*
X1758439Y134050D01*
X1758522Y134383D01*
X1758731Y134675D01*
X1759022Y134800D01*
X1759314Y134717D01*
X1759522Y134508D01*
X1759606Y134258D01*
Y133842D01*
X1759731Y133467D01*
X1759981Y133217D01*
X1760272Y133133D01*
X1760564Y133217D01*
X1760772Y133425D01*
X1760897Y133758D01*
X1760939Y134050D01*
G01X1760564Y136233D02*
X1760772Y136483D01*
X1760897Y136775D01*
X1760939Y137150D01*
X1760856Y137525D01*
X1760689Y137817D01*
X1760397Y138025D01*
X1760064Y138067D01*
X1759731Y137983D01*
X1759522Y137775D01*
X1759356Y137483D01*
X1759314Y137192D01*
X1759356Y136900D01*
X1759522Y136525D01*
X1758439Y136650D01*
Y137775D01*
G01X1758856Y139458D02*
X1758606Y139708D01*
X1758481Y140000D01*
X1758439Y140333D01*
X1758522Y140750D01*
X1758731Y141042D01*
X1758981Y141125D01*
X1759231Y141083D01*
X1759439Y140917D01*
X1759856Y140083D01*
X1760147Y139708D01*
X1760564Y139458D01*
X1760939Y139375D01*
Y141125D01*
G01X1757600Y120900D02*
X1761600D01*
Y128300D01*
G01X1793708Y157767D02*
X1793583Y157517D01*
X1793500Y157225D01*
Y156892D01*
X1793625Y156517D01*
X1793833Y156225D01*
X1794083Y156017D01*
X1794500Y155850D01*
X1794875Y155808D01*
X1795250Y155892D01*
X1795500Y156017D01*
X1795750Y156267D01*
X1795917Y156558D01*
X1796000Y156850D01*
Y157142D01*
X1795917Y157433D01*
X1795792Y157683D01*
X1795625Y157892D01*
G01X1796000Y160450D02*
X1793500D01*
X1795292Y158908D01*
Y160992D01*
G01X1796000Y162967D02*
X1795458Y163050D01*
X1795000Y163175D01*
X1794583Y163342D01*
X1794125Y163550D01*
X1793500Y163883D01*
Y162217D01*
G01X1793917Y165358D02*
X1793667Y165608D01*
X1793542Y165900D01*
X1793500Y166233D01*
X1793583Y166650D01*
X1793792Y166942D01*
X1794042Y167025D01*
X1794292Y166983D01*
X1794500Y166817D01*
X1794917Y165983D01*
X1795208Y165608D01*
X1795625Y165358D01*
X1796000Y165275D01*
Y167025D01*
G01X1793708Y189767D02*
X1793583Y189517D01*
X1793500Y189225D01*
Y188892D01*
X1793625Y188517D01*
X1793833Y188225D01*
X1794083Y188017D01*
X1794500Y187850D01*
X1794875Y187808D01*
X1795250Y187892D01*
X1795500Y188017D01*
X1795750Y188267D01*
X1795917Y188558D01*
X1796000Y188850D01*
Y189142D01*
X1795917Y189433D01*
X1795792Y189683D01*
X1795625Y189892D01*
G01X1796000Y192450D02*
X1793500D01*
X1795292Y190908D01*
Y192992D01*
G01X1796000Y194967D02*
X1795458Y195050D01*
X1795000Y195175D01*
X1794583Y195342D01*
X1794125Y195550D01*
X1793500Y195883D01*
Y194217D01*
G01X1795708Y197442D02*
X1795917Y197733D01*
X1796000Y198067D01*
X1795917Y198400D01*
X1795667Y198692D01*
X1795292Y198900D01*
X1794917Y198983D01*
X1794458D01*
X1794083Y198900D01*
X1793750Y198692D01*
X1793583Y198442D01*
X1793500Y198150D01*
X1793583Y197817D01*
X1793750Y197567D01*
X1794000Y197400D01*
X1794333Y197317D01*
X1794625Y197400D01*
X1794917Y197608D01*
X1795083Y197858D01*
X1795125Y198150D01*
X1795042Y198483D01*
X1794833Y198733D01*
X1794458Y198983D01*
G01X1747300Y163000D02*
Y160500D01*
G01X1746342Y163000D02*
X1748258D01*
G01X1749567Y160500D02*
Y163000D01*
X1750567D01*
X1750900Y162875D01*
X1751150Y162583D01*
X1751233Y162250D01*
X1751150Y161917D01*
X1750942Y161667D01*
X1750567Y161542D01*
X1749567D01*
G01X1753500Y160500D02*
Y163000D01*
X1753000Y162500D01*
G01Y160500D02*
X1754000D01*
G01X1755892Y160792D02*
X1756183Y160583D01*
X1756517Y160500D01*
X1756850Y160583D01*
X1757142Y160833D01*
X1757350Y161208D01*
X1757433Y161583D01*
Y162042D01*
X1757350Y162417D01*
X1757142Y162750D01*
X1756892Y162917D01*
X1756600Y163000D01*
X1756267Y162917D01*
X1756017Y162750D01*
X1755850Y162500D01*
X1755767Y162167D01*
X1755850Y161875D01*
X1756058Y161583D01*
X1756308Y161417D01*
X1756600Y161375D01*
X1756933Y161458D01*
X1757183Y161667D01*
X1757433Y162042D01*
G01X1759700Y160500D02*
Y163000D01*
X1759200Y162500D01*
G01Y160500D02*
X1760200D01*
G01X1796650Y116600D02*
X1796317Y116642D01*
X1796025Y116808D01*
X1795775Y117058D01*
X1795608Y117350D01*
X1795525Y117683D01*
Y118017D01*
X1795608Y118350D01*
X1795775Y118642D01*
X1796025Y118892D01*
X1796317Y119058D01*
X1796650Y119100D01*
X1796983Y119058D01*
X1797275Y118892D01*
X1797525Y118642D01*
X1797692Y118350D01*
X1797775Y118017D01*
Y117683D01*
X1797692Y117350D01*
X1797525Y117058D01*
X1797275Y116808D01*
X1796983Y116642D01*
X1796650Y116600D01*
G01X1796983Y117267D02*
X1797483Y116600D01*
G01X1799750D02*
Y119100D01*
X1799250Y118600D01*
G01Y116600D02*
X1800250D01*
G01X1802767D02*
X1802850Y117142D01*
X1802975Y117600D01*
X1803142Y118017D01*
X1803350Y118475D01*
X1803683Y119100D01*
X1802017D01*
G01X1805867Y116600D02*
X1805950Y117142D01*
X1806075Y117600D01*
X1806242Y118017D01*
X1806450Y118475D01*
X1806783Y119100D01*
X1805117D01*
G01X1814500Y99100D02*
X1812400Y100900D01*
X1814500Y103100D01*
G01X1814600Y106700D02*
X1795400D01*
Y95500D01*
X1814600D01*
Y106700D01*
X1814200D01*
G01X1811300Y132000D02*
X1813400Y130200D01*
X1811300Y128000D01*
G01X1811200Y124400D02*
X1830400D01*
Y135600D01*
X1811200D01*
Y124400D01*
X1811600D01*
G01X1750500Y137517D02*
X1748000D01*
Y138558D01*
X1748125Y138892D01*
X1748292Y139100D01*
X1748625Y139183D01*
X1748958Y139100D01*
X1749167Y138850D01*
X1749292Y138558D01*
Y137517D01*
G01Y138558D02*
X1750500Y139183D01*
G01Y141450D02*
X1750458Y141742D01*
X1750333Y142075D01*
X1750125Y142283D01*
X1749833Y142367D01*
X1749542Y142283D01*
X1749292Y142033D01*
X1749167Y141658D01*
Y141242D01*
X1749083Y140992D01*
X1748875Y140783D01*
X1748583Y140700D01*
X1748292Y140825D01*
X1748083Y141117D01*
X1748000Y141450D01*
X1748083Y141783D01*
X1748292Y142075D01*
X1748583Y142200D01*
X1748875Y142117D01*
X1749083Y141908D01*
X1749167Y141658D01*
Y141242D01*
X1749292Y140867D01*
X1749542Y140617D01*
X1749833Y140533D01*
X1750125Y140617D01*
X1750333Y140825D01*
X1750458Y141158D01*
X1750500Y141450D01*
G01X1750125Y143633D02*
X1750333Y143883D01*
X1750458Y144175D01*
X1750500Y144550D01*
X1750417Y144925D01*
X1750250Y145217D01*
X1749958Y145425D01*
X1749625Y145467D01*
X1749292Y145383D01*
X1749083Y145175D01*
X1748917Y144883D01*
X1748875Y144592D01*
X1748917Y144300D01*
X1749083Y143925D01*
X1748000Y144050D01*
Y145175D01*
G01X1749458Y146858D02*
X1749167Y147150D01*
X1749000Y147400D01*
X1748917Y147733D01*
X1749000Y148025D01*
X1749167Y148233D01*
X1749417Y148400D01*
X1749708Y148442D01*
X1749958Y148400D01*
X1750208Y148233D01*
X1750417Y147983D01*
X1750500Y147692D01*
X1750417Y147358D01*
X1750167Y147067D01*
X1749792Y146900D01*
X1749375Y146858D01*
X1748833Y146942D01*
X1748542Y147067D01*
X1748250Y147275D01*
X1748042Y147567D01*
X1748000Y147858D01*
X1748083Y148150D01*
X1748292Y148358D01*
G01X1797708Y156267D02*
X1797583Y156017D01*
X1797500Y155725D01*
Y155392D01*
X1797625Y155017D01*
X1797833Y154725D01*
X1798083Y154517D01*
X1798500Y154350D01*
X1798875Y154308D01*
X1799250Y154392D01*
X1799500Y154517D01*
X1799750Y154767D01*
X1799917Y155058D01*
X1800000Y155350D01*
Y155642D01*
X1799917Y155933D01*
X1799792Y156183D01*
X1799625Y156392D01*
G01X1800000Y158950D02*
X1797500D01*
X1799292Y157408D01*
Y159492D01*
G01X1800000Y161467D02*
X1799458Y161550D01*
X1799000Y161675D01*
X1798583Y161842D01*
X1798125Y162050D01*
X1797500Y162383D01*
Y160717D01*
G01X1799500Y163733D02*
X1799792Y163983D01*
X1799958Y164317D01*
X1800000Y164692D01*
X1799958Y165025D01*
X1799750Y165358D01*
X1799500Y165567D01*
X1799250Y165608D01*
X1798958Y165525D01*
X1798750Y165233D01*
X1798667Y164942D01*
Y164567D01*
G01Y164942D02*
X1798542Y165192D01*
X1798333Y165400D01*
X1798083Y165483D01*
X1797833Y165400D01*
X1797625Y165192D01*
X1797500Y164817D01*
X1797542Y164442D01*
X1797708Y164067D01*
G01X1801000Y136200D02*
Y141700D01*
G01X1809000Y136200D02*
X1801000D01*
G01X1809000Y141700D02*
Y136200D01*
G01Y153800D02*
Y148300D01*
G01X1801000Y153800D02*
X1809000D01*
G01X1801000Y148300D02*
Y153800D01*
G01X1815800Y97900D02*
X1831900D01*
G01X1794017Y131500D02*
Y134000D01*
X1795058D01*
X1795392Y133875D01*
X1795600Y133708D01*
X1795683Y133375D01*
X1795600Y133042D01*
X1795350Y132833D01*
X1795058Y132708D01*
X1794017D01*
G01X1795058D02*
X1795683Y131500D01*
G01X1797950D02*
X1798242Y131542D01*
X1798575Y131667D01*
X1798783Y131875D01*
X1798867Y132167D01*
X1798783Y132458D01*
X1798533Y132708D01*
X1798158Y132833D01*
X1797742D01*
X1797492Y132917D01*
X1797283Y133125D01*
X1797200Y133417D01*
X1797325Y133708D01*
X1797617Y133917D01*
X1797950Y134000D01*
X1798283Y133917D01*
X1798575Y133708D01*
X1798700Y133417D01*
X1798617Y133125D01*
X1798408Y132917D01*
X1798158Y132833D01*
X1797742D01*
X1797367Y132708D01*
X1797117Y132458D01*
X1797033Y132167D01*
X1797117Y131875D01*
X1797325Y131667D01*
X1797658Y131542D01*
X1797950Y131500D01*
G01X1800133Y131875D02*
X1800383Y131667D01*
X1800675Y131542D01*
X1801050Y131500D01*
X1801425Y131583D01*
X1801717Y131750D01*
X1801925Y132042D01*
X1801967Y132375D01*
X1801883Y132708D01*
X1801675Y132917D01*
X1801383Y133083D01*
X1801092Y133125D01*
X1800800Y133083D01*
X1800425Y132917D01*
X1800550Y134000D01*
X1801675D01*
G01X1804150Y131500D02*
Y134000D01*
X1803650Y133500D01*
G01Y131500D02*
X1804650D01*
G01X1810300Y130000D02*
Y122000D01*
X1792700D01*
Y130000D01*
X1810300D01*
G01X1808017Y165200D02*
Y167700D01*
X1809058D01*
X1809392Y167575D01*
X1809600Y167408D01*
X1809683Y167075D01*
X1809600Y166742D01*
X1809350Y166533D01*
X1809058Y166408D01*
X1808017D01*
G01X1809058D02*
X1809683Y165200D01*
G01X1811950D02*
X1812242Y165242D01*
X1812575Y165367D01*
X1812783Y165575D01*
X1812867Y165867D01*
X1812783Y166158D01*
X1812533Y166408D01*
X1812158Y166533D01*
X1811742D01*
X1811492Y166617D01*
X1811283Y166825D01*
X1811200Y167117D01*
X1811325Y167408D01*
X1811617Y167617D01*
X1811950Y167700D01*
X1812283Y167617D01*
X1812575Y167408D01*
X1812700Y167117D01*
X1812617Y166825D01*
X1812408Y166617D01*
X1812158Y166533D01*
X1811742D01*
X1811367Y166408D01*
X1811117Y166158D01*
X1811033Y165867D01*
X1811117Y165575D01*
X1811325Y165367D01*
X1811658Y165242D01*
X1811950Y165200D01*
G01X1814133Y165575D02*
X1814383Y165367D01*
X1814675Y165242D01*
X1815050Y165200D01*
X1815425Y165283D01*
X1815717Y165450D01*
X1815925Y165742D01*
X1815967Y166075D01*
X1815883Y166408D01*
X1815675Y166617D01*
X1815383Y166783D01*
X1815092Y166825D01*
X1814800Y166783D01*
X1814425Y166617D01*
X1814550Y167700D01*
X1815675D01*
G01X1817233Y165700D02*
X1817483Y165408D01*
X1817817Y165242D01*
X1818192Y165200D01*
X1818525Y165242D01*
X1818858Y165450D01*
X1819067Y165700D01*
X1819108Y165950D01*
X1819025Y166242D01*
X1818733Y166450D01*
X1818442Y166533D01*
X1818067D01*
G01X1818442D02*
X1818692Y166658D01*
X1818900Y166867D01*
X1818983Y167117D01*
X1818900Y167367D01*
X1818692Y167575D01*
X1818317Y167700D01*
X1817942Y167658D01*
X1817567Y167492D01*
G01X1818800Y163700D02*
Y155700D01*
X1801200D01*
Y163700D01*
X1818800D01*
G01X1800547Y189767D02*
X1800422Y189517D01*
X1800339Y189225D01*
Y188892D01*
X1800464Y188517D01*
X1800672Y188225D01*
X1800922Y188017D01*
X1801339Y187850D01*
X1801714Y187808D01*
X1802089Y187892D01*
X1802339Y188017D01*
X1802589Y188267D01*
X1802756Y188558D01*
X1802839Y188850D01*
Y189142D01*
X1802756Y189433D01*
X1802631Y189683D01*
X1802464Y189892D01*
G01X1802839Y192450D02*
X1800339D01*
X1802131Y190908D01*
Y192992D01*
G01X1802839Y194967D02*
X1802297Y195050D01*
X1801839Y195175D01*
X1801422Y195342D01*
X1800964Y195550D01*
X1800339Y195883D01*
Y194217D01*
G01X1802839Y198067D02*
X1802297Y198150D01*
X1801839Y198275D01*
X1801422Y198442D01*
X1800964Y198650D01*
X1800339Y198983D01*
Y197317D01*
G01X1808547Y189767D02*
X1808422Y189517D01*
X1808339Y189225D01*
Y188892D01*
X1808464Y188517D01*
X1808672Y188225D01*
X1808922Y188017D01*
X1809339Y187850D01*
X1809714Y187808D01*
X1810089Y187892D01*
X1810339Y188017D01*
X1810589Y188267D01*
X1810756Y188558D01*
X1810839Y188850D01*
Y189142D01*
X1810756Y189433D01*
X1810631Y189683D01*
X1810464Y189892D01*
G01X1810839Y192450D02*
X1808339D01*
X1810131Y190908D01*
Y192992D01*
G01X1810839Y194967D02*
X1810297Y195050D01*
X1809839Y195175D01*
X1809422Y195342D01*
X1808964Y195550D01*
X1808339Y195883D01*
Y194217D01*
G01X1810839Y198150D02*
X1810797Y198442D01*
X1810672Y198775D01*
X1810464Y198983D01*
X1810172Y199067D01*
X1809881Y198983D01*
X1809631Y198733D01*
X1809506Y198358D01*
Y197942D01*
X1809422Y197692D01*
X1809214Y197483D01*
X1808922Y197400D01*
X1808631Y197525D01*
X1808422Y197817D01*
X1808339Y198150D01*
X1808422Y198483D01*
X1808631Y198775D01*
X1808922Y198900D01*
X1809214Y198817D01*
X1809422Y198608D01*
X1809506Y198358D01*
Y197942D01*
X1809631Y197567D01*
X1809881Y197317D01*
X1810172Y197233D01*
X1810464Y197317D01*
X1810672Y197525D01*
X1810797Y197858D01*
X1810839Y198150D01*
G01X1768275Y209500D02*
Y212000D01*
G01X1770025D02*
Y209500D01*
G01Y210750D02*
X1768275D01*
G01X1771333Y209500D02*
Y212000D01*
X1772167D01*
X1772500Y211875D01*
X1772750Y211708D01*
X1772958Y211458D01*
X1773125Y211167D01*
X1773167Y210750D01*
X1773125Y210333D01*
X1772958Y210042D01*
X1772750Y209792D01*
X1772500Y209625D01*
X1772167Y209500D01*
X1771333D01*
G01X1774433D02*
Y212000D01*
X1775267D01*
X1775600Y211875D01*
X1775850Y211708D01*
X1776058Y211458D01*
X1776225Y211167D01*
X1776267Y210750D01*
X1776225Y210333D01*
X1776058Y210042D01*
X1775850Y209792D01*
X1775600Y209625D01*
X1775267Y209500D01*
X1774433D01*
G01X1777575Y209833D02*
X1777908Y209625D01*
X1778283Y209500D01*
X1778617D01*
X1778950Y209625D01*
X1779200Y209833D01*
X1779325Y210125D01*
X1779242Y210417D01*
X1779033Y210667D01*
X1778658Y210833D01*
X1778158Y210917D01*
X1777867Y211083D01*
X1777742Y211375D01*
X1777825Y211667D01*
X1778033Y211875D01*
X1778325Y212000D01*
X1778617D01*
X1778908Y211917D01*
X1779158Y211708D01*
G01X1780508Y209500D02*
X1781550Y212000D01*
X1782592Y209500D01*
G01X1782217Y210375D02*
X1780883D01*
G01X1783775Y209833D02*
X1784108Y209625D01*
X1784483Y209500D01*
X1784817D01*
X1785150Y209625D01*
X1785400Y209833D01*
X1785525Y210125D01*
X1785442Y210417D01*
X1785233Y210667D01*
X1784858Y210833D01*
X1784358Y210917D01*
X1784067Y211083D01*
X1783942Y211375D01*
X1784025Y211667D01*
X1784233Y211875D01*
X1784525Y212000D01*
X1784817D01*
X1785108Y211917D01*
X1785358Y211708D01*
G01X1786833Y210000D02*
X1787083Y209708D01*
X1787417Y209542D01*
X1787792Y209500D01*
X1788125Y209542D01*
X1788458Y209750D01*
X1788667Y210000D01*
X1788708Y210250D01*
X1788625Y210542D01*
X1788333Y210750D01*
X1788042Y210833D01*
X1787667D01*
G01X1788042D02*
X1788292Y210958D01*
X1788500Y211167D01*
X1788583Y211417D01*
X1788500Y211667D01*
X1788292Y211875D01*
X1787917Y212000D01*
X1787542Y211958D01*
X1787167Y211792D01*
G01X1791350Y209500D02*
Y212000D01*
X1789808Y210208D01*
X1791892D01*
G01X1731967Y269000D02*
Y266500D01*
X1733633D01*
G01X1736733D02*
X1735067D01*
Y269000D01*
X1736733D01*
G01X1736067Y267792D02*
X1735067D01*
G01X1738083Y266500D02*
Y269000D01*
X1738917D01*
X1739250Y268875D01*
X1739500Y268708D01*
X1739708Y268458D01*
X1739875Y268167D01*
X1739917Y267750D01*
X1739875Y267333D01*
X1739708Y267042D01*
X1739500Y266792D01*
X1739250Y266625D01*
X1738917Y266500D01*
X1738083D01*
G01X1741308Y268583D02*
X1741558Y268833D01*
X1741850Y268958D01*
X1742183Y269000D01*
X1742600Y268917D01*
X1742892Y268708D01*
X1742975Y268458D01*
X1742933Y268208D01*
X1742767Y268000D01*
X1741933Y267583D01*
X1741558Y267292D01*
X1741308Y266875D01*
X1741225Y266500D01*
X1742975D01*
G01X1744283Y267000D02*
X1744533Y266708D01*
X1744867Y266542D01*
X1745242Y266500D01*
X1745575Y266542D01*
X1745908Y266750D01*
X1746117Y267000D01*
X1746158Y267250D01*
X1746075Y267542D01*
X1745783Y267750D01*
X1745492Y267833D01*
X1745117D01*
G01X1745492D02*
X1745742Y267958D01*
X1745950Y268167D01*
X1746033Y268417D01*
X1745950Y268667D01*
X1745742Y268875D01*
X1745367Y269000D01*
X1744992Y268958D01*
X1744617Y268792D01*
G01X1733198Y251880D02*
Y263080D01*
X1741998D01*
Y251880D01*
X1733198D01*
G01X1761643Y560075D02*
X1766693D01*
Y658775D01*
X1791343D01*
Y474375D01*
X1766693D01*
Y533075D01*
X1761643D01*
Y560075D01*
G01X1757819Y444697D02*
X1757569Y444822D01*
X1757277Y444905D01*
X1756944D01*
X1756569Y444780D01*
X1756277Y444572D01*
X1756069Y444322D01*
X1755902Y443905D01*
X1755860Y443530D01*
X1755944Y443155D01*
X1756069Y442905D01*
X1756319Y442655D01*
X1756610Y442488D01*
X1756902Y442405D01*
X1757194D01*
X1757485Y442488D01*
X1757735Y442613D01*
X1757944Y442780D01*
G01X1759210Y443447D02*
X1759502Y443738D01*
X1759752Y443905D01*
X1760085Y443988D01*
X1760377Y443905D01*
X1760585Y443738D01*
X1760752Y443488D01*
X1760794Y443197D01*
X1760752Y442947D01*
X1760585Y442697D01*
X1760335Y442488D01*
X1760044Y442405D01*
X1759710Y442488D01*
X1759419Y442738D01*
X1759252Y443113D01*
X1759210Y443530D01*
X1759294Y444072D01*
X1759419Y444363D01*
X1759627Y444655D01*
X1759919Y444863D01*
X1760210Y444905D01*
X1760502Y444822D01*
X1760710Y444613D01*
G01X1763019Y442405D02*
X1763102Y442947D01*
X1763227Y443405D01*
X1763394Y443822D01*
X1763602Y444280D01*
X1763935Y444905D01*
X1762269D01*
G01X1765494Y442697D02*
X1765785Y442488D01*
X1766119Y442405D01*
X1766452Y442488D01*
X1766744Y442738D01*
X1766952Y443113D01*
X1767035Y443488D01*
Y443947D01*
X1766952Y444322D01*
X1766744Y444655D01*
X1766494Y444822D01*
X1766202Y444905D01*
X1765869Y444822D01*
X1765619Y444655D01*
X1765452Y444405D01*
X1765369Y444072D01*
X1765452Y443780D01*
X1765660Y443488D01*
X1765910Y443322D01*
X1766202Y443280D01*
X1766535Y443363D01*
X1766785Y443572D01*
X1767035Y443947D01*
G01X1757791Y439670D02*
X1757541Y439795D01*
X1757249Y439878D01*
X1756916D01*
X1756541Y439753D01*
X1756249Y439545D01*
X1756041Y439295D01*
X1755874Y438878D01*
X1755832Y438503D01*
X1755916Y438128D01*
X1756041Y437878D01*
X1756291Y437628D01*
X1756582Y437461D01*
X1756874Y437378D01*
X1757166D01*
X1757457Y437461D01*
X1757707Y437586D01*
X1757916Y437753D01*
G01X1759182Y438420D02*
X1759474Y438711D01*
X1759724Y438878D01*
X1760057Y438961D01*
X1760349Y438878D01*
X1760557Y438711D01*
X1760724Y438461D01*
X1760766Y438170D01*
X1760724Y437920D01*
X1760557Y437670D01*
X1760307Y437461D01*
X1760016Y437378D01*
X1759682Y437461D01*
X1759391Y437711D01*
X1759224Y438086D01*
X1759182Y438503D01*
X1759266Y439045D01*
X1759391Y439336D01*
X1759599Y439628D01*
X1759891Y439836D01*
X1760182Y439878D01*
X1760474Y439795D01*
X1760682Y439586D01*
G01X1763074Y437378D02*
X1763366Y437420D01*
X1763699Y437545D01*
X1763907Y437753D01*
X1763991Y438045D01*
X1763907Y438336D01*
X1763657Y438586D01*
X1763282Y438711D01*
X1762866D01*
X1762616Y438795D01*
X1762407Y439003D01*
X1762324Y439295D01*
X1762449Y439586D01*
X1762741Y439795D01*
X1763074Y439878D01*
X1763407Y439795D01*
X1763699Y439586D01*
X1763824Y439295D01*
X1763741Y439003D01*
X1763532Y438795D01*
X1763282Y438711D01*
X1762866D01*
X1762491Y438586D01*
X1762241Y438336D01*
X1762157Y438045D01*
X1762241Y437753D01*
X1762449Y437545D01*
X1762782Y437420D01*
X1763074Y437378D01*
G01X1765382Y439461D02*
X1765632Y439711D01*
X1765924Y439836D01*
X1766257Y439878D01*
X1766674Y439795D01*
X1766966Y439586D01*
X1767049Y439336D01*
X1767007Y439086D01*
X1766841Y438878D01*
X1766007Y438461D01*
X1765632Y438170D01*
X1765382Y437753D01*
X1765299Y437378D01*
X1767049D01*
G01X1740559Y471707D02*
Y475707D01*
X1733159D01*
G01X1761467Y464500D02*
Y467000D01*
X1762508D01*
X1762842Y466875D01*
X1763050Y466708D01*
X1763133Y466375D01*
X1763050Y466042D01*
X1762800Y465833D01*
X1762508Y465708D01*
X1761467D01*
G01X1762508D02*
X1763133Y464500D01*
G01X1765400D02*
Y467000D01*
X1764900Y466500D01*
G01Y464500D02*
X1765900D01*
G01X1768500D02*
Y467000D01*
X1768000Y466500D01*
G01Y464500D02*
X1769000D01*
G01X1770683Y464875D02*
X1770933Y464667D01*
X1771225Y464542D01*
X1771600Y464500D01*
X1771975Y464583D01*
X1772267Y464750D01*
X1772475Y465042D01*
X1772517Y465375D01*
X1772433Y465708D01*
X1772225Y465917D01*
X1771933Y466083D01*
X1771642Y466125D01*
X1771350Y466083D01*
X1770975Y465917D01*
X1771100Y467000D01*
X1772225D01*
G01X1773992Y464792D02*
X1774283Y464583D01*
X1774617Y464500D01*
X1774950Y464583D01*
X1775242Y464833D01*
X1775450Y465208D01*
X1775533Y465583D01*
Y466042D01*
X1775450Y466417D01*
X1775242Y466750D01*
X1774992Y466917D01*
X1774700Y467000D01*
X1774367Y466917D01*
X1774117Y466750D01*
X1773950Y466500D01*
X1773867Y466167D01*
X1773950Y465875D01*
X1774158Y465583D01*
X1774408Y465417D01*
X1774700Y465375D01*
X1775033Y465458D01*
X1775283Y465667D01*
X1775533Y466042D01*
G01X1752318Y467232D02*
Y471232D01*
X1744918D01*
G01X1739651Y462705D02*
Y466705D01*
X1732251D01*
G01X1732193Y464983D02*
Y468983D01*
X1724793D01*
G01X1724791Y473049D02*
Y469049D01*
X1732191D01*
G01X1787517Y382500D02*
Y385000D01*
X1788558D01*
X1788892Y384875D01*
X1789100Y384708D01*
X1789183Y384375D01*
X1789100Y384042D01*
X1788850Y383833D01*
X1788558Y383708D01*
X1787517D01*
G01X1788558D02*
X1789183Y382500D01*
G01X1791950D02*
Y385000D01*
X1790408Y383208D01*
X1792492D01*
G01X1794550Y382500D02*
X1794842Y382542D01*
X1795175Y382667D01*
X1795383Y382875D01*
X1795467Y383167D01*
X1795383Y383458D01*
X1795133Y383708D01*
X1794758Y383833D01*
X1794342D01*
X1794092Y383917D01*
X1793883Y384125D01*
X1793800Y384417D01*
X1793925Y384708D01*
X1794217Y384917D01*
X1794550Y385000D01*
X1794883Y384917D01*
X1795175Y384708D01*
X1795300Y384417D01*
X1795217Y384125D01*
X1795008Y383917D01*
X1794758Y383833D01*
X1794342D01*
X1793967Y383708D01*
X1793717Y383458D01*
X1793633Y383167D01*
X1793717Y382875D01*
X1793925Y382667D01*
X1794258Y382542D01*
X1794550Y382500D01*
G01X1796942Y382792D02*
X1797233Y382583D01*
X1797567Y382500D01*
X1797900Y382583D01*
X1798192Y382833D01*
X1798400Y383208D01*
X1798483Y383583D01*
Y384042D01*
X1798400Y384417D01*
X1798192Y384750D01*
X1797942Y384917D01*
X1797650Y385000D01*
X1797317Y384917D01*
X1797067Y384750D01*
X1796900Y384500D01*
X1796817Y384167D01*
X1796900Y383875D01*
X1797108Y383583D01*
X1797358Y383417D01*
X1797650Y383375D01*
X1797983Y383458D01*
X1798233Y383667D01*
X1798483Y384042D01*
G01X1807092Y381782D02*
Y385782D01*
X1799692D01*
G01X1813517Y406500D02*
Y409000D01*
X1814558D01*
X1814892Y408875D01*
X1815100Y408708D01*
X1815183Y408375D01*
X1815100Y408042D01*
X1814850Y407833D01*
X1814558Y407708D01*
X1813517D01*
G01X1814558D02*
X1815183Y406500D01*
G01X1817950D02*
Y409000D01*
X1816408Y407208D01*
X1818492D01*
G01X1820550Y406500D02*
X1820842Y406542D01*
X1821175Y406667D01*
X1821383Y406875D01*
X1821467Y407167D01*
X1821383Y407458D01*
X1821133Y407708D01*
X1820758Y407833D01*
X1820342D01*
X1820092Y407917D01*
X1819883Y408125D01*
X1819800Y408417D01*
X1819925Y408708D01*
X1820217Y408917D01*
X1820550Y409000D01*
X1820883Y408917D01*
X1821175Y408708D01*
X1821300Y408417D01*
X1821217Y408125D01*
X1821008Y407917D01*
X1820758Y407833D01*
X1820342D01*
X1819967Y407708D01*
X1819717Y407458D01*
X1819633Y407167D01*
X1819717Y406875D01*
X1819925Y406667D01*
X1820258Y406542D01*
X1820550Y406500D01*
G01X1823567D02*
X1823650Y407042D01*
X1823775Y407500D01*
X1823942Y407917D01*
X1824150Y408375D01*
X1824483Y409000D01*
X1822817D01*
G01X1821825Y401559D02*
Y405559D01*
X1814425D01*
G01X1747309Y407740D02*
Y410240D01*
X1748350D01*
X1748684Y410115D01*
X1748892Y409948D01*
X1748975Y409615D01*
X1748892Y409282D01*
X1748642Y409073D01*
X1748350Y408948D01*
X1747309D01*
G01X1748350D02*
X1748975Y407740D01*
G01X1751742D02*
Y410240D01*
X1750200Y408448D01*
X1752284D01*
G01X1754342Y407740D02*
X1754634Y407782D01*
X1754967Y407907D01*
X1755175Y408115D01*
X1755259Y408407D01*
X1755175Y408698D01*
X1754925Y408948D01*
X1754550Y409073D01*
X1754134D01*
X1753884Y409157D01*
X1753675Y409365D01*
X1753592Y409657D01*
X1753717Y409948D01*
X1754009Y410157D01*
X1754342Y410240D01*
X1754675Y410157D01*
X1754967Y409948D01*
X1755092Y409657D01*
X1755009Y409365D01*
X1754800Y409157D01*
X1754550Y409073D01*
X1754134D01*
X1753759Y408948D01*
X1753509Y408698D01*
X1753425Y408407D01*
X1753509Y408115D01*
X1753717Y407907D01*
X1754050Y407782D01*
X1754342Y407740D01*
G01X1756650Y408782D02*
X1756942Y409073D01*
X1757192Y409240D01*
X1757525Y409323D01*
X1757817Y409240D01*
X1758025Y409073D01*
X1758192Y408823D01*
X1758234Y408532D01*
X1758192Y408282D01*
X1758025Y408032D01*
X1757775Y407823D01*
X1757484Y407740D01*
X1757150Y407823D01*
X1756859Y408073D01*
X1756692Y408448D01*
X1756650Y408865D01*
X1756734Y409407D01*
X1756859Y409698D01*
X1757067Y409990D01*
X1757359Y410198D01*
X1757650Y410240D01*
X1757942Y410157D01*
X1758150Y409948D01*
G01X1755392Y400630D02*
Y404630D01*
X1747992D01*
G01X1766643Y405696D02*
Y408196D01*
X1767684D01*
X1768018Y408071D01*
X1768226Y407904D01*
X1768309Y407571D01*
X1768226Y407238D01*
X1767976Y407029D01*
X1767684Y406904D01*
X1766643D01*
G01X1767684D02*
X1768309Y405696D01*
G01X1771076D02*
Y408196D01*
X1769534Y406404D01*
X1771618D01*
G01X1773676Y405696D02*
X1773968Y405738D01*
X1774301Y405863D01*
X1774509Y406071D01*
X1774593Y406363D01*
X1774509Y406654D01*
X1774259Y406904D01*
X1773884Y407029D01*
X1773468D01*
X1773218Y407113D01*
X1773009Y407321D01*
X1772926Y407613D01*
X1773051Y407904D01*
X1773343Y408113D01*
X1773676Y408196D01*
X1774009Y408113D01*
X1774301Y407904D01*
X1774426Y407613D01*
X1774343Y407321D01*
X1774134Y407113D01*
X1773884Y407029D01*
X1773468D01*
X1773093Y406904D01*
X1772843Y406654D01*
X1772759Y406363D01*
X1772843Y406071D01*
X1773051Y405863D01*
X1773384Y405738D01*
X1773676Y405696D01*
G01X1775984Y407779D02*
X1776234Y408029D01*
X1776526Y408154D01*
X1776859Y408196D01*
X1777276Y408113D01*
X1777568Y407904D01*
X1777651Y407654D01*
X1777609Y407404D01*
X1777443Y407196D01*
X1776609Y406779D01*
X1776234Y406488D01*
X1775984Y406071D01*
X1775901Y405696D01*
X1777651D01*
G01X1769601Y400301D02*
Y404301D01*
X1762201D01*
G01X1761796Y471482D02*
Y468982D01*
G01X1760838Y471482D02*
X1762754D01*
G01X1764063Y468982D02*
Y471482D01*
X1765063D01*
X1765396Y471357D01*
X1765646Y471065D01*
X1765729Y470732D01*
X1765646Y470399D01*
X1765438Y470149D01*
X1765063Y470024D01*
X1764063D01*
G01X1767204Y471065D02*
X1767454Y471315D01*
X1767746Y471440D01*
X1768079Y471482D01*
X1768496Y471399D01*
X1768788Y471190D01*
X1768871Y470940D01*
X1768829Y470690D01*
X1768663Y470482D01*
X1767829Y470065D01*
X1767454Y469774D01*
X1767204Y469357D01*
X1767121Y468982D01*
X1768871D01*
G01X1771096Y471482D02*
X1770763Y471399D01*
X1770513Y471190D01*
X1770346Y470940D01*
X1770221Y470607D01*
X1770179Y470232D01*
X1770221Y469857D01*
X1770346Y469524D01*
X1770513Y469274D01*
X1770763Y469065D01*
X1771096Y468982D01*
X1771429Y469065D01*
X1771679Y469274D01*
X1771846Y469524D01*
X1771971Y469857D01*
X1772013Y470232D01*
X1771971Y470607D01*
X1771846Y470940D01*
X1771679Y471190D01*
X1771429Y471399D01*
X1771096Y471482D01*
G01X1773279Y469357D02*
X1773529Y469149D01*
X1773821Y469024D01*
X1774196Y468982D01*
X1774571Y469065D01*
X1774863Y469232D01*
X1775071Y469524D01*
X1775113Y469857D01*
X1775029Y470190D01*
X1774821Y470399D01*
X1774529Y470565D01*
X1774238Y470607D01*
X1773946Y470565D01*
X1773571Y470399D01*
X1773696Y471482D01*
X1774821D01*
G01X1741996Y439449D02*
X1739496D01*
Y440490D01*
X1739621Y440824D01*
X1739788Y441032D01*
X1740121Y441115D01*
X1740454Y441032D01*
X1740663Y440782D01*
X1740788Y440490D01*
Y439449D01*
G01Y440490D02*
X1741996Y441115D01*
G01Y443382D02*
X1739496D01*
X1739996Y442882D01*
G01X1741996D02*
Y443882D01*
G01Y446482D02*
X1739496D01*
X1739996Y445982D01*
G01X1741996D02*
Y446982D01*
G01X1741621Y448665D02*
X1741829Y448915D01*
X1741954Y449207D01*
X1741996Y449582D01*
X1741913Y449957D01*
X1741746Y450249D01*
X1741454Y450457D01*
X1741121Y450499D01*
X1740788Y450415D01*
X1740579Y450207D01*
X1740413Y449915D01*
X1740371Y449624D01*
X1740413Y449332D01*
X1740579Y448957D01*
X1739496Y449082D01*
Y450207D01*
G01X1741996Y452682D02*
X1741954Y452974D01*
X1741829Y453307D01*
X1741621Y453515D01*
X1741329Y453599D01*
X1741038Y453515D01*
X1740788Y453265D01*
X1740663Y452890D01*
Y452474D01*
X1740579Y452224D01*
X1740371Y452015D01*
X1740079Y451932D01*
X1739788Y452057D01*
X1739579Y452349D01*
X1739496Y452682D01*
X1739579Y453015D01*
X1739788Y453307D01*
X1740079Y453432D01*
X1740371Y453349D01*
X1740579Y453140D01*
X1740663Y452890D01*
Y452474D01*
X1740788Y452099D01*
X1741038Y451849D01*
X1741329Y451765D01*
X1741621Y451849D01*
X1741829Y452057D01*
X1741954Y452390D01*
X1741996Y452682D01*
G01X1736663Y399399D02*
X1734163D01*
Y400440D01*
X1734288Y400774D01*
X1734455Y400982D01*
X1734788Y401065D01*
X1735121Y400982D01*
X1735330Y400732D01*
X1735455Y400440D01*
Y399399D01*
G01Y400440D02*
X1736663Y401065D01*
G01Y403832D02*
X1734163D01*
X1735955Y402290D01*
Y404374D01*
G01X1736288Y405515D02*
X1736496Y405765D01*
X1736621Y406057D01*
X1736663Y406432D01*
X1736580Y406807D01*
X1736413Y407099D01*
X1736121Y407307D01*
X1735788Y407349D01*
X1735455Y407265D01*
X1735246Y407057D01*
X1735080Y406765D01*
X1735038Y406474D01*
X1735080Y406182D01*
X1735246Y405807D01*
X1734163Y405932D01*
Y407057D01*
G01X1735621Y408740D02*
X1735330Y409032D01*
X1735163Y409282D01*
X1735080Y409615D01*
X1735163Y409907D01*
X1735330Y410115D01*
X1735580Y410282D01*
X1735871Y410324D01*
X1736121Y410282D01*
X1736371Y410115D01*
X1736580Y409865D01*
X1736663Y409574D01*
X1736580Y409240D01*
X1736330Y408949D01*
X1735955Y408782D01*
X1735538Y408740D01*
X1734996Y408824D01*
X1734705Y408949D01*
X1734413Y409157D01*
X1734205Y409449D01*
X1734163Y409740D01*
X1734246Y410032D01*
X1734455Y410240D01*
G01X1741098Y399599D02*
X1738598D01*
Y400640D01*
X1738723Y400974D01*
X1738890Y401182D01*
X1739223Y401265D01*
X1739556Y401182D01*
X1739765Y400932D01*
X1739890Y400640D01*
Y399599D01*
G01Y400640D02*
X1741098Y401265D01*
G01Y404032D02*
X1738598D01*
X1740390Y402490D01*
Y404574D01*
G01X1740723Y405715D02*
X1740931Y405965D01*
X1741056Y406257D01*
X1741098Y406632D01*
X1741015Y407007D01*
X1740848Y407299D01*
X1740556Y407507D01*
X1740223Y407549D01*
X1739890Y407465D01*
X1739681Y407257D01*
X1739515Y406965D01*
X1739473Y406674D01*
X1739515Y406382D01*
X1739681Y406007D01*
X1738598Y406132D01*
Y407257D01*
G01X1741098Y409649D02*
X1740556Y409732D01*
X1740098Y409857D01*
X1739681Y410024D01*
X1739223Y410232D01*
X1738598Y410565D01*
Y408899D01*
G01X1760822Y381803D02*
X1760489Y381845D01*
X1760197Y382011D01*
X1759947Y382261D01*
X1759780Y382553D01*
X1759697Y382886D01*
Y383220D01*
X1759780Y383553D01*
X1759947Y383845D01*
X1760197Y384095D01*
X1760489Y384261D01*
X1760822Y384303D01*
X1761155Y384261D01*
X1761447Y384095D01*
X1761697Y383845D01*
X1761864Y383553D01*
X1761947Y383220D01*
Y382886D01*
X1761864Y382553D01*
X1761697Y382261D01*
X1761447Y382011D01*
X1761155Y381845D01*
X1760822Y381803D01*
G01X1761155Y382470D02*
X1761655Y381803D01*
G01X1763130Y383886D02*
X1763380Y384136D01*
X1763672Y384261D01*
X1764005Y384303D01*
X1764422Y384220D01*
X1764714Y384011D01*
X1764797Y383761D01*
X1764755Y383511D01*
X1764589Y383303D01*
X1763755Y382886D01*
X1763380Y382595D01*
X1763130Y382178D01*
X1763047Y381803D01*
X1764797D01*
G01X1767522D02*
Y384303D01*
X1765980Y382511D01*
X1768064D01*
G01X1770122Y381803D02*
Y384303D01*
X1769622Y383803D01*
G01Y381803D02*
X1770622D01*
G01X1770291Y385547D02*
Y399547D01*
G01X1757291Y385547D02*
X1770291D01*
G01X1757291Y399547D02*
Y385547D01*
G01X1770291Y399547D02*
X1757291D01*
G01X1813850Y382000D02*
X1813517Y382042D01*
X1813225Y382208D01*
X1812975Y382458D01*
X1812808Y382750D01*
X1812725Y383083D01*
Y383417D01*
X1812808Y383750D01*
X1812975Y384042D01*
X1813225Y384292D01*
X1813517Y384458D01*
X1813850Y384500D01*
X1814183Y384458D01*
X1814475Y384292D01*
X1814725Y384042D01*
X1814892Y383750D01*
X1814975Y383417D01*
Y383083D01*
X1814892Y382750D01*
X1814725Y382458D01*
X1814475Y382208D01*
X1814183Y382042D01*
X1813850Y382000D01*
G01X1814183Y382667D02*
X1814683Y382000D01*
G01X1816158Y384083D02*
X1816408Y384333D01*
X1816700Y384458D01*
X1817033Y384500D01*
X1817450Y384417D01*
X1817742Y384208D01*
X1817825Y383958D01*
X1817783Y383708D01*
X1817617Y383500D01*
X1816783Y383083D01*
X1816408Y382792D01*
X1816158Y382375D01*
X1816075Y382000D01*
X1817825D01*
G01X1820550D02*
Y384500D01*
X1819008Y382708D01*
X1821092D01*
G01X1822358Y384083D02*
X1822608Y384333D01*
X1822900Y384458D01*
X1823233Y384500D01*
X1823650Y384417D01*
X1823942Y384208D01*
X1824025Y383958D01*
X1823983Y383708D01*
X1823817Y383500D01*
X1822983Y383083D01*
X1822608Y382792D01*
X1822358Y382375D01*
X1822275Y382000D01*
X1824025D01*
G01X1809500Y386100D02*
X1822500D01*
G01X1809500Y400100D02*
Y386100D01*
G01X1822500Y400100D02*
X1809500D01*
G01X1799850Y403000D02*
X1799517Y403042D01*
X1799225Y403208D01*
X1798975Y403458D01*
X1798808Y403750D01*
X1798725Y404083D01*
Y404417D01*
X1798808Y404750D01*
X1798975Y405042D01*
X1799225Y405292D01*
X1799517Y405458D01*
X1799850Y405500D01*
X1800183Y405458D01*
X1800475Y405292D01*
X1800725Y405042D01*
X1800892Y404750D01*
X1800975Y404417D01*
Y404083D01*
X1800892Y403750D01*
X1800725Y403458D01*
X1800475Y403208D01*
X1800183Y403042D01*
X1799850Y403000D01*
G01X1800183Y403667D02*
X1800683Y403000D01*
G01X1802158Y405083D02*
X1802408Y405333D01*
X1802700Y405458D01*
X1803033Y405500D01*
X1803450Y405417D01*
X1803742Y405208D01*
X1803825Y404958D01*
X1803783Y404708D01*
X1803617Y404500D01*
X1802783Y404083D01*
X1802408Y403792D01*
X1802158Y403375D01*
X1802075Y403000D01*
X1803825D01*
G01X1805258Y404042D02*
X1805550Y404333D01*
X1805800Y404500D01*
X1806133Y404583D01*
X1806425Y404500D01*
X1806633Y404333D01*
X1806800Y404083D01*
X1806842Y403792D01*
X1806800Y403542D01*
X1806633Y403292D01*
X1806383Y403083D01*
X1806092Y403000D01*
X1805758Y403083D01*
X1805467Y403333D01*
X1805300Y403708D01*
X1805258Y404125D01*
X1805342Y404667D01*
X1805467Y404958D01*
X1805675Y405250D01*
X1805967Y405458D01*
X1806258Y405500D01*
X1806550Y405417D01*
X1806758Y405208D01*
G01X1809650Y403000D02*
Y405500D01*
X1808108Y403708D01*
X1810192D01*
G01X1794392Y387007D02*
X1808392D01*
G01X1794392Y400007D02*
Y387007D01*
G01X1808392Y400007D02*
X1794392D01*
G01X1808392Y387007D02*
Y400007D01*
G01X1745460Y381240D02*
X1745127Y381282D01*
X1744835Y381448D01*
X1744585Y381698D01*
X1744418Y381990D01*
X1744335Y382323D01*
Y382657D01*
X1744418Y382990D01*
X1744585Y383282D01*
X1744835Y383532D01*
X1745127Y383698D01*
X1745460Y383740D01*
X1745793Y383698D01*
X1746085Y383532D01*
X1746335Y383282D01*
X1746502Y382990D01*
X1746585Y382657D01*
Y382323D01*
X1746502Y381990D01*
X1746335Y381698D01*
X1746085Y381448D01*
X1745793Y381282D01*
X1745460Y381240D01*
G01X1745793Y381907D02*
X1746293Y381240D01*
G01X1747768Y383323D02*
X1748018Y383573D01*
X1748310Y383698D01*
X1748643Y383740D01*
X1749060Y383657D01*
X1749352Y383448D01*
X1749435Y383198D01*
X1749393Y382948D01*
X1749227Y382740D01*
X1748393Y382323D01*
X1748018Y382032D01*
X1747768Y381615D01*
X1747685Y381240D01*
X1749435D01*
G01X1750868Y382282D02*
X1751160Y382573D01*
X1751410Y382740D01*
X1751743Y382823D01*
X1752035Y382740D01*
X1752243Y382573D01*
X1752410Y382323D01*
X1752452Y382032D01*
X1752410Y381782D01*
X1752243Y381532D01*
X1751993Y381323D01*
X1751702Y381240D01*
X1751368Y381323D01*
X1751077Y381573D01*
X1750910Y381948D01*
X1750868Y382365D01*
X1750952Y382907D01*
X1751077Y383198D01*
X1751285Y383490D01*
X1751577Y383698D01*
X1751868Y383740D01*
X1752160Y383657D01*
X1752368Y383448D01*
G01X1753843Y381740D02*
X1754093Y381448D01*
X1754427Y381282D01*
X1754802Y381240D01*
X1755135Y381282D01*
X1755468Y381490D01*
X1755677Y381740D01*
X1755718Y381990D01*
X1755635Y382282D01*
X1755343Y382490D01*
X1755052Y382573D01*
X1754677D01*
G01X1755052D02*
X1755302Y382698D01*
X1755510Y382907D01*
X1755593Y383157D01*
X1755510Y383407D01*
X1755302Y383615D01*
X1754927Y383740D01*
X1754552Y383698D01*
X1754177Y383532D01*
G01X1756134Y385543D02*
Y399543D01*
G01X1743134Y385543D02*
X1756134D01*
G01X1743134Y399543D02*
Y385543D01*
G01X1756134Y399543D02*
X1743134D01*
G01X1725513Y430182D02*
Y432682D01*
X1726554D01*
X1726888Y432557D01*
X1727096Y432390D01*
X1727179Y432057D01*
X1727096Y431724D01*
X1726846Y431515D01*
X1726554Y431390D01*
X1725513D01*
G01X1726554D02*
X1727179Y430182D01*
G01X1729446D02*
Y432682D01*
X1728946Y432182D01*
G01Y430182D02*
X1729946D01*
G01X1732546D02*
Y432682D01*
X1732046Y432182D01*
G01Y430182D02*
X1733046D01*
G01X1734854Y431224D02*
X1735146Y431515D01*
X1735396Y431682D01*
X1735729Y431765D01*
X1736021Y431682D01*
X1736229Y431515D01*
X1736396Y431265D01*
X1736438Y430974D01*
X1736396Y430724D01*
X1736229Y430474D01*
X1735979Y430265D01*
X1735688Y430182D01*
X1735354Y430265D01*
X1735063Y430515D01*
X1734896Y430890D01*
X1734854Y431307D01*
X1734938Y431849D01*
X1735063Y432140D01*
X1735271Y432432D01*
X1735563Y432640D01*
X1735854Y432682D01*
X1736146Y432599D01*
X1736354Y432390D01*
G01X1737954Y432265D02*
X1738204Y432515D01*
X1738496Y432640D01*
X1738829Y432682D01*
X1739246Y432599D01*
X1739538Y432390D01*
X1739621Y432140D01*
X1739579Y431890D01*
X1739413Y431682D01*
X1738579Y431265D01*
X1738204Y430974D01*
X1737954Y430557D01*
X1737871Y430182D01*
X1739621D01*
G01X1738290Y434557D02*
X1733090D01*
G01X1738290Y441557D02*
X1730490D01*
G01X1738290Y434557D02*
Y441557D01*
G01X1724890Y434557D02*
X1733590D01*
G01X1724890Y441557D02*
Y434557D01*
G01X1731290Y441557D02*
X1724890D01*
G01X1750895Y517728D02*
X1750645Y517853D01*
X1750353Y517936D01*
X1750020D01*
X1749645Y517811D01*
X1749353Y517603D01*
X1749145Y517353D01*
X1748978Y516936D01*
X1748936Y516561D01*
X1749020Y516186D01*
X1749145Y515936D01*
X1749395Y515686D01*
X1749686Y515519D01*
X1749978Y515436D01*
X1750270D01*
X1750561Y515519D01*
X1750811Y515644D01*
X1751020Y515811D01*
G01X1752161Y515936D02*
X1752411Y515644D01*
X1752745Y515478D01*
X1753120Y515436D01*
X1753453Y515478D01*
X1753786Y515686D01*
X1753995Y515936D01*
X1754036Y516186D01*
X1753953Y516478D01*
X1753661Y516686D01*
X1753370Y516769D01*
X1752995D01*
G01X1753370D02*
X1753620Y516894D01*
X1753828Y517103D01*
X1753911Y517353D01*
X1753828Y517603D01*
X1753620Y517811D01*
X1753245Y517936D01*
X1752870Y517894D01*
X1752495Y517728D01*
G01X1756178Y515436D02*
Y517936D01*
X1755678Y517436D01*
G01Y515436D02*
X1756678D01*
G01X1758361Y515811D02*
X1758611Y515603D01*
X1758903Y515478D01*
X1759278Y515436D01*
X1759653Y515519D01*
X1759945Y515686D01*
X1760153Y515978D01*
X1760195Y516311D01*
X1760111Y516644D01*
X1759903Y516853D01*
X1759611Y517019D01*
X1759320Y517061D01*
X1759028Y517019D01*
X1758653Y516853D01*
X1758778Y517936D01*
X1759903D01*
G01X1750767Y521592D02*
X1750517Y521717D01*
X1750225Y521800D01*
X1749892D01*
X1749517Y521675D01*
X1749225Y521467D01*
X1749017Y521217D01*
X1748850Y520800D01*
X1748808Y520425D01*
X1748892Y520050D01*
X1749017Y519800D01*
X1749267Y519550D01*
X1749558Y519383D01*
X1749850Y519300D01*
X1750142D01*
X1750433Y519383D01*
X1750683Y519508D01*
X1750892Y519675D01*
G01X1752033Y519800D02*
X1752283Y519508D01*
X1752617Y519342D01*
X1752992Y519300D01*
X1753325Y519342D01*
X1753658Y519550D01*
X1753867Y519800D01*
X1753908Y520050D01*
X1753825Y520342D01*
X1753533Y520550D01*
X1753242Y520633D01*
X1752867D01*
G01X1753242D02*
X1753492Y520758D01*
X1753700Y520967D01*
X1753783Y521217D01*
X1753700Y521467D01*
X1753492Y521675D01*
X1753117Y521800D01*
X1752742Y521758D01*
X1752367Y521592D01*
G01X1756050Y519300D02*
Y521800D01*
X1755550Y521300D01*
G01Y519300D02*
X1756550D01*
G01X1759650D02*
Y521800D01*
X1758108Y520008D01*
X1760192D01*
G01X1793208Y536267D02*
X1793083Y536017D01*
X1793000Y535725D01*
Y535392D01*
X1793125Y535017D01*
X1793333Y534725D01*
X1793583Y534517D01*
X1794000Y534350D01*
X1794375Y534308D01*
X1794750Y534392D01*
X1795000Y534517D01*
X1795250Y534767D01*
X1795417Y535058D01*
X1795500Y535350D01*
Y535642D01*
X1795417Y535933D01*
X1795292Y536183D01*
X1795125Y536392D01*
G01X1795000Y537533D02*
X1795292Y537783D01*
X1795458Y538117D01*
X1795500Y538492D01*
X1795458Y538825D01*
X1795250Y539158D01*
X1795000Y539367D01*
X1794750Y539408D01*
X1794458Y539325D01*
X1794250Y539033D01*
X1794167Y538742D01*
Y538367D01*
G01Y538742D02*
X1794042Y538992D01*
X1793833Y539200D01*
X1793583Y539283D01*
X1793333Y539200D01*
X1793125Y538992D01*
X1793000Y538617D01*
X1793042Y538242D01*
X1793208Y537867D01*
G01X1793417Y540758D02*
X1793167Y541008D01*
X1793042Y541300D01*
X1793000Y541633D01*
X1793083Y542050D01*
X1793292Y542342D01*
X1793542Y542425D01*
X1793792Y542383D01*
X1794000Y542217D01*
X1794417Y541383D01*
X1794708Y541008D01*
X1795125Y540758D01*
X1795500Y540675D01*
Y542425D01*
G01Y545150D02*
X1793000D01*
X1794792Y543608D01*
Y545692D01*
G01X1814206Y564802D02*
X1813956Y564927D01*
X1813664Y565010D01*
X1813331D01*
X1812956Y564885D01*
X1812664Y564677D01*
X1812456Y564427D01*
X1812289Y564010D01*
X1812247Y563635D01*
X1812331Y563260D01*
X1812456Y563010D01*
X1812706Y562760D01*
X1812997Y562593D01*
X1813289Y562510D01*
X1813581D01*
X1813872Y562593D01*
X1814122Y562718D01*
X1814331Y562885D01*
G01X1815472Y563010D02*
X1815722Y562718D01*
X1816056Y562552D01*
X1816431Y562510D01*
X1816764Y562552D01*
X1817097Y562760D01*
X1817306Y563010D01*
X1817347Y563260D01*
X1817264Y563552D01*
X1816972Y563760D01*
X1816681Y563843D01*
X1816306D01*
G01X1816681D02*
X1816931Y563968D01*
X1817139Y564177D01*
X1817222Y564427D01*
X1817139Y564677D01*
X1816931Y564885D01*
X1816556Y565010D01*
X1816181Y564968D01*
X1815806Y564802D01*
G01X1818697Y564593D02*
X1818947Y564843D01*
X1819239Y564968D01*
X1819572Y565010D01*
X1819989Y564927D01*
X1820281Y564718D01*
X1820364Y564468D01*
X1820322Y564218D01*
X1820156Y564010D01*
X1819322Y563593D01*
X1818947Y563302D01*
X1818697Y562885D01*
X1818614Y562510D01*
X1820364D01*
G01X1821672Y562885D02*
X1821922Y562677D01*
X1822214Y562552D01*
X1822589Y562510D01*
X1822964Y562593D01*
X1823256Y562760D01*
X1823464Y563052D01*
X1823506Y563385D01*
X1823422Y563718D01*
X1823214Y563927D01*
X1822922Y564093D01*
X1822631Y564135D01*
X1822339Y564093D01*
X1821964Y563927D01*
X1822089Y565010D01*
X1823214D01*
G01X1795500Y521517D02*
X1793000D01*
Y522558D01*
X1793125Y522892D01*
X1793292Y523100D01*
X1793625Y523183D01*
X1793958Y523100D01*
X1794167Y522850D01*
X1794292Y522558D01*
Y521517D01*
G01Y522558D02*
X1795500Y523183D01*
G01X1795125Y524533D02*
X1795333Y524783D01*
X1795458Y525075D01*
X1795500Y525450D01*
X1795417Y525825D01*
X1795250Y526117D01*
X1794958Y526325D01*
X1794625Y526367D01*
X1794292Y526283D01*
X1794083Y526075D01*
X1793917Y525783D01*
X1793875Y525492D01*
X1793917Y525200D01*
X1794083Y524825D01*
X1793000Y524950D01*
Y526075D01*
G01X1795500Y528550D02*
X1795458Y528842D01*
X1795333Y529175D01*
X1795125Y529383D01*
X1794833Y529467D01*
X1794542Y529383D01*
X1794292Y529133D01*
X1794167Y528758D01*
Y528342D01*
X1794083Y528092D01*
X1793875Y527883D01*
X1793583Y527800D01*
X1793292Y527925D01*
X1793083Y528217D01*
X1793000Y528550D01*
X1793083Y528883D01*
X1793292Y529175D01*
X1793583Y529300D01*
X1793875Y529217D01*
X1794083Y529008D01*
X1794167Y528758D01*
Y528342D01*
X1794292Y527967D01*
X1794542Y527717D01*
X1794833Y527633D01*
X1795125Y527717D01*
X1795333Y527925D01*
X1795458Y528258D01*
X1795500Y528550D01*
G01X1795000Y530733D02*
X1795292Y530983D01*
X1795458Y531317D01*
X1795500Y531692D01*
X1795458Y532025D01*
X1795250Y532358D01*
X1795000Y532567D01*
X1794750Y532608D01*
X1794458Y532525D01*
X1794250Y532233D01*
X1794167Y531942D01*
Y531567D01*
G01Y531942D02*
X1794042Y532192D01*
X1793833Y532400D01*
X1793583Y532483D01*
X1793333Y532400D01*
X1793125Y532192D01*
X1793000Y531817D01*
X1793042Y531442D01*
X1793208Y531067D01*
G01X1798600Y532100D02*
Y528100D01*
X1806000D01*
G01X1801000Y495517D02*
X1798500D01*
Y496558D01*
X1798625Y496892D01*
X1798792Y497100D01*
X1799125Y497183D01*
X1799458Y497100D01*
X1799667Y496850D01*
X1799792Y496558D01*
Y495517D01*
G01Y496558D02*
X1801000Y497183D01*
G01X1800625Y498533D02*
X1800833Y498783D01*
X1800958Y499075D01*
X1801000Y499450D01*
X1800917Y499825D01*
X1800750Y500117D01*
X1800458Y500325D01*
X1800125Y500367D01*
X1799792Y500283D01*
X1799583Y500075D01*
X1799417Y499783D01*
X1799375Y499492D01*
X1799417Y499200D01*
X1799583Y498825D01*
X1798500Y498950D01*
Y500075D01*
G01X1801000Y502550D02*
X1800958Y502842D01*
X1800833Y503175D01*
X1800625Y503383D01*
X1800333Y503467D01*
X1800042Y503383D01*
X1799792Y503133D01*
X1799667Y502758D01*
Y502342D01*
X1799583Y502092D01*
X1799375Y501883D01*
X1799083Y501800D01*
X1798792Y501925D01*
X1798583Y502217D01*
X1798500Y502550D01*
X1798583Y502883D01*
X1798792Y503175D01*
X1799083Y503300D01*
X1799375Y503217D01*
X1799583Y503008D01*
X1799667Y502758D01*
Y502342D01*
X1799792Y501967D01*
X1800042Y501717D01*
X1800333Y501633D01*
X1800625Y501717D01*
X1800833Y501925D01*
X1800958Y502258D01*
X1801000Y502550D01*
G01Y506150D02*
X1798500D01*
X1800292Y504608D01*
Y506692D01*
G01X1806500Y502800D02*
X1810500D01*
Y510200D01*
G01X1816500Y502800D02*
X1820500D01*
Y510200D01*
G01X1797000Y495517D02*
X1794500D01*
Y496558D01*
X1794625Y496892D01*
X1794792Y497100D01*
X1795125Y497183D01*
X1795458Y497100D01*
X1795667Y496850D01*
X1795792Y496558D01*
Y495517D01*
G01Y496558D02*
X1797000Y497183D01*
G01X1796625Y498533D02*
X1796833Y498783D01*
X1796958Y499075D01*
X1797000Y499450D01*
X1796917Y499825D01*
X1796750Y500117D01*
X1796458Y500325D01*
X1796125Y500367D01*
X1795792Y500283D01*
X1795583Y500075D01*
X1795417Y499783D01*
X1795375Y499492D01*
X1795417Y499200D01*
X1795583Y498825D01*
X1794500Y498950D01*
Y500075D01*
G01X1797000Y502550D02*
X1796958Y502842D01*
X1796833Y503175D01*
X1796625Y503383D01*
X1796333Y503467D01*
X1796042Y503383D01*
X1795792Y503133D01*
X1795667Y502758D01*
Y502342D01*
X1795583Y502092D01*
X1795375Y501883D01*
X1795083Y501800D01*
X1794792Y501925D01*
X1794583Y502217D01*
X1794500Y502550D01*
X1794583Y502883D01*
X1794792Y503175D01*
X1795083Y503300D01*
X1795375Y503217D01*
X1795583Y503008D01*
X1795667Y502758D01*
Y502342D01*
X1795792Y501967D01*
X1796042Y501717D01*
X1796333Y501633D01*
X1796625Y501717D01*
X1796833Y501925D01*
X1796958Y502258D01*
X1797000Y502550D01*
G01X1796708Y504942D02*
X1796917Y505233D01*
X1797000Y505567D01*
X1796917Y505900D01*
X1796667Y506192D01*
X1796292Y506400D01*
X1795917Y506483D01*
X1795458D01*
X1795083Y506400D01*
X1794750Y506192D01*
X1794583Y505942D01*
X1794500Y505650D01*
X1794583Y505317D01*
X1794750Y505067D01*
X1795000Y504900D01*
X1795333Y504817D01*
X1795625Y504900D01*
X1795917Y505108D01*
X1796083Y505358D01*
X1796125Y505650D01*
X1796042Y505983D01*
X1795833Y506233D01*
X1795458Y506483D01*
G01X1806000Y510200D02*
X1802000D01*
Y502800D01*
G01X1813015Y558715D02*
Y561215D01*
X1814056D01*
X1814390Y561090D01*
X1814598Y560923D01*
X1814681Y560590D01*
X1814598Y560257D01*
X1814348Y560048D01*
X1814056Y559923D01*
X1813015D01*
G01X1814056D02*
X1814681Y558715D01*
G01X1816031Y559090D02*
X1816281Y558882D01*
X1816573Y558757D01*
X1816948Y558715D01*
X1817323Y558798D01*
X1817615Y558965D01*
X1817823Y559257D01*
X1817865Y559590D01*
X1817781Y559923D01*
X1817573Y560132D01*
X1817281Y560298D01*
X1816990Y560340D01*
X1816698Y560298D01*
X1816323Y560132D01*
X1816448Y561215D01*
X1817573D01*
G01X1819340Y559007D02*
X1819631Y558798D01*
X1819965Y558715D01*
X1820298Y558798D01*
X1820590Y559048D01*
X1820798Y559423D01*
X1820881Y559798D01*
Y560257D01*
X1820798Y560632D01*
X1820590Y560965D01*
X1820340Y561132D01*
X1820048Y561215D01*
X1819715Y561132D01*
X1819465Y560965D01*
X1819298Y560715D01*
X1819215Y560382D01*
X1819298Y560090D01*
X1819506Y559798D01*
X1819756Y559632D01*
X1820048Y559590D01*
X1820381Y559673D01*
X1820631Y559882D01*
X1820881Y560257D01*
G01X1823148Y558715D02*
Y561215D01*
X1822648Y560715D01*
G01Y558715D02*
X1823648D01*
G01X1808017Y532500D02*
Y535000D01*
X1809058D01*
X1809392Y534875D01*
X1809600Y534708D01*
X1809683Y534375D01*
X1809600Y534042D01*
X1809350Y533833D01*
X1809058Y533708D01*
X1808017D01*
G01X1809058D02*
X1809683Y532500D01*
G01X1811033Y532875D02*
X1811283Y532667D01*
X1811575Y532542D01*
X1811950Y532500D01*
X1812325Y532583D01*
X1812617Y532750D01*
X1812825Y533042D01*
X1812867Y533375D01*
X1812783Y533708D01*
X1812575Y533917D01*
X1812283Y534083D01*
X1811992Y534125D01*
X1811700Y534083D01*
X1811325Y533917D01*
X1811450Y535000D01*
X1812575D01*
G01X1814342Y532792D02*
X1814633Y532583D01*
X1814967Y532500D01*
X1815300Y532583D01*
X1815592Y532833D01*
X1815800Y533208D01*
X1815883Y533583D01*
Y534042D01*
X1815800Y534417D01*
X1815592Y534750D01*
X1815342Y534917D01*
X1815050Y535000D01*
X1814717Y534917D01*
X1814467Y534750D01*
X1814300Y534500D01*
X1814217Y534167D01*
X1814300Y533875D01*
X1814508Y533583D01*
X1814758Y533417D01*
X1815050Y533375D01*
X1815383Y533458D01*
X1815633Y533667D01*
X1815883Y534042D01*
G01X1817358Y534583D02*
X1817608Y534833D01*
X1817900Y534958D01*
X1818233Y535000D01*
X1818650Y534917D01*
X1818942Y534708D01*
X1819025Y534458D01*
X1818983Y534208D01*
X1818817Y534000D01*
X1817983Y533583D01*
X1817608Y533292D01*
X1817358Y532875D01*
X1817275Y532500D01*
X1819025D01*
G01X1816500Y515300D02*
X1820500D01*
Y522700D01*
G01X1742463Y486982D02*
Y489482D01*
X1743504D01*
X1743838Y489357D01*
X1744046Y489190D01*
X1744129Y488857D01*
X1744046Y488524D01*
X1743796Y488315D01*
X1743504Y488190D01*
X1742463D01*
G01X1743504D02*
X1744129Y486982D01*
G01X1746396D02*
Y489482D01*
X1745896Y488982D01*
G01Y486982D02*
X1746896D01*
G01X1749496D02*
Y489482D01*
X1748996Y488982D01*
G01Y486982D02*
X1749996D01*
G01X1751679Y487357D02*
X1751929Y487149D01*
X1752221Y487024D01*
X1752596Y486982D01*
X1752971Y487065D01*
X1753263Y487232D01*
X1753471Y487524D01*
X1753513Y487857D01*
X1753429Y488190D01*
X1753221Y488399D01*
X1752929Y488565D01*
X1752638Y488607D01*
X1752346Y488565D01*
X1751971Y488399D01*
X1752096Y489482D01*
X1753221D01*
G01X1756196Y486982D02*
Y489482D01*
X1754654Y487690D01*
X1756738D01*
G01X1744859Y483407D02*
X1740859D01*
Y476007D01*
G01X1748463Y481482D02*
Y483982D01*
X1749504D01*
X1749838Y483857D01*
X1750046Y483690D01*
X1750129Y483357D01*
X1750046Y483024D01*
X1749796Y482815D01*
X1749504Y482690D01*
X1748463D01*
G01X1749504D02*
X1750129Y481482D01*
G01X1752396D02*
Y483982D01*
X1751896Y483482D01*
G01Y481482D02*
X1752896D01*
G01X1755496D02*
Y483982D01*
X1754996Y483482D01*
G01Y481482D02*
X1755996D01*
G01X1757679Y481857D02*
X1757929Y481649D01*
X1758221Y481524D01*
X1758596Y481482D01*
X1758971Y481565D01*
X1759263Y481732D01*
X1759471Y482024D01*
X1759513Y482357D01*
X1759429Y482690D01*
X1759221Y482899D01*
X1758929Y483065D01*
X1758638Y483107D01*
X1758346Y483065D01*
X1757971Y482899D01*
X1758096Y483982D01*
X1759221D01*
G01X1760779Y481857D02*
X1761029Y481649D01*
X1761321Y481524D01*
X1761696Y481482D01*
X1762071Y481565D01*
X1762363Y481732D01*
X1762571Y482024D01*
X1762613Y482357D01*
X1762529Y482690D01*
X1762321Y482899D01*
X1762029Y483065D01*
X1761738Y483107D01*
X1761446Y483065D01*
X1761071Y482899D01*
X1761196Y483982D01*
X1762321D01*
G01X1752359Y475607D02*
Y479607D01*
X1744959D01*
G01X1726063Y490682D02*
Y493182D01*
X1727104D01*
X1727438Y493057D01*
X1727646Y492890D01*
X1727729Y492557D01*
X1727646Y492224D01*
X1727396Y492015D01*
X1727104Y491890D01*
X1726063D01*
G01X1727104D02*
X1727729Y490682D01*
G01X1729996D02*
Y493182D01*
X1729496Y492682D01*
G01Y490682D02*
X1730496D01*
G01X1733096D02*
Y493182D01*
X1732596Y492682D01*
G01Y490682D02*
X1733596D01*
G01X1735279Y491057D02*
X1735529Y490849D01*
X1735821Y490724D01*
X1736196Y490682D01*
X1736571Y490765D01*
X1736863Y490932D01*
X1737071Y491224D01*
X1737113Y491557D01*
X1737029Y491890D01*
X1736821Y492099D01*
X1736529Y492265D01*
X1736238Y492307D01*
X1735946Y492265D01*
X1735571Y492099D01*
X1735696Y493182D01*
X1736821D01*
G01X1739213Y490682D02*
X1739296Y491224D01*
X1739421Y491682D01*
X1739588Y492099D01*
X1739796Y492557D01*
X1740129Y493182D01*
X1738463D01*
G01X1726063Y482182D02*
Y484682D01*
X1727104D01*
X1727438Y484557D01*
X1727646Y484390D01*
X1727729Y484057D01*
X1727646Y483724D01*
X1727396Y483515D01*
X1727104Y483390D01*
X1726063D01*
G01X1727104D02*
X1727729Y482182D01*
G01X1729996D02*
Y484682D01*
X1729496Y484182D01*
G01Y482182D02*
X1730496D01*
G01X1733096D02*
Y484682D01*
X1732596Y484182D01*
G01Y482182D02*
X1733596D01*
G01X1735404Y483224D02*
X1735696Y483515D01*
X1735946Y483682D01*
X1736279Y483765D01*
X1736571Y483682D01*
X1736779Y483515D01*
X1736946Y483265D01*
X1736988Y482974D01*
X1736946Y482724D01*
X1736779Y482474D01*
X1736529Y482265D01*
X1736238Y482182D01*
X1735904Y482265D01*
X1735613Y482515D01*
X1735446Y482890D01*
X1735404Y483307D01*
X1735488Y483849D01*
X1735613Y484140D01*
X1735821Y484432D01*
X1736113Y484640D01*
X1736404Y484682D01*
X1736696Y484599D01*
X1736904Y484390D01*
G01X1739296Y482182D02*
Y484682D01*
X1738796Y484182D01*
G01Y482182D02*
X1739796D01*
G01X1727626Y488660D02*
X1727376Y488785D01*
X1727084Y488868D01*
X1726751D01*
X1726376Y488743D01*
X1726084Y488535D01*
X1725876Y488285D01*
X1725709Y487868D01*
X1725667Y487493D01*
X1725751Y487118D01*
X1725876Y486868D01*
X1726126Y486618D01*
X1726417Y486451D01*
X1726709Y486368D01*
X1727001D01*
X1727292Y486451D01*
X1727542Y486576D01*
X1727751Y486743D01*
G01X1729017Y487410D02*
X1729309Y487701D01*
X1729559Y487868D01*
X1729892Y487951D01*
X1730184Y487868D01*
X1730392Y487701D01*
X1730559Y487451D01*
X1730601Y487160D01*
X1730559Y486910D01*
X1730392Y486660D01*
X1730142Y486451D01*
X1729851Y486368D01*
X1729517Y486451D01*
X1729226Y486701D01*
X1729059Y487076D01*
X1729017Y487493D01*
X1729101Y488035D01*
X1729226Y488326D01*
X1729434Y488618D01*
X1729726Y488826D01*
X1730017Y488868D01*
X1730309Y488785D01*
X1730517Y488576D01*
G01X1732826Y486368D02*
X1732909Y486910D01*
X1733034Y487368D01*
X1733201Y487785D01*
X1733409Y488243D01*
X1733742Y488868D01*
X1732076D01*
G01X1735926Y486368D02*
X1736009Y486910D01*
X1736134Y487368D01*
X1736301Y487785D01*
X1736509Y488243D01*
X1736842Y488868D01*
X1735176D01*
G01X1798850Y559000D02*
X1798517Y559042D01*
X1798225Y559208D01*
X1797975Y559458D01*
X1797808Y559750D01*
X1797725Y560083D01*
Y560417D01*
X1797808Y560750D01*
X1797975Y561042D01*
X1798225Y561292D01*
X1798517Y561458D01*
X1798850Y561500D01*
X1799183Y561458D01*
X1799475Y561292D01*
X1799725Y561042D01*
X1799892Y560750D01*
X1799975Y560417D01*
Y560083D01*
X1799892Y559750D01*
X1799725Y559458D01*
X1799475Y559208D01*
X1799183Y559042D01*
X1798850Y559000D01*
G01X1799183Y559667D02*
X1799683Y559000D01*
G01X1801950D02*
Y561500D01*
X1801450Y561000D01*
G01Y559000D02*
X1802450D01*
G01X1805050Y561500D02*
X1804717Y561417D01*
X1804467Y561208D01*
X1804300Y560958D01*
X1804175Y560625D01*
X1804133Y560250D01*
X1804175Y559875D01*
X1804300Y559542D01*
X1804467Y559292D01*
X1804717Y559083D01*
X1805050Y559000D01*
X1805383Y559083D01*
X1805633Y559292D01*
X1805800Y559542D01*
X1805925Y559875D01*
X1805967Y560250D01*
X1805925Y560625D01*
X1805800Y560958D01*
X1805633Y561208D01*
X1805383Y561417D01*
X1805050Y561500D01*
G01X1807358Y560042D02*
X1807650Y560333D01*
X1807900Y560500D01*
X1808233Y560583D01*
X1808525Y560500D01*
X1808733Y560333D01*
X1808900Y560083D01*
X1808942Y559792D01*
X1808900Y559542D01*
X1808733Y559292D01*
X1808483Y559083D01*
X1808192Y559000D01*
X1807858Y559083D01*
X1807567Y559333D01*
X1807400Y559708D01*
X1807358Y560125D01*
X1807442Y560667D01*
X1807567Y560958D01*
X1807775Y561250D01*
X1808067Y561458D01*
X1808358Y561500D01*
X1808650Y561417D01*
X1808858Y561208D01*
G01X1817000Y557700D02*
X1815200Y555600D01*
X1813000Y557700D01*
G01X1809400Y557800D02*
Y538600D01*
X1820600D01*
Y557800D01*
X1809400D01*
Y557400D01*
G01X1807983Y527000D02*
Y529500D01*
X1808817D01*
X1809150Y529375D01*
X1809400Y529208D01*
X1809608Y528958D01*
X1809775Y528667D01*
X1809817Y528250D01*
X1809775Y527833D01*
X1809608Y527542D01*
X1809400Y527292D01*
X1809150Y527125D01*
X1808817Y527000D01*
X1807983D01*
G01X1811208Y529083D02*
X1811458Y529333D01*
X1811750Y529458D01*
X1812083Y529500D01*
X1812500Y529417D01*
X1812792Y529208D01*
X1812875Y528958D01*
X1812833Y528708D01*
X1812667Y528500D01*
X1811833Y528083D01*
X1811458Y527792D01*
X1811208Y527375D01*
X1811125Y527000D01*
X1812875D01*
G01X1814308Y529083D02*
X1814558Y529333D01*
X1814850Y529458D01*
X1815183Y529500D01*
X1815600Y529417D01*
X1815892Y529208D01*
X1815975Y528958D01*
X1815933Y528708D01*
X1815767Y528500D01*
X1814933Y528083D01*
X1814558Y527792D01*
X1814308Y527375D01*
X1814225Y527000D01*
X1815975D01*
G01X1833000Y523500D02*
X1816900D01*
G01Y530500D02*
X1833000D01*
G01X1816900Y523500D02*
Y530500D01*
G01X1796000Y509350D02*
X1795958Y509017D01*
X1795792Y508725D01*
X1795542Y508475D01*
X1795250Y508308D01*
X1794917Y508225D01*
X1794583D01*
X1794250Y508308D01*
X1793958Y508475D01*
X1793708Y508725D01*
X1793542Y509017D01*
X1793500Y509350D01*
X1793542Y509683D01*
X1793708Y509975D01*
X1793958Y510225D01*
X1794250Y510392D01*
X1794583Y510475D01*
X1794917D01*
X1795250Y510392D01*
X1795542Y510225D01*
X1795792Y509975D01*
X1795958Y509683D01*
X1796000Y509350D01*
G01X1795333Y509683D02*
X1796000Y510183D01*
G01Y512450D02*
X1793500D01*
X1794000Y511950D01*
G01X1796000D02*
Y512950D01*
G01X1793500Y515550D02*
X1793583Y515217D01*
X1793792Y514967D01*
X1794042Y514800D01*
X1794375Y514675D01*
X1794750Y514633D01*
X1795125Y514675D01*
X1795458Y514800D01*
X1795708Y514967D01*
X1795917Y515217D01*
X1796000Y515550D01*
X1795917Y515883D01*
X1795708Y516133D01*
X1795458Y516300D01*
X1795125Y516425D01*
X1794750Y516467D01*
X1794375Y516425D01*
X1794042Y516300D01*
X1793792Y516133D01*
X1793583Y515883D01*
X1793500Y515550D01*
G01X1796000Y518567D02*
X1795458Y518650D01*
X1795000Y518775D01*
X1794583Y518942D01*
X1794125Y519150D01*
X1793500Y519483D01*
Y517817D01*
G01X1797300Y522700D02*
Y511300D01*
G01X1810700Y522700D02*
X1797300D01*
G01X1810700Y511300D02*
Y522700D01*
G01X1797300Y511300D02*
X1810700D01*
G01X1797017Y571000D02*
Y573500D01*
X1798058D01*
X1798392Y573375D01*
X1798600Y573208D01*
X1798683Y572875D01*
X1798600Y572542D01*
X1798350Y572333D01*
X1798058Y572208D01*
X1797017D01*
G01X1798058D02*
X1798683Y571000D01*
G01X1800033Y571375D02*
X1800283Y571167D01*
X1800575Y571042D01*
X1800950Y571000D01*
X1801325Y571083D01*
X1801617Y571250D01*
X1801825Y571542D01*
X1801867Y571875D01*
X1801783Y572208D01*
X1801575Y572417D01*
X1801283Y572583D01*
X1800992Y572625D01*
X1800700Y572583D01*
X1800325Y572417D01*
X1800450Y573500D01*
X1801575D01*
G01X1803967Y571000D02*
X1804050Y571542D01*
X1804175Y572000D01*
X1804342Y572417D01*
X1804550Y572875D01*
X1804883Y573500D01*
X1803217D01*
G01X1806233Y571375D02*
X1806483Y571167D01*
X1806775Y571042D01*
X1807150Y571000D01*
X1807525Y571083D01*
X1807817Y571250D01*
X1808025Y571542D01*
X1808067Y571875D01*
X1807983Y572208D01*
X1807775Y572417D01*
X1807483Y572583D01*
X1807192Y572625D01*
X1806900Y572583D01*
X1806525Y572417D01*
X1806650Y573500D01*
X1807775D01*
G01X1766275Y662000D02*
Y664500D01*
G01X1768025D02*
Y662000D01*
G01Y663250D02*
X1766275D01*
G01X1769333Y662000D02*
Y664500D01*
X1770167D01*
X1770500Y664375D01*
X1770750Y664208D01*
X1770958Y663958D01*
X1771125Y663667D01*
X1771167Y663250D01*
X1771125Y662833D01*
X1770958Y662542D01*
X1770750Y662292D01*
X1770500Y662125D01*
X1770167Y662000D01*
X1769333D01*
G01X1772433D02*
Y664500D01*
X1773267D01*
X1773600Y664375D01*
X1773850Y664208D01*
X1774058Y663958D01*
X1774225Y663667D01*
X1774267Y663250D01*
X1774225Y662833D01*
X1774058Y662542D01*
X1773850Y662292D01*
X1773600Y662125D01*
X1773267Y662000D01*
X1772433D01*
G01X1775575Y662333D02*
X1775908Y662125D01*
X1776283Y662000D01*
X1776617D01*
X1776950Y662125D01*
X1777200Y662333D01*
X1777325Y662625D01*
X1777242Y662917D01*
X1777033Y663167D01*
X1776658Y663333D01*
X1776158Y663417D01*
X1775867Y663583D01*
X1775742Y663875D01*
X1775825Y664167D01*
X1776033Y664375D01*
X1776325Y664500D01*
X1776617D01*
X1776908Y664417D01*
X1777158Y664208D01*
G01X1778508Y662000D02*
X1779550Y664500D01*
X1780592Y662000D01*
G01X1780217Y662875D02*
X1778883D01*
G01X1781775Y662333D02*
X1782108Y662125D01*
X1782483Y662000D01*
X1782817D01*
X1783150Y662125D01*
X1783400Y662333D01*
X1783525Y662625D01*
X1783442Y662917D01*
X1783233Y663167D01*
X1782858Y663333D01*
X1782358Y663417D01*
X1782067Y663583D01*
X1781942Y663875D01*
X1782025Y664167D01*
X1782233Y664375D01*
X1782525Y664500D01*
X1782817D01*
X1783108Y664417D01*
X1783358Y664208D01*
G01X1784958Y664083D02*
X1785208Y664333D01*
X1785500Y664458D01*
X1785833Y664500D01*
X1786250Y664417D01*
X1786542Y664208D01*
X1786625Y663958D01*
X1786583Y663708D01*
X1786417Y663500D01*
X1785583Y663083D01*
X1785208Y662792D01*
X1784958Y662375D01*
X1784875Y662000D01*
X1786625D01*
G01X1788058Y664083D02*
X1788308Y664333D01*
X1788600Y664458D01*
X1788933Y664500D01*
X1789350Y664417D01*
X1789642Y664208D01*
X1789725Y663958D01*
X1789683Y663708D01*
X1789517Y663500D01*
X1788683Y663083D01*
X1788308Y662792D01*
X1788058Y662375D01*
X1787975Y662000D01*
X1789725D01*
G01X1745267Y580953D02*
X1745017Y581078D01*
X1744725Y581161D01*
X1744392D01*
X1744017Y581036D01*
X1743725Y580828D01*
X1743517Y580578D01*
X1743350Y580161D01*
X1743308Y579786D01*
X1743392Y579411D01*
X1743517Y579161D01*
X1743767Y578911D01*
X1744058Y578744D01*
X1744350Y578661D01*
X1744642D01*
X1744933Y578744D01*
X1745183Y578869D01*
X1745392Y579036D01*
G01X1746533Y579161D02*
X1746783Y578869D01*
X1747117Y578703D01*
X1747492Y578661D01*
X1747825Y578703D01*
X1748158Y578911D01*
X1748367Y579161D01*
X1748408Y579411D01*
X1748325Y579703D01*
X1748033Y579911D01*
X1747742Y579994D01*
X1747367D01*
G01X1747742D02*
X1747992Y580119D01*
X1748200Y580328D01*
X1748283Y580578D01*
X1748200Y580828D01*
X1747992Y581036D01*
X1747617Y581161D01*
X1747242Y581119D01*
X1746867Y580953D01*
G01X1750550Y578661D02*
Y581161D01*
X1750050Y580661D01*
G01Y578661D02*
X1751050D01*
G01X1753650D02*
X1753942Y578703D01*
X1754275Y578828D01*
X1754483Y579036D01*
X1754567Y579328D01*
X1754483Y579619D01*
X1754233Y579869D01*
X1753858Y579994D01*
X1753442D01*
X1753192Y580078D01*
X1752983Y580286D01*
X1752900Y580578D01*
X1753025Y580869D01*
X1753317Y581078D01*
X1753650Y581161D01*
X1753983Y581078D01*
X1754275Y580869D01*
X1754400Y580578D01*
X1754317Y580286D01*
X1754108Y580078D01*
X1753858Y579994D01*
X1753442D01*
X1753067Y579869D01*
X1752817Y579619D01*
X1752733Y579328D01*
X1752817Y579036D01*
X1753025Y578828D01*
X1753358Y578703D01*
X1753650Y578661D01*
G01X1743517Y582661D02*
Y585161D01*
X1744558D01*
X1744892Y585036D01*
X1745100Y584869D01*
X1745183Y584536D01*
X1745100Y584203D01*
X1744850Y583994D01*
X1744558Y583869D01*
X1743517D01*
G01X1744558D02*
X1745183Y582661D01*
G01X1746533Y583036D02*
X1746783Y582828D01*
X1747075Y582703D01*
X1747450Y582661D01*
X1747825Y582744D01*
X1748117Y582911D01*
X1748325Y583203D01*
X1748367Y583536D01*
X1748283Y583869D01*
X1748075Y584078D01*
X1747783Y584244D01*
X1747492Y584286D01*
X1747200Y584244D01*
X1746825Y584078D01*
X1746950Y585161D01*
X1748075D01*
G01X1750467Y582661D02*
X1750550Y583203D01*
X1750675Y583661D01*
X1750842Y584078D01*
X1751050Y584536D01*
X1751383Y585161D01*
X1749717D01*
G01X1752858Y583703D02*
X1753150Y583994D01*
X1753400Y584161D01*
X1753733Y584244D01*
X1754025Y584161D01*
X1754233Y583994D01*
X1754400Y583744D01*
X1754442Y583453D01*
X1754400Y583203D01*
X1754233Y582953D01*
X1753983Y582744D01*
X1753692Y582661D01*
X1753358Y582744D01*
X1753067Y582994D01*
X1752900Y583369D01*
X1752858Y583786D01*
X1752942Y584328D01*
X1753067Y584619D01*
X1753275Y584911D01*
X1753567Y585119D01*
X1753858Y585161D01*
X1754150Y585078D01*
X1754358Y584869D01*
G01X1757800Y585500D02*
Y581500D01*
X1765200D01*
G01X1794208Y609767D02*
X1794083Y609517D01*
X1794000Y609225D01*
Y608892D01*
X1794125Y608517D01*
X1794333Y608225D01*
X1794583Y608017D01*
X1795000Y607850D01*
X1795375Y607808D01*
X1795750Y607892D01*
X1796000Y608017D01*
X1796250Y608267D01*
X1796417Y608558D01*
X1796500Y608850D01*
Y609142D01*
X1796417Y609433D01*
X1796292Y609683D01*
X1796125Y609892D01*
G01X1796000Y611033D02*
X1796292Y611283D01*
X1796458Y611617D01*
X1796500Y611992D01*
X1796458Y612325D01*
X1796250Y612658D01*
X1796000Y612867D01*
X1795750Y612908D01*
X1795458Y612825D01*
X1795250Y612533D01*
X1795167Y612242D01*
Y611867D01*
G01Y612242D02*
X1795042Y612492D01*
X1794833Y612700D01*
X1794583Y612783D01*
X1794333Y612700D01*
X1794125Y612492D01*
X1794000Y612117D01*
X1794042Y611742D01*
X1794208Y611367D01*
G01X1796500Y615050D02*
X1794000D01*
X1794500Y614550D01*
G01X1796500D02*
Y615550D01*
G01X1795458Y617358D02*
X1795167Y617650D01*
X1795000Y617900D01*
X1794917Y618233D01*
X1795000Y618525D01*
X1795167Y618733D01*
X1795417Y618900D01*
X1795708Y618942D01*
X1795958Y618900D01*
X1796208Y618733D01*
X1796417Y618483D01*
X1796500Y618192D01*
X1796417Y617858D01*
X1796167Y617567D01*
X1795792Y617400D01*
X1795375Y617358D01*
X1794833Y617442D01*
X1794542Y617567D01*
X1794250Y617775D01*
X1794042Y618067D01*
X1794000Y618358D01*
X1794083Y618650D01*
X1794292Y618858D01*
G01X1793708Y643767D02*
X1793583Y643517D01*
X1793500Y643225D01*
Y642892D01*
X1793625Y642517D01*
X1793833Y642225D01*
X1794083Y642017D01*
X1794500Y641850D01*
X1794875Y641808D01*
X1795250Y641892D01*
X1795500Y642017D01*
X1795750Y642267D01*
X1795917Y642558D01*
X1796000Y642850D01*
Y643142D01*
X1795917Y643433D01*
X1795792Y643683D01*
X1795625Y643892D01*
G01X1795500Y645033D02*
X1795792Y645283D01*
X1795958Y645617D01*
X1796000Y645992D01*
X1795958Y646325D01*
X1795750Y646658D01*
X1795500Y646867D01*
X1795250Y646908D01*
X1794958Y646825D01*
X1794750Y646533D01*
X1794667Y646242D01*
Y645867D01*
G01Y646242D02*
X1794542Y646492D01*
X1794333Y646700D01*
X1794083Y646783D01*
X1793833Y646700D01*
X1793625Y646492D01*
X1793500Y646117D01*
X1793542Y645742D01*
X1793708Y645367D01*
G01X1793917Y648258D02*
X1793667Y648508D01*
X1793542Y648800D01*
X1793500Y649133D01*
X1793583Y649550D01*
X1793792Y649842D01*
X1794042Y649925D01*
X1794292Y649883D01*
X1794500Y649717D01*
X1794917Y648883D01*
X1795208Y648508D01*
X1795625Y648258D01*
X1796000Y648175D01*
Y649925D01*
G01X1795500Y651233D02*
X1795792Y651483D01*
X1795958Y651817D01*
X1796000Y652192D01*
X1795958Y652525D01*
X1795750Y652858D01*
X1795500Y653067D01*
X1795250Y653108D01*
X1794958Y653025D01*
X1794750Y652733D01*
X1794667Y652442D01*
Y652067D01*
G01Y652442D02*
X1794542Y652692D01*
X1794333Y652900D01*
X1794083Y652983D01*
X1793833Y652900D01*
X1793625Y652692D01*
X1793500Y652317D01*
X1793542Y651942D01*
X1793708Y651567D01*
G01X1747300Y616000D02*
Y613500D01*
G01X1746342Y616000D02*
X1748258D01*
G01X1749567Y613500D02*
Y616000D01*
X1750567D01*
X1750900Y615875D01*
X1751150Y615583D01*
X1751233Y615250D01*
X1751150Y614917D01*
X1750942Y614667D01*
X1750567Y614542D01*
X1749567D01*
G01X1753500Y613500D02*
Y616000D01*
X1753000Y615500D01*
G01Y613500D02*
X1754000D01*
G01X1755683Y614000D02*
X1755933Y613708D01*
X1756267Y613542D01*
X1756642Y613500D01*
X1756975Y613542D01*
X1757308Y613750D01*
X1757517Y614000D01*
X1757558Y614250D01*
X1757475Y614542D01*
X1757183Y614750D01*
X1756892Y614833D01*
X1756517D01*
G01X1756892D02*
X1757142Y614958D01*
X1757350Y615167D01*
X1757433Y615417D01*
X1757350Y615667D01*
X1757142Y615875D01*
X1756767Y616000D01*
X1756392Y615958D01*
X1756017Y615792D01*
G01X1759700Y613500D02*
Y616000D01*
X1759200Y615500D01*
G01Y613500D02*
X1760200D01*
G01X1811800Y585000D02*
X1813900Y583200D01*
X1811800Y581000D01*
G01X1811700Y577400D02*
X1830900D01*
Y588600D01*
X1811700D01*
Y577400D01*
X1812100D01*
G01X1752517Y598500D02*
Y601000D01*
X1753558D01*
X1753892Y600875D01*
X1754100Y600708D01*
X1754183Y600375D01*
X1754100Y600042D01*
X1753850Y599833D01*
X1753558Y599708D01*
X1752517D01*
G01X1753558D02*
X1754183Y598500D01*
G01X1755533Y598875D02*
X1755783Y598667D01*
X1756075Y598542D01*
X1756450Y598500D01*
X1756825Y598583D01*
X1757117Y598750D01*
X1757325Y599042D01*
X1757367Y599375D01*
X1757283Y599708D01*
X1757075Y599917D01*
X1756783Y600083D01*
X1756492Y600125D01*
X1756200Y600083D01*
X1755825Y599917D01*
X1755950Y601000D01*
X1757075D01*
G01X1759550Y598500D02*
X1759842Y598542D01*
X1760175Y598667D01*
X1760383Y598875D01*
X1760467Y599167D01*
X1760383Y599458D01*
X1760133Y599708D01*
X1759758Y599833D01*
X1759342D01*
X1759092Y599917D01*
X1758883Y600125D01*
X1758800Y600417D01*
X1758925Y600708D01*
X1759217Y600917D01*
X1759550Y601000D01*
X1759883Y600917D01*
X1760175Y600708D01*
X1760300Y600417D01*
X1760217Y600125D01*
X1760008Y599917D01*
X1759758Y599833D01*
X1759342D01*
X1758967Y599708D01*
X1758717Y599458D01*
X1758633Y599167D01*
X1758717Y598875D01*
X1758925Y598667D01*
X1759258Y598542D01*
X1759550Y598500D01*
G01X1762650Y601000D02*
X1762317Y600917D01*
X1762067Y600708D01*
X1761900Y600458D01*
X1761775Y600125D01*
X1761733Y599750D01*
X1761775Y599375D01*
X1761900Y599042D01*
X1762067Y598792D01*
X1762317Y598583D01*
X1762650Y598500D01*
X1762983Y598583D01*
X1763233Y598792D01*
X1763400Y599042D01*
X1763525Y599375D01*
X1763567Y599750D01*
X1763525Y600125D01*
X1763400Y600458D01*
X1763233Y600708D01*
X1762983Y600917D01*
X1762650Y601000D01*
G01X1798208Y608767D02*
X1798083Y608517D01*
X1798000Y608225D01*
Y607892D01*
X1798125Y607517D01*
X1798333Y607225D01*
X1798583Y607017D01*
X1799000Y606850D01*
X1799375Y606808D01*
X1799750Y606892D01*
X1800000Y607017D01*
X1800250Y607267D01*
X1800417Y607558D01*
X1800500Y607850D01*
Y608142D01*
X1800417Y608433D01*
X1800292Y608683D01*
X1800125Y608892D01*
G01X1800000Y610033D02*
X1800292Y610283D01*
X1800458Y610617D01*
X1800500Y610992D01*
X1800458Y611325D01*
X1800250Y611658D01*
X1800000Y611867D01*
X1799750Y611908D01*
X1799458Y611825D01*
X1799250Y611533D01*
X1799167Y611242D01*
Y610867D01*
G01Y611242D02*
X1799042Y611492D01*
X1798833Y611700D01*
X1798583Y611783D01*
X1798333Y611700D01*
X1798125Y611492D01*
X1798000Y611117D01*
X1798042Y610742D01*
X1798208Y610367D01*
G01X1800500Y614050D02*
X1798000D01*
X1798500Y613550D01*
G01X1800500D02*
Y614550D01*
G01Y617067D02*
X1799958Y617150D01*
X1799500Y617275D01*
X1799083Y617442D01*
X1798625Y617650D01*
X1798000Y617983D01*
Y616317D01*
G01X1801000Y589200D02*
Y594700D01*
G01X1809000Y589200D02*
X1801000D01*
G01X1809000Y594700D02*
Y589200D01*
G01Y606800D02*
Y601300D01*
G01X1801000Y606800D02*
X1809000D01*
G01X1801000Y601300D02*
Y606800D01*
G01X1810300Y583000D02*
Y575000D01*
X1792700D01*
Y583000D01*
X1810300D01*
G01X1809817Y618000D02*
Y620500D01*
X1810858D01*
X1811192Y620375D01*
X1811400Y620208D01*
X1811483Y619875D01*
X1811400Y619542D01*
X1811150Y619333D01*
X1810858Y619208D01*
X1809817D01*
G01X1810858D02*
X1811483Y618000D01*
G01X1812833Y618375D02*
X1813083Y618167D01*
X1813375Y618042D01*
X1813750Y618000D01*
X1814125Y618083D01*
X1814417Y618250D01*
X1814625Y618542D01*
X1814667Y618875D01*
X1814583Y619208D01*
X1814375Y619417D01*
X1814083Y619583D01*
X1813792Y619625D01*
X1813500Y619583D01*
X1813125Y619417D01*
X1813250Y620500D01*
X1814375D01*
G01X1816767Y618000D02*
X1816850Y618542D01*
X1816975Y619000D01*
X1817142Y619417D01*
X1817350Y619875D01*
X1817683Y620500D01*
X1816017D01*
G01X1819867Y618000D02*
X1819950Y618542D01*
X1820075Y619000D01*
X1820242Y619417D01*
X1820450Y619875D01*
X1820783Y620500D01*
X1819117D01*
G01X1819100Y616500D02*
Y608500D01*
X1801500D01*
Y616500D01*
X1819100D01*
G01X1800547Y643767D02*
X1800422Y643517D01*
X1800339Y643225D01*
Y642892D01*
X1800464Y642517D01*
X1800672Y642225D01*
X1800922Y642017D01*
X1801339Y641850D01*
X1801714Y641808D01*
X1802089Y641892D01*
X1802339Y642017D01*
X1802589Y642267D01*
X1802756Y642558D01*
X1802839Y642850D01*
Y643142D01*
X1802756Y643433D01*
X1802631Y643683D01*
X1802464Y643892D01*
G01X1802339Y645033D02*
X1802631Y645283D01*
X1802797Y645617D01*
X1802839Y645992D01*
X1802797Y646325D01*
X1802589Y646658D01*
X1802339Y646867D01*
X1802089Y646908D01*
X1801797Y646825D01*
X1801589Y646533D01*
X1801506Y646242D01*
Y645867D01*
G01Y646242D02*
X1801381Y646492D01*
X1801172Y646700D01*
X1800922Y646783D01*
X1800672Y646700D01*
X1800464Y646492D01*
X1800339Y646117D01*
X1800381Y645742D01*
X1800547Y645367D01*
G01X1800756Y648258D02*
X1800506Y648508D01*
X1800381Y648800D01*
X1800339Y649133D01*
X1800422Y649550D01*
X1800631Y649842D01*
X1800881Y649925D01*
X1801131Y649883D01*
X1801339Y649717D01*
X1801756Y648883D01*
X1802047Y648508D01*
X1802464Y648258D01*
X1802839Y648175D01*
Y649925D01*
G01Y652150D02*
X1800339D01*
X1800839Y651650D01*
G01X1802839D02*
Y652650D01*
G01X1808547Y643767D02*
X1808422Y643517D01*
X1808339Y643225D01*
Y642892D01*
X1808464Y642517D01*
X1808672Y642225D01*
X1808922Y642017D01*
X1809339Y641850D01*
X1809714Y641808D01*
X1810089Y641892D01*
X1810339Y642017D01*
X1810589Y642267D01*
X1810756Y642558D01*
X1810839Y642850D01*
Y643142D01*
X1810756Y643433D01*
X1810631Y643683D01*
X1810464Y643892D01*
G01X1810339Y645033D02*
X1810631Y645283D01*
X1810797Y645617D01*
X1810839Y645992D01*
X1810797Y646325D01*
X1810589Y646658D01*
X1810339Y646867D01*
X1810089Y646908D01*
X1809797Y646825D01*
X1809589Y646533D01*
X1809506Y646242D01*
Y645867D01*
G01Y646242D02*
X1809381Y646492D01*
X1809172Y646700D01*
X1808922Y646783D01*
X1808672Y646700D01*
X1808464Y646492D01*
X1808339Y646117D01*
X1808381Y645742D01*
X1808547Y645367D01*
G01X1808756Y648258D02*
X1808506Y648508D01*
X1808381Y648800D01*
X1808339Y649133D01*
X1808422Y649550D01*
X1808631Y649842D01*
X1808881Y649925D01*
X1809131Y649883D01*
X1809339Y649717D01*
X1809756Y648883D01*
X1810047Y648508D01*
X1810464Y648258D01*
X1810839Y648175D01*
Y649925D01*
G01X1808756Y651358D02*
X1808506Y651608D01*
X1808381Y651900D01*
X1808339Y652233D01*
X1808422Y652650D01*
X1808631Y652942D01*
X1808881Y653025D01*
X1809131Y652983D01*
X1809339Y652817D01*
X1809756Y651983D01*
X1810047Y651608D01*
X1810464Y651358D01*
X1810839Y651275D01*
Y653025D01*
G01X1730967Y721500D02*
Y719000D01*
X1732633D01*
G01X1735733D02*
X1734067D01*
Y721500D01*
X1735733D01*
G01X1735067Y720292D02*
X1734067D01*
G01X1737083Y719000D02*
Y721500D01*
X1737917D01*
X1738250Y721375D01*
X1738500Y721208D01*
X1738708Y720958D01*
X1738875Y720667D01*
X1738917Y720250D01*
X1738875Y719833D01*
X1738708Y719542D01*
X1738500Y719292D01*
X1738250Y719125D01*
X1737917Y719000D01*
X1737083D01*
G01X1741100D02*
Y721500D01*
X1740600Y721000D01*
G01Y719000D02*
X1741600D01*
G01X1744200D02*
Y721500D01*
X1743700Y721000D01*
G01Y719000D02*
X1744700D01*
G01X1733198Y704636D02*
Y715836D01*
X1741998D01*
Y704636D01*
X1733198D01*
G01X1730644Y853959D02*
Y857959D01*
X1723244D01*
G01X1748500Y839017D02*
X1746000D01*
Y840058D01*
X1746125Y840392D01*
X1746292Y840600D01*
X1746625Y840683D01*
X1746958Y840600D01*
X1747167Y840350D01*
X1747292Y840058D01*
Y839017D01*
G01Y840058D02*
X1748500Y840683D01*
G01X1748000Y842033D02*
X1748292Y842283D01*
X1748458Y842617D01*
X1748500Y842992D01*
X1748458Y843325D01*
X1748250Y843658D01*
X1748000Y843867D01*
X1747750Y843908D01*
X1747458Y843825D01*
X1747250Y843533D01*
X1747167Y843242D01*
Y842867D01*
G01Y843242D02*
X1747042Y843492D01*
X1746833Y843700D01*
X1746583Y843783D01*
X1746333Y843700D01*
X1746125Y843492D01*
X1746000Y843117D01*
X1746042Y842742D01*
X1746208Y842367D01*
G01X1747458Y845258D02*
X1747167Y845550D01*
X1747000Y845800D01*
X1746917Y846133D01*
X1747000Y846425D01*
X1747167Y846633D01*
X1747417Y846800D01*
X1747708Y846842D01*
X1747958Y846800D01*
X1748208Y846633D01*
X1748417Y846383D01*
X1748500Y846092D01*
X1748417Y845758D01*
X1748167Y845467D01*
X1747792Y845300D01*
X1747375Y845258D01*
X1746833Y845342D01*
X1746542Y845467D01*
X1746250Y845675D01*
X1746042Y845967D01*
X1746000Y846258D01*
X1746083Y846550D01*
X1746292Y846758D01*
G01X1748500Y849650D02*
X1746000D01*
X1747792Y848108D01*
Y850192D01*
G01X1752500Y839017D02*
X1750000D01*
Y840058D01*
X1750125Y840392D01*
X1750292Y840600D01*
X1750625Y840683D01*
X1750958Y840600D01*
X1751167Y840350D01*
X1751292Y840058D01*
Y839017D01*
G01Y840058D02*
X1752500Y840683D01*
G01X1752000Y842033D02*
X1752292Y842283D01*
X1752458Y842617D01*
X1752500Y842992D01*
X1752458Y843325D01*
X1752250Y843658D01*
X1752000Y843867D01*
X1751750Y843908D01*
X1751458Y843825D01*
X1751250Y843533D01*
X1751167Y843242D01*
Y842867D01*
G01Y843242D02*
X1751042Y843492D01*
X1750833Y843700D01*
X1750583Y843783D01*
X1750333Y843700D01*
X1750125Y843492D01*
X1750000Y843117D01*
X1750042Y842742D01*
X1750208Y842367D01*
G01X1751458Y845258D02*
X1751167Y845550D01*
X1751000Y845800D01*
X1750917Y846133D01*
X1751000Y846425D01*
X1751167Y846633D01*
X1751417Y846800D01*
X1751708Y846842D01*
X1751958Y846800D01*
X1752208Y846633D01*
X1752417Y846383D01*
X1752500Y846092D01*
X1752417Y845758D01*
X1752167Y845467D01*
X1751792Y845300D01*
X1751375Y845258D01*
X1750833Y845342D01*
X1750542Y845467D01*
X1750250Y845675D01*
X1750042Y845967D01*
X1750000Y846258D01*
X1750083Y846550D01*
X1750292Y846758D01*
G01X1752500Y849067D02*
X1751958Y849150D01*
X1751500Y849275D01*
X1751083Y849442D01*
X1750625Y849650D01*
X1750000Y849983D01*
Y848317D01*
G01X1731319Y838500D02*
Y852500D01*
G01X1761643Y1012831D02*
X1766693D01*
Y1111531D01*
X1791343D01*
Y927131D01*
X1766693D01*
Y985831D01*
X1761643D01*
Y1012831D01*
G01X1754767Y951292D02*
X1754517Y951417D01*
X1754225Y951500D01*
X1753892D01*
X1753517Y951375D01*
X1753225Y951167D01*
X1753017Y950917D01*
X1752850Y950500D01*
X1752808Y950125D01*
X1752892Y949750D01*
X1753017Y949500D01*
X1753267Y949250D01*
X1753558Y949083D01*
X1753850Y949000D01*
X1754142D01*
X1754433Y949083D01*
X1754683Y949208D01*
X1754892Y949375D01*
G01X1756950Y949000D02*
Y951500D01*
X1756450Y951000D01*
G01Y949000D02*
X1757450D01*
G01X1759133Y949375D02*
X1759383Y949167D01*
X1759675Y949042D01*
X1760050Y949000D01*
X1760425Y949083D01*
X1760717Y949250D01*
X1760925Y949542D01*
X1760967Y949875D01*
X1760883Y950208D01*
X1760675Y950417D01*
X1760383Y950583D01*
X1760092Y950625D01*
X1759800Y950583D01*
X1759425Y950417D01*
X1759550Y951500D01*
X1760675D01*
G01X1762442Y949292D02*
X1762733Y949083D01*
X1763067Y949000D01*
X1763400Y949083D01*
X1763692Y949333D01*
X1763900Y949708D01*
X1763983Y950083D01*
Y950542D01*
X1763900Y950917D01*
X1763692Y951250D01*
X1763442Y951417D01*
X1763150Y951500D01*
X1762817Y951417D01*
X1762567Y951250D01*
X1762400Y951000D01*
X1762317Y950667D01*
X1762400Y950375D01*
X1762608Y950083D01*
X1762858Y949917D01*
X1763150Y949875D01*
X1763483Y949958D01*
X1763733Y950167D01*
X1763983Y950542D01*
G01X1801000Y950517D02*
X1798500D01*
Y951558D01*
X1798625Y951892D01*
X1798792Y952100D01*
X1799125Y952183D01*
X1799458Y952100D01*
X1799667Y951850D01*
X1799792Y951558D01*
Y950517D01*
G01Y951558D02*
X1801000Y952183D01*
G01X1800500Y953533D02*
X1800792Y953783D01*
X1800958Y954117D01*
X1801000Y954492D01*
X1800958Y954825D01*
X1800750Y955158D01*
X1800500Y955367D01*
X1800250Y955408D01*
X1799958Y955325D01*
X1799750Y955033D01*
X1799667Y954742D01*
Y954367D01*
G01Y954742D02*
X1799542Y954992D01*
X1799333Y955200D01*
X1799083Y955283D01*
X1798833Y955200D01*
X1798625Y954992D01*
X1798500Y954617D01*
X1798542Y954242D01*
X1798708Y953867D01*
G01X1798917Y956758D02*
X1798667Y957008D01*
X1798542Y957300D01*
X1798500Y957633D01*
X1798583Y958050D01*
X1798792Y958342D01*
X1799042Y958425D01*
X1799292Y958383D01*
X1799500Y958217D01*
X1799917Y957383D01*
X1800208Y957008D01*
X1800625Y956758D01*
X1801000Y956675D01*
Y958425D01*
G01Y961150D02*
X1798500D01*
X1800292Y959608D01*
Y961692D01*
G01X1815000Y947017D02*
X1812500D01*
Y948058D01*
X1812625Y948392D01*
X1812792Y948600D01*
X1813125Y948683D01*
X1813458Y948600D01*
X1813667Y948350D01*
X1813792Y948058D01*
Y947017D01*
G01Y948058D02*
X1815000Y948683D01*
G01X1814500Y950033D02*
X1814792Y950283D01*
X1814958Y950617D01*
X1815000Y950992D01*
X1814958Y951325D01*
X1814750Y951658D01*
X1814500Y951867D01*
X1814250Y951908D01*
X1813958Y951825D01*
X1813750Y951533D01*
X1813667Y951242D01*
Y950867D01*
G01Y951242D02*
X1813542Y951492D01*
X1813333Y951700D01*
X1813083Y951783D01*
X1812833Y951700D01*
X1812625Y951492D01*
X1812500Y951117D01*
X1812542Y950742D01*
X1812708Y950367D01*
G01X1812917Y953258D02*
X1812667Y953508D01*
X1812542Y953800D01*
X1812500Y954133D01*
X1812583Y954550D01*
X1812792Y954842D01*
X1813042Y954925D01*
X1813292Y954883D01*
X1813500Y954717D01*
X1813917Y953883D01*
X1814208Y953508D01*
X1814625Y953258D01*
X1815000Y953175D01*
Y954925D01*
G01X1813958Y956358D02*
X1813667Y956650D01*
X1813500Y956900D01*
X1813417Y957233D01*
X1813500Y957525D01*
X1813667Y957733D01*
X1813917Y957900D01*
X1814208Y957942D01*
X1814458Y957900D01*
X1814708Y957733D01*
X1814917Y957483D01*
X1815000Y957192D01*
X1814917Y956858D01*
X1814667Y956567D01*
X1814292Y956400D01*
X1813875Y956358D01*
X1813333Y956442D01*
X1813042Y956567D01*
X1812750Y956775D01*
X1812542Y957067D01*
X1812500Y957358D01*
X1812583Y957650D01*
X1812792Y957858D01*
G01X1797000Y950517D02*
X1794500D01*
Y951558D01*
X1794625Y951892D01*
X1794792Y952100D01*
X1795125Y952183D01*
X1795458Y952100D01*
X1795667Y951850D01*
X1795792Y951558D01*
Y950517D01*
G01Y951558D02*
X1797000Y952183D01*
G01X1796500Y953533D02*
X1796792Y953783D01*
X1796958Y954117D01*
X1797000Y954492D01*
X1796958Y954825D01*
X1796750Y955158D01*
X1796500Y955367D01*
X1796250Y955408D01*
X1795958Y955325D01*
X1795750Y955033D01*
X1795667Y954742D01*
Y954367D01*
G01Y954742D02*
X1795542Y954992D01*
X1795333Y955200D01*
X1795083Y955283D01*
X1794833Y955200D01*
X1794625Y954992D01*
X1794500Y954617D01*
X1794542Y954242D01*
X1794708Y953867D01*
G01X1794917Y956758D02*
X1794667Y957008D01*
X1794542Y957300D01*
X1794500Y957633D01*
X1794583Y958050D01*
X1794792Y958342D01*
X1795042Y958425D01*
X1795292Y958383D01*
X1795500Y958217D01*
X1795917Y957383D01*
X1796208Y957008D01*
X1796625Y956758D01*
X1797000Y956675D01*
Y958425D01*
G01Y960567D02*
X1796458Y960650D01*
X1796000Y960775D01*
X1795583Y960942D01*
X1795125Y961150D01*
X1794500Y961483D01*
Y959817D01*
G01X1816967Y921000D02*
Y923500D01*
X1818008D01*
X1818342Y923375D01*
X1818550Y923208D01*
X1818633Y922875D01*
X1818550Y922542D01*
X1818300Y922333D01*
X1818008Y922208D01*
X1816967D01*
G01X1818008D02*
X1818633Y921000D01*
G01X1820900D02*
Y923500D01*
X1820400Y923000D01*
G01Y921000D02*
X1821400D01*
G01X1824000D02*
Y923500D01*
X1823500Y923000D01*
G01Y921000D02*
X1824500D01*
G01X1826183Y921500D02*
X1826433Y921208D01*
X1826767Y921042D01*
X1827142Y921000D01*
X1827475Y921042D01*
X1827808Y921250D01*
X1828017Y921500D01*
X1828058Y921750D01*
X1827975Y922042D01*
X1827683Y922250D01*
X1827392Y922333D01*
X1827017D01*
G01X1827392D02*
X1827642Y922458D01*
X1827850Y922667D01*
X1827933Y922917D01*
X1827850Y923167D01*
X1827642Y923375D01*
X1827267Y923500D01*
X1826892Y923458D01*
X1826517Y923292D01*
G01X1829283Y921375D02*
X1829533Y921167D01*
X1829825Y921042D01*
X1830200Y921000D01*
X1830575Y921083D01*
X1830867Y921250D01*
X1831075Y921542D01*
X1831117Y921875D01*
X1831033Y922208D01*
X1830825Y922417D01*
X1830533Y922583D01*
X1830242Y922625D01*
X1829950Y922583D01*
X1829575Y922417D01*
X1829700Y923500D01*
X1830825D01*
G01X1819263Y917725D02*
X1815263D01*
Y910325D01*
G01X1799967Y924000D02*
Y926500D01*
X1801008D01*
X1801342Y926375D01*
X1801550Y926208D01*
X1801633Y925875D01*
X1801550Y925542D01*
X1801300Y925333D01*
X1801008Y925208D01*
X1799967D01*
G01X1801008D02*
X1801633Y924000D01*
G01X1803900D02*
Y926500D01*
X1803400Y926000D01*
G01Y924000D02*
X1804400D01*
G01X1807000D02*
Y926500D01*
X1806500Y926000D01*
G01Y924000D02*
X1807500D01*
G01X1809183Y924500D02*
X1809433Y924208D01*
X1809767Y924042D01*
X1810142Y924000D01*
X1810475Y924042D01*
X1810808Y924250D01*
X1811017Y924500D01*
X1811058Y924750D01*
X1810975Y925042D01*
X1810683Y925250D01*
X1810392Y925333D01*
X1810017D01*
G01X1810392D02*
X1810642Y925458D01*
X1810850Y925667D01*
X1810933Y925917D01*
X1810850Y926167D01*
X1810642Y926375D01*
X1810267Y926500D01*
X1809892Y926458D01*
X1809517Y926292D01*
G01X1813200Y924000D02*
X1813492Y924042D01*
X1813825Y924167D01*
X1814033Y924375D01*
X1814117Y924667D01*
X1814033Y924958D01*
X1813783Y925208D01*
X1813408Y925333D01*
X1812992D01*
X1812742Y925417D01*
X1812533Y925625D01*
X1812450Y925917D01*
X1812575Y926208D01*
X1812867Y926417D01*
X1813200Y926500D01*
X1813533Y926417D01*
X1813825Y926208D01*
X1813950Y925917D01*
X1813867Y925625D01*
X1813658Y925417D01*
X1813408Y925333D01*
X1812992D01*
X1812617Y925208D01*
X1812367Y924958D01*
X1812283Y924667D01*
X1812367Y924375D01*
X1812575Y924167D01*
X1812908Y924042D01*
X1813200Y924000D01*
G01X1814963Y906025D02*
Y910025D01*
X1807563D01*
G01X1799967Y916000D02*
Y918500D01*
X1801008D01*
X1801342Y918375D01*
X1801550Y918208D01*
X1801633Y917875D01*
X1801550Y917542D01*
X1801300Y917333D01*
X1801008Y917208D01*
X1799967D01*
G01X1801008D02*
X1801633Y916000D01*
G01X1803900D02*
Y918500D01*
X1803400Y918000D01*
G01Y916000D02*
X1804400D01*
G01X1807000D02*
Y918500D01*
X1806500Y918000D01*
G01Y916000D02*
X1807500D01*
G01X1810600D02*
Y918500D01*
X1809058Y916708D01*
X1811142D01*
G01X1812408Y918083D02*
X1812658Y918333D01*
X1812950Y918458D01*
X1813283Y918500D01*
X1813700Y918417D01*
X1813992Y918208D01*
X1814075Y917958D01*
X1814033Y917708D01*
X1813867Y917500D01*
X1813033Y917083D01*
X1812658Y916792D01*
X1812408Y916375D01*
X1812325Y916000D01*
X1814075D01*
G01X1814055Y897023D02*
Y901023D01*
X1806655D01*
G01X1783967Y917000D02*
Y919500D01*
X1785008D01*
X1785342Y919375D01*
X1785550Y919208D01*
X1785633Y918875D01*
X1785550Y918542D01*
X1785300Y918333D01*
X1785008Y918208D01*
X1783967D01*
G01X1785008D02*
X1785633Y917000D01*
G01X1787900D02*
Y919500D01*
X1787400Y919000D01*
G01Y917000D02*
X1788400D01*
G01X1791000D02*
Y919500D01*
X1790500Y919000D01*
G01Y917000D02*
X1791500D01*
G01X1794600D02*
Y919500D01*
X1793058Y917708D01*
X1795142D01*
G01X1796283Y917375D02*
X1796533Y917167D01*
X1796825Y917042D01*
X1797200Y917000D01*
X1797575Y917083D01*
X1797867Y917250D01*
X1798075Y917542D01*
X1798117Y917875D01*
X1798033Y918208D01*
X1797825Y918417D01*
X1797533Y918583D01*
X1797242Y918625D01*
X1796950Y918583D01*
X1796575Y918417D01*
X1796700Y919500D01*
X1797825D01*
G01X1806597Y899301D02*
Y903301D01*
X1799197D01*
G01X1783967Y921000D02*
Y923500D01*
X1785008D01*
X1785342Y923375D01*
X1785550Y923208D01*
X1785633Y922875D01*
X1785550Y922542D01*
X1785300Y922333D01*
X1785008Y922208D01*
X1783967D01*
G01X1785008D02*
X1785633Y921000D01*
G01X1787900D02*
Y923500D01*
X1787400Y923000D01*
G01Y921000D02*
X1788400D01*
G01X1791000D02*
Y923500D01*
X1790500Y923000D01*
G01Y921000D02*
X1791500D01*
G01X1794600D02*
Y923500D01*
X1793058Y921708D01*
X1795142D01*
G01X1796408Y922042D02*
X1796700Y922333D01*
X1796950Y922500D01*
X1797283Y922583D01*
X1797575Y922500D01*
X1797783Y922333D01*
X1797950Y922083D01*
X1797992Y921792D01*
X1797950Y921542D01*
X1797783Y921292D01*
X1797533Y921083D01*
X1797242Y921000D01*
X1796908Y921083D01*
X1796617Y921333D01*
X1796450Y921708D01*
X1796408Y922125D01*
X1796492Y922667D01*
X1796617Y922958D01*
X1796825Y923250D01*
X1797117Y923458D01*
X1797408Y923500D01*
X1797700Y923417D01*
X1797908Y923208D01*
G01X1799195Y907367D02*
Y903367D01*
X1806595D01*
G01X1767467Y912500D02*
Y915000D01*
X1768508D01*
X1768842Y914875D01*
X1769050Y914708D01*
X1769133Y914375D01*
X1769050Y914042D01*
X1768800Y913833D01*
X1768508Y913708D01*
X1767467D01*
G01X1768508D02*
X1769133Y912500D01*
G01X1771400D02*
Y915000D01*
X1770900Y914500D01*
G01Y912500D02*
X1771900D01*
G01X1774500D02*
Y915000D01*
X1774000Y914500D01*
G01Y912500D02*
X1775000D01*
G01X1778100D02*
Y915000D01*
X1776558Y913208D01*
X1778642D01*
G01X1780700Y912500D02*
X1780992Y912542D01*
X1781325Y912667D01*
X1781533Y912875D01*
X1781617Y913167D01*
X1781533Y913458D01*
X1781283Y913708D01*
X1780908Y913833D01*
X1780492D01*
X1780242Y913917D01*
X1780033Y914125D01*
X1779950Y914417D01*
X1780075Y914708D01*
X1780367Y914917D01*
X1780700Y915000D01*
X1781033Y914917D01*
X1781325Y914708D01*
X1781450Y914417D01*
X1781367Y914125D01*
X1781158Y913917D01*
X1780908Y913833D01*
X1780492D01*
X1780117Y913708D01*
X1779867Y913458D01*
X1779783Y913167D01*
X1779867Y912875D01*
X1780075Y912667D01*
X1780408Y912542D01*
X1780700Y912500D01*
G01X1791763Y907325D02*
Y911325D01*
X1784363D01*
G01X1767967Y891500D02*
Y894000D01*
X1769008D01*
X1769342Y893875D01*
X1769550Y893708D01*
X1769633Y893375D01*
X1769550Y893042D01*
X1769300Y892833D01*
X1769008Y892708D01*
X1767967D01*
G01X1769008D02*
X1769633Y891500D01*
G01X1771900D02*
Y894000D01*
X1771400Y893500D01*
G01Y891500D02*
X1772400D01*
G01X1775000D02*
Y894000D01*
X1774500Y893500D01*
G01Y891500D02*
X1775500D01*
G01X1777183Y891875D02*
X1777433Y891667D01*
X1777725Y891542D01*
X1778100Y891500D01*
X1778475Y891583D01*
X1778767Y891750D01*
X1778975Y892042D01*
X1779017Y892375D01*
X1778933Y892708D01*
X1778725Y892917D01*
X1778433Y893083D01*
X1778142Y893125D01*
X1777850Y893083D01*
X1777475Y892917D01*
X1777600Y894000D01*
X1778725D01*
G01X1781200Y891500D02*
Y894000D01*
X1780700Y893500D01*
G01Y891500D02*
X1781700D01*
G01X1790463Y890025D02*
Y894025D01*
X1783063D01*
G01X1777402Y896492D02*
X1774902D01*
Y897533D01*
X1775027Y897867D01*
X1775194Y898075D01*
X1775527Y898158D01*
X1775860Y898075D01*
X1776069Y897825D01*
X1776194Y897533D01*
Y896492D01*
G01Y897533D02*
X1777402Y898158D01*
G01Y900425D02*
X1774902D01*
X1775402Y899925D01*
G01X1777402D02*
Y900925D01*
G01Y903525D02*
X1774902D01*
X1775402Y903025D01*
G01X1777402D02*
Y904025D01*
G01X1777027Y905708D02*
X1777235Y905958D01*
X1777360Y906250D01*
X1777402Y906625D01*
X1777319Y907000D01*
X1777152Y907292D01*
X1776860Y907500D01*
X1776527Y907542D01*
X1776194Y907458D01*
X1775985Y907250D01*
X1775819Y906958D01*
X1775777Y906667D01*
X1775819Y906375D01*
X1775985Y906000D01*
X1774902Y906125D01*
Y907250D01*
G01X1775319Y908933D02*
X1775069Y909183D01*
X1774944Y909475D01*
X1774902Y909808D01*
X1774985Y910225D01*
X1775194Y910517D01*
X1775444Y910600D01*
X1775694Y910558D01*
X1775902Y910392D01*
X1776319Y909558D01*
X1776610Y909183D01*
X1777027Y908933D01*
X1777402Y908850D01*
Y910600D01*
G01X1790563Y899825D02*
X1794563D01*
Y907225D01*
G01X1781539Y896547D02*
X1779039D01*
Y897588D01*
X1779164Y897922D01*
X1779331Y898130D01*
X1779664Y898213D01*
X1779997Y898130D01*
X1780206Y897880D01*
X1780331Y897588D01*
Y896547D01*
G01Y897588D02*
X1781539Y898213D01*
G01Y900480D02*
X1779039D01*
X1779539Y899980D01*
G01X1781539D02*
Y900980D01*
G01Y903580D02*
X1779039D01*
X1779539Y903080D01*
G01X1781539D02*
Y904080D01*
G01X1781164Y905763D02*
X1781372Y906013D01*
X1781497Y906305D01*
X1781539Y906680D01*
X1781456Y907055D01*
X1781289Y907347D01*
X1780997Y907555D01*
X1780664Y907597D01*
X1780331Y907513D01*
X1780122Y907305D01*
X1779956Y907013D01*
X1779914Y906722D01*
X1779956Y906430D01*
X1780122Y906055D01*
X1779039Y906180D01*
Y907305D01*
G01X1781039Y908863D02*
X1781331Y909113D01*
X1781497Y909447D01*
X1781539Y909822D01*
X1781497Y910155D01*
X1781289Y910488D01*
X1781039Y910697D01*
X1780789Y910738D01*
X1780497Y910655D01*
X1780289Y910363D01*
X1780206Y910072D01*
Y909697D01*
G01Y910072D02*
X1780081Y910322D01*
X1779872Y910530D01*
X1779622Y910613D01*
X1779372Y910530D01*
X1779164Y910322D01*
X1779039Y909947D01*
X1779081Y909572D01*
X1779247Y909197D01*
G01X1794700Y899880D02*
X1798700D01*
Y907280D01*
G01X1801767Y922292D02*
X1801517Y922417D01*
X1801225Y922500D01*
X1800892D01*
X1800517Y922375D01*
X1800225Y922167D01*
X1800017Y921917D01*
X1799850Y921500D01*
X1799808Y921125D01*
X1799892Y920750D01*
X1800017Y920500D01*
X1800267Y920250D01*
X1800558Y920083D01*
X1800850Y920000D01*
X1801142D01*
X1801433Y920083D01*
X1801683Y920208D01*
X1801892Y920375D01*
G01X1803158Y921042D02*
X1803450Y921333D01*
X1803700Y921500D01*
X1804033Y921583D01*
X1804325Y921500D01*
X1804533Y921333D01*
X1804700Y921083D01*
X1804742Y920792D01*
X1804700Y920542D01*
X1804533Y920292D01*
X1804283Y920083D01*
X1803992Y920000D01*
X1803658Y920083D01*
X1803367Y920333D01*
X1803200Y920708D01*
X1803158Y921125D01*
X1803242Y921667D01*
X1803367Y921958D01*
X1803575Y922250D01*
X1803867Y922458D01*
X1804158Y922500D01*
X1804450Y922417D01*
X1804658Y922208D01*
G01X1806133Y920375D02*
X1806383Y920167D01*
X1806675Y920042D01*
X1807050Y920000D01*
X1807425Y920083D01*
X1807717Y920250D01*
X1807925Y920542D01*
X1807967Y920875D01*
X1807883Y921208D01*
X1807675Y921417D01*
X1807383Y921583D01*
X1807092Y921625D01*
X1806800Y921583D01*
X1806425Y921417D01*
X1806550Y922500D01*
X1807675D01*
G01X1809442Y920292D02*
X1809733Y920083D01*
X1810067Y920000D01*
X1810400Y920083D01*
X1810692Y920333D01*
X1810900Y920708D01*
X1810983Y921083D01*
Y921542D01*
X1810900Y921917D01*
X1810692Y922250D01*
X1810442Y922417D01*
X1810150Y922500D01*
X1809817Y922417D01*
X1809567Y922250D01*
X1809400Y922000D01*
X1809317Y921667D01*
X1809400Y921375D01*
X1809608Y921083D01*
X1809858Y920917D01*
X1810150Y920875D01*
X1810483Y920958D01*
X1810733Y921167D01*
X1810983Y921542D01*
G01X1816000Y874467D02*
X1813500D01*
Y875508D01*
X1813625Y875842D01*
X1813792Y876050D01*
X1814125Y876133D01*
X1814458Y876050D01*
X1814667Y875800D01*
X1814792Y875508D01*
Y874467D01*
G01Y875508D02*
X1816000Y876133D01*
G01Y878400D02*
X1813500D01*
X1814000Y877900D01*
G01X1816000D02*
Y878900D01*
G01Y881500D02*
X1813500D01*
X1814000Y881000D01*
G01X1816000D02*
Y882000D01*
G01X1815500Y883683D02*
X1815792Y883933D01*
X1815958Y884267D01*
X1816000Y884642D01*
X1815958Y884975D01*
X1815750Y885308D01*
X1815500Y885517D01*
X1815250Y885558D01*
X1814958Y885475D01*
X1814750Y885183D01*
X1814667Y884892D01*
Y884517D01*
G01Y884892D02*
X1814542Y885142D01*
X1814333Y885350D01*
X1814083Y885433D01*
X1813833Y885350D01*
X1813625Y885142D01*
X1813500Y884767D01*
X1813542Y884392D01*
X1813708Y884017D01*
G01X1815708Y886992D02*
X1815917Y887283D01*
X1816000Y887617D01*
X1815917Y887950D01*
X1815667Y888242D01*
X1815292Y888450D01*
X1814917Y888533D01*
X1814458D01*
X1814083Y888450D01*
X1813750Y888242D01*
X1813583Y887992D01*
X1813500Y887700D01*
X1813583Y887367D01*
X1813750Y887117D01*
X1814000Y886950D01*
X1814333Y886867D01*
X1814625Y886950D01*
X1814917Y887158D01*
X1815083Y887408D01*
X1815125Y887700D01*
X1815042Y888033D01*
X1814833Y888283D01*
X1814458Y888533D01*
G01X1767767Y882792D02*
X1767517Y882917D01*
X1767225Y883000D01*
X1766892D01*
X1766517Y882875D01*
X1766225Y882667D01*
X1766017Y882417D01*
X1765850Y882000D01*
X1765808Y881625D01*
X1765892Y881250D01*
X1766017Y881000D01*
X1766267Y880750D01*
X1766558Y880583D01*
X1766850Y880500D01*
X1767142D01*
X1767433Y880583D01*
X1767683Y880708D01*
X1767892Y880875D01*
G01X1769158Y881542D02*
X1769450Y881833D01*
X1769700Y882000D01*
X1770033Y882083D01*
X1770325Y882000D01*
X1770533Y881833D01*
X1770700Y881583D01*
X1770742Y881292D01*
X1770700Y881042D01*
X1770533Y880792D01*
X1770283Y880583D01*
X1769992Y880500D01*
X1769658Y880583D01*
X1769367Y880833D01*
X1769200Y881208D01*
X1769158Y881625D01*
X1769242Y882167D01*
X1769367Y882458D01*
X1769575Y882750D01*
X1769867Y882958D01*
X1770158Y883000D01*
X1770450Y882917D01*
X1770658Y882708D01*
G01X1772133Y880875D02*
X1772383Y880667D01*
X1772675Y880542D01*
X1773050Y880500D01*
X1773425Y880583D01*
X1773717Y880750D01*
X1773925Y881042D01*
X1773967Y881375D01*
X1773883Y881708D01*
X1773675Y881917D01*
X1773383Y882083D01*
X1773092Y882125D01*
X1772800Y882083D01*
X1772425Y881917D01*
X1772550Y883000D01*
X1773675D01*
G01X1776067Y880500D02*
X1776150Y881042D01*
X1776275Y881500D01*
X1776442Y881917D01*
X1776650Y882375D01*
X1776983Y883000D01*
X1775317D01*
G01X1767767Y876792D02*
X1767517Y876917D01*
X1767225Y877000D01*
X1766892D01*
X1766517Y876875D01*
X1766225Y876667D01*
X1766017Y876417D01*
X1765850Y876000D01*
X1765808Y875625D01*
X1765892Y875250D01*
X1766017Y875000D01*
X1766267Y874750D01*
X1766558Y874583D01*
X1766850Y874500D01*
X1767142D01*
X1767433Y874583D01*
X1767683Y874708D01*
X1767892Y874875D01*
G01X1769158Y875542D02*
X1769450Y875833D01*
X1769700Y876000D01*
X1770033Y876083D01*
X1770325Y876000D01*
X1770533Y875833D01*
X1770700Y875583D01*
X1770742Y875292D01*
X1770700Y875042D01*
X1770533Y874792D01*
X1770283Y874583D01*
X1769992Y874500D01*
X1769658Y874583D01*
X1769367Y874833D01*
X1769200Y875208D01*
X1769158Y875625D01*
X1769242Y876167D01*
X1769367Y876458D01*
X1769575Y876750D01*
X1769867Y876958D01*
X1770158Y877000D01*
X1770450Y876917D01*
X1770658Y876708D01*
G01X1772133Y874875D02*
X1772383Y874667D01*
X1772675Y874542D01*
X1773050Y874500D01*
X1773425Y874583D01*
X1773717Y874750D01*
X1773925Y875042D01*
X1773967Y875375D01*
X1773883Y875708D01*
X1773675Y875917D01*
X1773383Y876083D01*
X1773092Y876125D01*
X1772800Y876083D01*
X1772425Y875917D01*
X1772550Y877000D01*
X1773675D01*
G01X1776150Y874500D02*
X1776442Y874542D01*
X1776775Y874667D01*
X1776983Y874875D01*
X1777067Y875167D01*
X1776983Y875458D01*
X1776733Y875708D01*
X1776358Y875833D01*
X1775942D01*
X1775692Y875917D01*
X1775483Y876125D01*
X1775400Y876417D01*
X1775525Y876708D01*
X1775817Y876917D01*
X1776150Y877000D01*
X1776483Y876917D01*
X1776775Y876708D01*
X1776900Y876417D01*
X1776817Y876125D01*
X1776608Y875917D01*
X1776358Y875833D01*
X1775942D01*
X1775567Y875708D01*
X1775317Y875458D01*
X1775233Y875167D01*
X1775317Y874875D01*
X1775525Y874667D01*
X1775858Y874542D01*
X1776150Y874500D01*
G01X1798917Y865000D02*
Y867500D01*
X1799958D01*
X1800292Y867375D01*
X1800500Y867208D01*
X1800583Y866875D01*
X1800500Y866542D01*
X1800250Y866333D01*
X1799958Y866208D01*
X1798917D01*
G01X1799958D02*
X1800583Y865000D01*
G01X1802850D02*
Y867500D01*
X1802350Y867000D01*
G01Y865000D02*
X1803350D01*
G01X1805950D02*
Y867500D01*
X1805450Y867000D01*
G01Y865000D02*
X1806450D01*
G01X1809550D02*
Y867500D01*
X1808008Y865708D01*
X1810092D01*
G01X1811233Y865500D02*
X1811483Y865208D01*
X1811817Y865042D01*
X1812192Y865000D01*
X1812525Y865042D01*
X1812858Y865250D01*
X1813067Y865500D01*
X1813108Y865750D01*
X1813025Y866042D01*
X1812733Y866250D01*
X1812442Y866333D01*
X1812067D01*
G01X1812442D02*
X1812692Y866458D01*
X1812900Y866667D01*
X1812983Y866917D01*
X1812900Y867167D01*
X1812692Y867375D01*
X1812317Y867500D01*
X1811942Y867458D01*
X1811567Y867292D01*
G01X1812694Y868875D02*
X1807494D01*
G01X1812694Y875875D02*
X1804894D01*
G01X1812694Y868875D02*
Y875875D01*
G01X1799294Y868875D02*
X1807994D01*
G01X1799294Y875875D02*
Y868875D01*
G01X1805694Y875875D02*
X1799294D01*
G01X1754767Y955292D02*
X1754517Y955417D01*
X1754225Y955500D01*
X1753892D01*
X1753517Y955375D01*
X1753225Y955167D01*
X1753017Y954917D01*
X1752850Y954500D01*
X1752808Y954125D01*
X1752892Y953750D01*
X1753017Y953500D01*
X1753267Y953250D01*
X1753558Y953083D01*
X1753850Y953000D01*
X1754142D01*
X1754433Y953083D01*
X1754683Y953208D01*
X1754892Y953375D01*
G01X1756950Y953000D02*
Y955500D01*
X1756450Y955000D01*
G01Y953000D02*
X1757450D01*
G01X1759133Y953375D02*
X1759383Y953167D01*
X1759675Y953042D01*
X1760050Y953000D01*
X1760425Y953083D01*
X1760717Y953250D01*
X1760925Y953542D01*
X1760967Y953875D01*
X1760883Y954208D01*
X1760675Y954417D01*
X1760383Y954583D01*
X1760092Y954625D01*
X1759800Y954583D01*
X1759425Y954417D01*
X1759550Y955500D01*
X1760675D01*
G01X1763150Y953000D02*
X1763442Y953042D01*
X1763775Y953167D01*
X1763983Y953375D01*
X1764067Y953667D01*
X1763983Y953958D01*
X1763733Y954208D01*
X1763358Y954333D01*
X1762942D01*
X1762692Y954417D01*
X1762483Y954625D01*
X1762400Y954917D01*
X1762525Y955208D01*
X1762817Y955417D01*
X1763150Y955500D01*
X1763483Y955417D01*
X1763775Y955208D01*
X1763900Y954917D01*
X1763817Y954625D01*
X1763608Y954417D01*
X1763358Y954333D01*
X1762942D01*
X1762567Y954208D01*
X1762317Y953958D01*
X1762233Y953667D01*
X1762317Y953375D01*
X1762525Y953167D01*
X1762858Y953042D01*
X1763150Y953000D01*
G01X1761708Y1037267D02*
X1761583Y1037017D01*
X1761500Y1036725D01*
Y1036392D01*
X1761625Y1036017D01*
X1761833Y1035725D01*
X1762083Y1035517D01*
X1762500Y1035350D01*
X1762875Y1035308D01*
X1763250Y1035392D01*
X1763500Y1035517D01*
X1763750Y1035767D01*
X1763917Y1036058D01*
X1764000Y1036350D01*
Y1036642D01*
X1763917Y1036933D01*
X1763792Y1037183D01*
X1763625Y1037392D01*
G01X1764000Y1039450D02*
X1761500D01*
X1762000Y1038950D01*
G01X1764000D02*
Y1039950D01*
G01X1762958Y1041758D02*
X1762667Y1042050D01*
X1762500Y1042300D01*
X1762417Y1042633D01*
X1762500Y1042925D01*
X1762667Y1043133D01*
X1762917Y1043300D01*
X1763208Y1043342D01*
X1763458Y1043300D01*
X1763708Y1043133D01*
X1763917Y1042883D01*
X1764000Y1042592D01*
X1763917Y1042258D01*
X1763667Y1041967D01*
X1763292Y1041800D01*
X1762875Y1041758D01*
X1762333Y1041842D01*
X1762042Y1041967D01*
X1761750Y1042175D01*
X1761542Y1042467D01*
X1761500Y1042758D01*
X1761583Y1043050D01*
X1761792Y1043258D01*
G01X1764000Y1045567D02*
X1763458Y1045650D01*
X1763000Y1045775D01*
X1762583Y1045942D01*
X1762125Y1046150D01*
X1761500Y1046483D01*
Y1044817D01*
G01X1792708Y989767D02*
X1792583Y989517D01*
X1792500Y989225D01*
Y988892D01*
X1792625Y988517D01*
X1792833Y988225D01*
X1793083Y988017D01*
X1793500Y987850D01*
X1793875Y987808D01*
X1794250Y987892D01*
X1794500Y988017D01*
X1794750Y988267D01*
X1794917Y988558D01*
X1795000Y988850D01*
Y989142D01*
X1794917Y989433D01*
X1794792Y989683D01*
X1794625Y989892D01*
G01X1795000Y991950D02*
X1792500D01*
X1793000Y991450D01*
G01X1795000D02*
Y992450D01*
G01X1793958Y994258D02*
X1793667Y994550D01*
X1793500Y994800D01*
X1793417Y995133D01*
X1793500Y995425D01*
X1793667Y995633D01*
X1793917Y995800D01*
X1794208Y995842D01*
X1794458Y995800D01*
X1794708Y995633D01*
X1794917Y995383D01*
X1795000Y995092D01*
X1794917Y994758D01*
X1794667Y994467D01*
X1794292Y994300D01*
X1793875Y994258D01*
X1793333Y994342D01*
X1793042Y994467D01*
X1792750Y994675D01*
X1792542Y994967D01*
X1792500Y995258D01*
X1792583Y995550D01*
X1792792Y995758D01*
G01X1795000Y998150D02*
X1794958Y998442D01*
X1794833Y998775D01*
X1794625Y998983D01*
X1794333Y999067D01*
X1794042Y998983D01*
X1793792Y998733D01*
X1793667Y998358D01*
Y997942D01*
X1793583Y997692D01*
X1793375Y997483D01*
X1793083Y997400D01*
X1792792Y997525D01*
X1792583Y997817D01*
X1792500Y998150D01*
X1792583Y998483D01*
X1792792Y998775D01*
X1793083Y998900D01*
X1793375Y998817D01*
X1793583Y998608D01*
X1793667Y998358D01*
Y997942D01*
X1793792Y997567D01*
X1794042Y997317D01*
X1794333Y997233D01*
X1794625Y997317D01*
X1794833Y997525D01*
X1794958Y997858D01*
X1795000Y998150D01*
G01X1813968Y1017059D02*
X1813718Y1017184D01*
X1813426Y1017267D01*
X1813093D01*
X1812718Y1017142D01*
X1812426Y1016934D01*
X1812218Y1016684D01*
X1812051Y1016267D01*
X1812009Y1015892D01*
X1812093Y1015517D01*
X1812218Y1015267D01*
X1812468Y1015017D01*
X1812759Y1014850D01*
X1813051Y1014767D01*
X1813343D01*
X1813634Y1014850D01*
X1813884Y1014975D01*
X1814093Y1015142D01*
G01X1816151Y1014767D02*
Y1017267D01*
X1815651Y1016767D01*
G01Y1014767D02*
X1816651D01*
G01X1818459Y1015809D02*
X1818751Y1016100D01*
X1819001Y1016267D01*
X1819334Y1016350D01*
X1819626Y1016267D01*
X1819834Y1016100D01*
X1820001Y1015850D01*
X1820043Y1015559D01*
X1820001Y1015309D01*
X1819834Y1015059D01*
X1819584Y1014850D01*
X1819293Y1014767D01*
X1818959Y1014850D01*
X1818668Y1015100D01*
X1818501Y1015475D01*
X1818459Y1015892D01*
X1818543Y1016434D01*
X1818668Y1016725D01*
X1818876Y1017017D01*
X1819168Y1017225D01*
X1819459Y1017267D01*
X1819751Y1017184D01*
X1819959Y1016975D01*
G01X1821643Y1015059D02*
X1821934Y1014850D01*
X1822268Y1014767D01*
X1822601Y1014850D01*
X1822893Y1015100D01*
X1823101Y1015475D01*
X1823184Y1015850D01*
Y1016309D01*
X1823101Y1016684D01*
X1822893Y1017017D01*
X1822643Y1017184D01*
X1822351Y1017267D01*
X1822018Y1017184D01*
X1821768Y1017017D01*
X1821601Y1016767D01*
X1821518Y1016434D01*
X1821601Y1016142D01*
X1821809Y1015850D01*
X1822059Y1015684D01*
X1822351Y1015642D01*
X1822684Y1015725D01*
X1822934Y1015934D01*
X1823184Y1016309D01*
G01X1759500Y1035517D02*
X1757000D01*
Y1036558D01*
X1757125Y1036892D01*
X1757292Y1037100D01*
X1757625Y1037183D01*
X1757958Y1037100D01*
X1758167Y1036850D01*
X1758292Y1036558D01*
Y1035517D01*
G01Y1036558D02*
X1759500Y1037183D01*
G01X1759000Y1038533D02*
X1759292Y1038783D01*
X1759458Y1039117D01*
X1759500Y1039492D01*
X1759458Y1039825D01*
X1759250Y1040158D01*
X1759000Y1040367D01*
X1758750Y1040408D01*
X1758458Y1040325D01*
X1758250Y1040033D01*
X1758167Y1039742D01*
Y1039367D01*
G01Y1039742D02*
X1758042Y1039992D01*
X1757833Y1040200D01*
X1757583Y1040283D01*
X1757333Y1040200D01*
X1757125Y1039992D01*
X1757000Y1039617D01*
X1757042Y1039242D01*
X1757208Y1038867D01*
G01X1759500Y1042550D02*
X1757000D01*
X1757500Y1042050D01*
G01X1759500D02*
Y1043050D01*
G01X1759208Y1044942D02*
X1759417Y1045233D01*
X1759500Y1045567D01*
X1759417Y1045900D01*
X1759167Y1046192D01*
X1758792Y1046400D01*
X1758417Y1046483D01*
X1757958D01*
X1757583Y1046400D01*
X1757250Y1046192D01*
X1757083Y1045942D01*
X1757000Y1045650D01*
X1757083Y1045317D01*
X1757250Y1045067D01*
X1757500Y1044900D01*
X1757833Y1044817D01*
X1758125Y1044900D01*
X1758417Y1045108D01*
X1758583Y1045358D01*
X1758625Y1045650D01*
X1758542Y1045983D01*
X1758333Y1046233D01*
X1757958Y1046483D01*
G01X1757300Y1026400D02*
X1761300D01*
Y1033800D01*
G01X1795000Y974017D02*
X1792500D01*
Y975058D01*
X1792625Y975392D01*
X1792792Y975600D01*
X1793125Y975683D01*
X1793458Y975600D01*
X1793667Y975350D01*
X1793792Y975058D01*
Y974017D01*
G01Y975058D02*
X1795000Y975683D01*
G01X1794500Y977033D02*
X1794792Y977283D01*
X1794958Y977617D01*
X1795000Y977992D01*
X1794958Y978325D01*
X1794750Y978658D01*
X1794500Y978867D01*
X1794250Y978908D01*
X1793958Y978825D01*
X1793750Y978533D01*
X1793667Y978242D01*
Y977867D01*
G01Y978242D02*
X1793542Y978492D01*
X1793333Y978700D01*
X1793083Y978783D01*
X1792833Y978700D01*
X1792625Y978492D01*
X1792500Y978117D01*
X1792542Y977742D01*
X1792708Y977367D01*
G01X1792917Y980258D02*
X1792667Y980508D01*
X1792542Y980800D01*
X1792500Y981133D01*
X1792583Y981550D01*
X1792792Y981842D01*
X1793042Y981925D01*
X1793292Y981883D01*
X1793500Y981717D01*
X1793917Y980883D01*
X1794208Y980508D01*
X1794625Y980258D01*
X1795000Y980175D01*
Y981925D01*
G01X1794500Y983233D02*
X1794792Y983483D01*
X1794958Y983817D01*
X1795000Y984192D01*
X1794958Y984525D01*
X1794750Y984858D01*
X1794500Y985067D01*
X1794250Y985108D01*
X1793958Y985025D01*
X1793750Y984733D01*
X1793667Y984442D01*
Y984067D01*
G01Y984442D02*
X1793542Y984692D01*
X1793333Y984900D01*
X1793083Y984983D01*
X1792833Y984900D01*
X1792625Y984692D01*
X1792500Y984317D01*
X1792542Y983942D01*
X1792708Y983567D01*
G01X1798300Y984200D02*
Y980200D01*
X1805700D01*
G01X1806500Y955300D02*
X1810500D01*
Y962700D01*
G01X1816500Y955300D02*
X1820500D01*
Y962700D01*
G01X1806000D02*
X1802000D01*
Y955300D01*
G01X1813517Y1011161D02*
Y1013661D01*
X1814558D01*
X1814892Y1013536D01*
X1815100Y1013369D01*
X1815183Y1013036D01*
X1815100Y1012703D01*
X1814850Y1012494D01*
X1814558Y1012369D01*
X1813517D01*
G01X1814558D02*
X1815183Y1011161D01*
G01X1816533Y1011661D02*
X1816783Y1011369D01*
X1817117Y1011203D01*
X1817492Y1011161D01*
X1817825Y1011203D01*
X1818158Y1011411D01*
X1818367Y1011661D01*
X1818408Y1011911D01*
X1818325Y1012203D01*
X1818033Y1012411D01*
X1817742Y1012494D01*
X1817367D01*
G01X1817742D02*
X1817992Y1012619D01*
X1818200Y1012828D01*
X1818283Y1013078D01*
X1818200Y1013328D01*
X1817992Y1013536D01*
X1817617Y1013661D01*
X1817242Y1013619D01*
X1816867Y1013453D01*
G01X1819758Y1013244D02*
X1820008Y1013494D01*
X1820300Y1013619D01*
X1820633Y1013661D01*
X1821050Y1013578D01*
X1821342Y1013369D01*
X1821425Y1013119D01*
X1821383Y1012869D01*
X1821217Y1012661D01*
X1820383Y1012244D01*
X1820008Y1011953D01*
X1819758Y1011536D01*
X1819675Y1011161D01*
X1821425D01*
G01X1822942Y1011453D02*
X1823233Y1011244D01*
X1823567Y1011161D01*
X1823900Y1011244D01*
X1824192Y1011494D01*
X1824400Y1011869D01*
X1824483Y1012244D01*
Y1012703D01*
X1824400Y1013078D01*
X1824192Y1013411D01*
X1823942Y1013578D01*
X1823650Y1013661D01*
X1823317Y1013578D01*
X1823067Y1013411D01*
X1822900Y1013161D01*
X1822817Y1012828D01*
X1822900Y1012536D01*
X1823108Y1012244D01*
X1823358Y1012078D01*
X1823650Y1012036D01*
X1823983Y1012119D01*
X1824233Y1012328D01*
X1824483Y1012703D01*
G01X1808017Y985000D02*
Y987500D01*
X1809058D01*
X1809392Y987375D01*
X1809600Y987208D01*
X1809683Y986875D01*
X1809600Y986542D01*
X1809350Y986333D01*
X1809058Y986208D01*
X1808017D01*
G01X1809058D02*
X1809683Y985000D01*
G01X1811033Y985500D02*
X1811283Y985208D01*
X1811617Y985042D01*
X1811992Y985000D01*
X1812325Y985042D01*
X1812658Y985250D01*
X1812867Y985500D01*
X1812908Y985750D01*
X1812825Y986042D01*
X1812533Y986250D01*
X1812242Y986333D01*
X1811867D01*
G01X1812242D02*
X1812492Y986458D01*
X1812700Y986667D01*
X1812783Y986917D01*
X1812700Y987167D01*
X1812492Y987375D01*
X1812117Y987500D01*
X1811742Y987458D01*
X1811367Y987292D01*
G01X1814133Y985500D02*
X1814383Y985208D01*
X1814717Y985042D01*
X1815092Y985000D01*
X1815425Y985042D01*
X1815758Y985250D01*
X1815967Y985500D01*
X1816008Y985750D01*
X1815925Y986042D01*
X1815633Y986250D01*
X1815342Y986333D01*
X1814967D01*
G01X1815342D02*
X1815592Y986458D01*
X1815800Y986667D01*
X1815883Y986917D01*
X1815800Y987167D01*
X1815592Y987375D01*
X1815217Y987500D01*
X1814842Y987458D01*
X1814467Y987292D01*
G01X1818150Y987500D02*
X1817817Y987417D01*
X1817567Y987208D01*
X1817400Y986958D01*
X1817275Y986625D01*
X1817233Y986250D01*
X1817275Y985875D01*
X1817400Y985542D01*
X1817567Y985292D01*
X1817817Y985083D01*
X1818150Y985000D01*
X1818483Y985083D01*
X1818733Y985292D01*
X1818900Y985542D01*
X1819025Y985875D01*
X1819067Y986250D01*
X1819025Y986625D01*
X1818900Y986958D01*
X1818733Y987208D01*
X1818483Y987417D01*
X1818150Y987500D01*
G01X1816500Y967800D02*
X1820500D01*
Y975200D01*
G01X1801900Y1012000D02*
X1801567Y1012042D01*
X1801275Y1012208D01*
X1801025Y1012458D01*
X1800858Y1012750D01*
X1800775Y1013083D01*
Y1013417D01*
X1800858Y1013750D01*
X1801025Y1014042D01*
X1801275Y1014292D01*
X1801567Y1014458D01*
X1801900Y1014500D01*
X1802233Y1014458D01*
X1802525Y1014292D01*
X1802775Y1014042D01*
X1802942Y1013750D01*
X1803025Y1013417D01*
Y1013083D01*
X1802942Y1012750D01*
X1802775Y1012458D01*
X1802525Y1012208D01*
X1802233Y1012042D01*
X1801900Y1012000D01*
G01X1802233Y1012667D02*
X1802733Y1012000D01*
G01X1804083Y1012500D02*
X1804333Y1012208D01*
X1804667Y1012042D01*
X1805042Y1012000D01*
X1805375Y1012042D01*
X1805708Y1012250D01*
X1805917Y1012500D01*
X1805958Y1012750D01*
X1805875Y1013042D01*
X1805583Y1013250D01*
X1805292Y1013333D01*
X1804917D01*
G01X1805292D02*
X1805542Y1013458D01*
X1805750Y1013667D01*
X1805833Y1013917D01*
X1805750Y1014167D01*
X1805542Y1014375D01*
X1805167Y1014500D01*
X1804792Y1014458D01*
X1804417Y1014292D01*
G01X1808100Y1012000D02*
X1808392Y1012042D01*
X1808725Y1012167D01*
X1808933Y1012375D01*
X1809017Y1012667D01*
X1808933Y1012958D01*
X1808683Y1013208D01*
X1808308Y1013333D01*
X1807892D01*
X1807642Y1013417D01*
X1807433Y1013625D01*
X1807350Y1013917D01*
X1807475Y1014208D01*
X1807767Y1014417D01*
X1808100Y1014500D01*
X1808433Y1014417D01*
X1808725Y1014208D01*
X1808850Y1013917D01*
X1808767Y1013625D01*
X1808558Y1013417D01*
X1808308Y1013333D01*
X1807892D01*
X1807517Y1013208D01*
X1807267Y1012958D01*
X1807183Y1012667D01*
X1807267Y1012375D01*
X1807475Y1012167D01*
X1807808Y1012042D01*
X1808100Y1012000D01*
G01X1817000Y1010200D02*
X1815200Y1008100D01*
X1813000Y1010200D01*
G01X1809400Y1010300D02*
Y991100D01*
X1820600D01*
Y1010300D01*
X1809400D01*
Y1009900D01*
G01X1811800Y1037500D02*
X1813900Y1035700D01*
X1811800Y1033500D01*
G01X1811700Y1029900D02*
X1830900D01*
Y1041100D01*
X1811700D01*
Y1029900D01*
X1812100D01*
G01X1750500Y1035517D02*
X1748000D01*
Y1036558D01*
X1748125Y1036892D01*
X1748292Y1037100D01*
X1748625Y1037183D01*
X1748958Y1037100D01*
X1749167Y1036850D01*
X1749292Y1036558D01*
Y1035517D01*
G01Y1036558D02*
X1750500Y1037183D01*
G01X1750000Y1038533D02*
X1750292Y1038783D01*
X1750458Y1039117D01*
X1750500Y1039492D01*
X1750458Y1039825D01*
X1750250Y1040158D01*
X1750000Y1040367D01*
X1749750Y1040408D01*
X1749458Y1040325D01*
X1749250Y1040033D01*
X1749167Y1039742D01*
Y1039367D01*
G01Y1039742D02*
X1749042Y1039992D01*
X1748833Y1040200D01*
X1748583Y1040283D01*
X1748333Y1040200D01*
X1748125Y1039992D01*
X1748000Y1039617D01*
X1748042Y1039242D01*
X1748208Y1038867D01*
G01X1748417Y1041758D02*
X1748167Y1042008D01*
X1748042Y1042300D01*
X1748000Y1042633D01*
X1748083Y1043050D01*
X1748292Y1043342D01*
X1748542Y1043425D01*
X1748792Y1043383D01*
X1749000Y1043217D01*
X1749417Y1042383D01*
X1749708Y1042008D01*
X1750125Y1041758D01*
X1750500Y1041675D01*
Y1043425D01*
G01Y1045650D02*
X1748000D01*
X1748500Y1045150D01*
G01X1750500D02*
Y1046150D01*
G01X1801000Y1041700D02*
Y1047200D01*
G01X1809000Y1041700D02*
X1801000D01*
G01X1809000Y1047200D02*
Y1041700D01*
G01X1807983Y978000D02*
Y980500D01*
X1808817D01*
X1809150Y980375D01*
X1809400Y980208D01*
X1809608Y979958D01*
X1809775Y979667D01*
X1809817Y979250D01*
X1809775Y978833D01*
X1809608Y978542D01*
X1809400Y978292D01*
X1809150Y978125D01*
X1808817Y978000D01*
X1807983D01*
G01X1812000D02*
Y980500D01*
X1811500Y980000D01*
G01Y978000D02*
X1812500D01*
G01X1815100Y980500D02*
X1814767Y980417D01*
X1814517Y980208D01*
X1814350Y979958D01*
X1814225Y979625D01*
X1814183Y979250D01*
X1814225Y978875D01*
X1814350Y978542D01*
X1814517Y978292D01*
X1814767Y978083D01*
X1815100Y978000D01*
X1815433Y978083D01*
X1815683Y978292D01*
X1815850Y978542D01*
X1815975Y978875D01*
X1816017Y979250D01*
X1815975Y979625D01*
X1815850Y979958D01*
X1815683Y980208D01*
X1815433Y980417D01*
X1815100Y980500D01*
G01X1833000Y976000D02*
X1816900D01*
G01Y983000D02*
X1833000D01*
G01X1816900Y976000D02*
Y983000D01*
G01X1796000Y964400D02*
X1795958Y964067D01*
X1795792Y963775D01*
X1795542Y963525D01*
X1795250Y963358D01*
X1794917Y963275D01*
X1794583D01*
X1794250Y963358D01*
X1793958Y963525D01*
X1793708Y963775D01*
X1793542Y964067D01*
X1793500Y964400D01*
X1793542Y964733D01*
X1793708Y965025D01*
X1793958Y965275D01*
X1794250Y965442D01*
X1794583Y965525D01*
X1794917D01*
X1795250Y965442D01*
X1795542Y965275D01*
X1795792Y965025D01*
X1795958Y964733D01*
X1796000Y964400D01*
G01X1795333Y964733D02*
X1796000Y965233D01*
G01X1795500Y966583D02*
X1795792Y966833D01*
X1795958Y967167D01*
X1796000Y967542D01*
X1795958Y967875D01*
X1795750Y968208D01*
X1795500Y968417D01*
X1795250Y968458D01*
X1794958Y968375D01*
X1794750Y968083D01*
X1794667Y967792D01*
Y967417D01*
G01Y967792D02*
X1794542Y968042D01*
X1794333Y968250D01*
X1794083Y968333D01*
X1793833Y968250D01*
X1793625Y968042D01*
X1793500Y967667D01*
X1793542Y967292D01*
X1793708Y966917D01*
G01X1795708Y969892D02*
X1795917Y970183D01*
X1796000Y970517D01*
X1795917Y970850D01*
X1795667Y971142D01*
X1795292Y971350D01*
X1794917Y971433D01*
X1794458D01*
X1794083Y971350D01*
X1793750Y971142D01*
X1793583Y970892D01*
X1793500Y970600D01*
X1793583Y970267D01*
X1793750Y970017D01*
X1794000Y969850D01*
X1794333Y969767D01*
X1794625Y969850D01*
X1794917Y970058D01*
X1795083Y970308D01*
X1795125Y970600D01*
X1795042Y970933D01*
X1794833Y971183D01*
X1794458Y971433D01*
G01X1797300Y975200D02*
Y963800D01*
G01X1810700Y975200D02*
X1797300D01*
G01X1810700Y963800D02*
Y975200D01*
G01X1797300Y963800D02*
X1810700D01*
G01X1793517Y1036500D02*
Y1039000D01*
X1794558D01*
X1794892Y1038875D01*
X1795100Y1038708D01*
X1795183Y1038375D01*
X1795100Y1038042D01*
X1794850Y1037833D01*
X1794558Y1037708D01*
X1793517D01*
G01X1794558D02*
X1795183Y1036500D01*
G01X1796533Y1037000D02*
X1796783Y1036708D01*
X1797117Y1036542D01*
X1797492Y1036500D01*
X1797825Y1036542D01*
X1798158Y1036750D01*
X1798367Y1037000D01*
X1798408Y1037250D01*
X1798325Y1037542D01*
X1798033Y1037750D01*
X1797742Y1037833D01*
X1797367D01*
G01X1797742D02*
X1797992Y1037958D01*
X1798200Y1038167D01*
X1798283Y1038417D01*
X1798200Y1038667D01*
X1797992Y1038875D01*
X1797617Y1039000D01*
X1797242Y1038958D01*
X1796867Y1038792D01*
G01X1800550Y1036500D02*
Y1039000D01*
X1800050Y1038500D01*
G01Y1036500D02*
X1801050D01*
G01X1803650D02*
X1803942Y1036542D01*
X1804275Y1036667D01*
X1804483Y1036875D01*
X1804567Y1037167D01*
X1804483Y1037458D01*
X1804233Y1037708D01*
X1803858Y1037833D01*
X1803442D01*
X1803192Y1037917D01*
X1802983Y1038125D01*
X1802900Y1038417D01*
X1803025Y1038708D01*
X1803317Y1038917D01*
X1803650Y1039000D01*
X1803983Y1038917D01*
X1804275Y1038708D01*
X1804400Y1038417D01*
X1804317Y1038125D01*
X1804108Y1037917D01*
X1803858Y1037833D01*
X1803442D01*
X1803067Y1037708D01*
X1802817Y1037458D01*
X1802733Y1037167D01*
X1802817Y1036875D01*
X1803025Y1036667D01*
X1803358Y1036542D01*
X1803650Y1036500D01*
G01X1810300Y1035500D02*
Y1027500D01*
X1792700D01*
Y1035500D01*
X1810300D01*
G01X1766275Y1114500D02*
Y1117000D01*
G01X1768025D02*
Y1114500D01*
G01Y1115750D02*
X1766275D01*
G01X1769333Y1114500D02*
Y1117000D01*
X1770167D01*
X1770500Y1116875D01*
X1770750Y1116708D01*
X1770958Y1116458D01*
X1771125Y1116167D01*
X1771167Y1115750D01*
X1771125Y1115333D01*
X1770958Y1115042D01*
X1770750Y1114792D01*
X1770500Y1114625D01*
X1770167Y1114500D01*
X1769333D01*
G01X1772433D02*
Y1117000D01*
X1773267D01*
X1773600Y1116875D01*
X1773850Y1116708D01*
X1774058Y1116458D01*
X1774225Y1116167D01*
X1774267Y1115750D01*
X1774225Y1115333D01*
X1774058Y1115042D01*
X1773850Y1114792D01*
X1773600Y1114625D01*
X1773267Y1114500D01*
X1772433D01*
G01X1775575Y1114833D02*
X1775908Y1114625D01*
X1776283Y1114500D01*
X1776617D01*
X1776950Y1114625D01*
X1777200Y1114833D01*
X1777325Y1115125D01*
X1777242Y1115417D01*
X1777033Y1115667D01*
X1776658Y1115833D01*
X1776158Y1115917D01*
X1775867Y1116083D01*
X1775742Y1116375D01*
X1775825Y1116667D01*
X1776033Y1116875D01*
X1776325Y1117000D01*
X1776617D01*
X1776908Y1116917D01*
X1777158Y1116708D01*
G01X1778508Y1114500D02*
X1779550Y1117000D01*
X1780592Y1114500D01*
G01X1780217Y1115375D02*
X1778883D01*
G01X1781775Y1114833D02*
X1782108Y1114625D01*
X1782483Y1114500D01*
X1782817D01*
X1783150Y1114625D01*
X1783400Y1114833D01*
X1783525Y1115125D01*
X1783442Y1115417D01*
X1783233Y1115667D01*
X1782858Y1115833D01*
X1782358Y1115917D01*
X1782067Y1116083D01*
X1781942Y1116375D01*
X1782025Y1116667D01*
X1782233Y1116875D01*
X1782525Y1117000D01*
X1782817D01*
X1783108Y1116917D01*
X1783358Y1116708D01*
G01X1785750Y1114500D02*
Y1117000D01*
X1785250Y1116500D01*
G01Y1114500D02*
X1786250D01*
G01X1788850Y1117000D02*
X1788517Y1116917D01*
X1788267Y1116708D01*
X1788100Y1116458D01*
X1787975Y1116125D01*
X1787933Y1115750D01*
X1787975Y1115375D01*
X1788100Y1115042D01*
X1788267Y1114792D01*
X1788517Y1114583D01*
X1788850Y1114500D01*
X1789183Y1114583D01*
X1789433Y1114792D01*
X1789600Y1115042D01*
X1789725Y1115375D01*
X1789767Y1115750D01*
X1789725Y1116125D01*
X1789600Y1116458D01*
X1789433Y1116708D01*
X1789183Y1116917D01*
X1788850Y1117000D01*
G01X1793708Y1062267D02*
X1793583Y1062017D01*
X1793500Y1061725D01*
Y1061392D01*
X1793625Y1061017D01*
X1793833Y1060725D01*
X1794083Y1060517D01*
X1794500Y1060350D01*
X1794875Y1060308D01*
X1795250Y1060392D01*
X1795500Y1060517D01*
X1795750Y1060767D01*
X1795917Y1061058D01*
X1796000Y1061350D01*
Y1061642D01*
X1795917Y1061933D01*
X1795792Y1062183D01*
X1795625Y1062392D01*
G01X1796000Y1064450D02*
X1793500D01*
X1794000Y1063950D01*
G01X1796000D02*
Y1064950D01*
G01X1794958Y1066758D02*
X1794667Y1067050D01*
X1794500Y1067300D01*
X1794417Y1067633D01*
X1794500Y1067925D01*
X1794667Y1068133D01*
X1794917Y1068300D01*
X1795208Y1068342D01*
X1795458Y1068300D01*
X1795708Y1068133D01*
X1795917Y1067883D01*
X1796000Y1067592D01*
X1795917Y1067258D01*
X1795667Y1066967D01*
X1795292Y1066800D01*
X1794875Y1066758D01*
X1794333Y1066842D01*
X1794042Y1066967D01*
X1793750Y1067175D01*
X1793542Y1067467D01*
X1793500Y1067758D01*
X1793583Y1068050D01*
X1793792Y1068258D01*
G01X1793500Y1070650D02*
X1793583Y1070317D01*
X1793792Y1070067D01*
X1794042Y1069900D01*
X1794375Y1069775D01*
X1794750Y1069733D01*
X1795125Y1069775D01*
X1795458Y1069900D01*
X1795708Y1070067D01*
X1795917Y1070317D01*
X1796000Y1070650D01*
X1795917Y1070983D01*
X1795708Y1071233D01*
X1795458Y1071400D01*
X1795125Y1071525D01*
X1794750Y1071567D01*
X1794375Y1071525D01*
X1794042Y1071400D01*
X1793792Y1071233D01*
X1793583Y1070983D01*
X1793500Y1070650D01*
G01X1793708Y1094767D02*
X1793583Y1094517D01*
X1793500Y1094225D01*
Y1093892D01*
X1793625Y1093517D01*
X1793833Y1093225D01*
X1794083Y1093017D01*
X1794500Y1092850D01*
X1794875Y1092808D01*
X1795250Y1092892D01*
X1795500Y1093017D01*
X1795750Y1093267D01*
X1795917Y1093558D01*
X1796000Y1093850D01*
Y1094142D01*
X1795917Y1094433D01*
X1795792Y1094683D01*
X1795625Y1094892D01*
G01X1796000Y1096950D02*
X1793500D01*
X1794000Y1096450D01*
G01X1796000D02*
Y1097450D01*
G01X1794958Y1099258D02*
X1794667Y1099550D01*
X1794500Y1099800D01*
X1794417Y1100133D01*
X1794500Y1100425D01*
X1794667Y1100633D01*
X1794917Y1100800D01*
X1795208Y1100842D01*
X1795458Y1100800D01*
X1795708Y1100633D01*
X1795917Y1100383D01*
X1796000Y1100092D01*
X1795917Y1099758D01*
X1795667Y1099467D01*
X1795292Y1099300D01*
X1794875Y1099258D01*
X1794333Y1099342D01*
X1794042Y1099467D01*
X1793750Y1099675D01*
X1793542Y1099967D01*
X1793500Y1100258D01*
X1793583Y1100550D01*
X1793792Y1100758D01*
G01X1794958Y1102358D02*
X1794667Y1102650D01*
X1794500Y1102900D01*
X1794417Y1103233D01*
X1794500Y1103525D01*
X1794667Y1103733D01*
X1794917Y1103900D01*
X1795208Y1103942D01*
X1795458Y1103900D01*
X1795708Y1103733D01*
X1795917Y1103483D01*
X1796000Y1103192D01*
X1795917Y1102858D01*
X1795667Y1102567D01*
X1795292Y1102400D01*
X1794875Y1102358D01*
X1794333Y1102442D01*
X1794042Y1102567D01*
X1793750Y1102775D01*
X1793542Y1103067D01*
X1793500Y1103358D01*
X1793583Y1103650D01*
X1793792Y1103858D01*
G01X1745350Y1068500D02*
Y1066000D01*
G01X1744392Y1068500D02*
X1746308D01*
G01X1747617Y1066000D02*
Y1068500D01*
X1748617D01*
X1748950Y1068375D01*
X1749200Y1068083D01*
X1749283Y1067750D01*
X1749200Y1067417D01*
X1748992Y1067167D01*
X1748617Y1067042D01*
X1747617D01*
G01X1751467Y1066000D02*
X1751550Y1066542D01*
X1751675Y1067000D01*
X1751842Y1067417D01*
X1752050Y1067875D01*
X1752383Y1068500D01*
X1750717D01*
G01X1754650Y1066000D02*
Y1068500D01*
X1754150Y1068000D01*
G01Y1066000D02*
X1755150D01*
G01X1798208Y1061267D02*
X1798083Y1061017D01*
X1798000Y1060725D01*
Y1060392D01*
X1798125Y1060017D01*
X1798333Y1059725D01*
X1798583Y1059517D01*
X1799000Y1059350D01*
X1799375Y1059308D01*
X1799750Y1059392D01*
X1800000Y1059517D01*
X1800250Y1059767D01*
X1800417Y1060058D01*
X1800500Y1060350D01*
Y1060642D01*
X1800417Y1060933D01*
X1800292Y1061183D01*
X1800125Y1061392D01*
G01X1800500Y1063450D02*
X1798000D01*
X1798500Y1062950D01*
G01X1800500D02*
Y1063950D01*
G01X1799458Y1065758D02*
X1799167Y1066050D01*
X1799000Y1066300D01*
X1798917Y1066633D01*
X1799000Y1066925D01*
X1799167Y1067133D01*
X1799417Y1067300D01*
X1799708Y1067342D01*
X1799958Y1067300D01*
X1800208Y1067133D01*
X1800417Y1066883D01*
X1800500Y1066592D01*
X1800417Y1066258D01*
X1800167Y1065967D01*
X1799792Y1065800D01*
X1799375Y1065758D01*
X1798833Y1065842D01*
X1798542Y1065967D01*
X1798250Y1066175D01*
X1798042Y1066467D01*
X1798000Y1066758D01*
X1798083Y1067050D01*
X1798292Y1067258D01*
G01X1800500Y1069650D02*
X1798000D01*
X1798500Y1069150D01*
G01X1800500D02*
Y1070150D01*
G01X1809000Y1059300D02*
Y1053800D01*
G01X1801000Y1059300D02*
X1809000D01*
G01X1801000Y1053800D02*
Y1059300D01*
G01X1808017Y1070500D02*
Y1073000D01*
X1809058D01*
X1809392Y1072875D01*
X1809600Y1072708D01*
X1809683Y1072375D01*
X1809600Y1072042D01*
X1809350Y1071833D01*
X1809058Y1071708D01*
X1808017D01*
G01X1809058D02*
X1809683Y1070500D01*
G01X1811033Y1071000D02*
X1811283Y1070708D01*
X1811617Y1070542D01*
X1811992Y1070500D01*
X1812325Y1070542D01*
X1812658Y1070750D01*
X1812867Y1071000D01*
X1812908Y1071250D01*
X1812825Y1071542D01*
X1812533Y1071750D01*
X1812242Y1071833D01*
X1811867D01*
G01X1812242D02*
X1812492Y1071958D01*
X1812700Y1072167D01*
X1812783Y1072417D01*
X1812700Y1072667D01*
X1812492Y1072875D01*
X1812117Y1073000D01*
X1811742Y1072958D01*
X1811367Y1072792D01*
G01X1814258Y1072583D02*
X1814508Y1072833D01*
X1814800Y1072958D01*
X1815133Y1073000D01*
X1815550Y1072917D01*
X1815842Y1072708D01*
X1815925Y1072458D01*
X1815883Y1072208D01*
X1815717Y1072000D01*
X1814883Y1071583D01*
X1814508Y1071292D01*
X1814258Y1070875D01*
X1814175Y1070500D01*
X1815925D01*
G01X1818150Y1073000D02*
X1817817Y1072917D01*
X1817567Y1072708D01*
X1817400Y1072458D01*
X1817275Y1072125D01*
X1817233Y1071750D01*
X1817275Y1071375D01*
X1817400Y1071042D01*
X1817567Y1070792D01*
X1817817Y1070583D01*
X1818150Y1070500D01*
X1818483Y1070583D01*
X1818733Y1070792D01*
X1818900Y1071042D01*
X1819025Y1071375D01*
X1819067Y1071750D01*
X1819025Y1072125D01*
X1818900Y1072458D01*
X1818733Y1072708D01*
X1818483Y1072917D01*
X1818150Y1073000D01*
G01X1819000Y1069300D02*
Y1061300D01*
X1801400D01*
Y1069300D01*
X1819000D01*
G01X1800547Y1094767D02*
X1800422Y1094517D01*
X1800339Y1094225D01*
Y1093892D01*
X1800464Y1093517D01*
X1800672Y1093225D01*
X1800922Y1093017D01*
X1801339Y1092850D01*
X1801714Y1092808D01*
X1802089Y1092892D01*
X1802339Y1093017D01*
X1802589Y1093267D01*
X1802756Y1093558D01*
X1802839Y1093850D01*
Y1094142D01*
X1802756Y1094433D01*
X1802631Y1094683D01*
X1802464Y1094892D01*
G01X1802839Y1096950D02*
X1800339D01*
X1800839Y1096450D01*
G01X1802839D02*
Y1097450D01*
G01X1801797Y1099258D02*
X1801506Y1099550D01*
X1801339Y1099800D01*
X1801256Y1100133D01*
X1801339Y1100425D01*
X1801506Y1100633D01*
X1801756Y1100800D01*
X1802047Y1100842D01*
X1802297Y1100800D01*
X1802547Y1100633D01*
X1802756Y1100383D01*
X1802839Y1100092D01*
X1802756Y1099758D01*
X1802506Y1099467D01*
X1802131Y1099300D01*
X1801714Y1099258D01*
X1801172Y1099342D01*
X1800881Y1099467D01*
X1800589Y1099675D01*
X1800381Y1099967D01*
X1800339Y1100258D01*
X1800422Y1100550D01*
X1800631Y1100758D01*
G01X1802839Y1103650D02*
X1800339D01*
X1802131Y1102108D01*
Y1104192D01*
G01X1808547Y1094767D02*
X1808422Y1094517D01*
X1808339Y1094225D01*
Y1093892D01*
X1808464Y1093517D01*
X1808672Y1093225D01*
X1808922Y1093017D01*
X1809339Y1092850D01*
X1809714Y1092808D01*
X1810089Y1092892D01*
X1810339Y1093017D01*
X1810589Y1093267D01*
X1810756Y1093558D01*
X1810839Y1093850D01*
Y1094142D01*
X1810756Y1094433D01*
X1810631Y1094683D01*
X1810464Y1094892D01*
G01X1810839Y1096950D02*
X1808339D01*
X1808839Y1096450D01*
G01X1810839D02*
Y1097450D01*
G01X1809797Y1099258D02*
X1809506Y1099550D01*
X1809339Y1099800D01*
X1809256Y1100133D01*
X1809339Y1100425D01*
X1809506Y1100633D01*
X1809756Y1100800D01*
X1810047Y1100842D01*
X1810297Y1100800D01*
X1810547Y1100633D01*
X1810756Y1100383D01*
X1810839Y1100092D01*
X1810756Y1099758D01*
X1810506Y1099467D01*
X1810131Y1099300D01*
X1809714Y1099258D01*
X1809172Y1099342D01*
X1808881Y1099467D01*
X1808589Y1099675D01*
X1808381Y1099967D01*
X1808339Y1100258D01*
X1808422Y1100550D01*
X1808631Y1100758D01*
G01X1810464Y1102233D02*
X1810672Y1102483D01*
X1810797Y1102775D01*
X1810839Y1103150D01*
X1810756Y1103525D01*
X1810589Y1103817D01*
X1810297Y1104025D01*
X1809964Y1104067D01*
X1809631Y1103983D01*
X1809422Y1103775D01*
X1809256Y1103483D01*
X1809214Y1103192D01*
X1809256Y1102900D01*
X1809422Y1102525D01*
X1808339Y1102650D01*
Y1103775D01*
G01X1771093Y1430253D02*
X1770843Y1430378D01*
X1770551Y1430461D01*
X1770218D01*
X1769843Y1430336D01*
X1769551Y1430128D01*
X1769343Y1429878D01*
X1769176Y1429461D01*
X1769134Y1429086D01*
X1769218Y1428711D01*
X1769343Y1428461D01*
X1769593Y1428211D01*
X1769884Y1428044D01*
X1770176Y1427961D01*
X1770468D01*
X1770759Y1428044D01*
X1771009Y1428169D01*
X1771218Y1428336D01*
G01X1772359D02*
X1772609Y1428128D01*
X1772901Y1428003D01*
X1773276Y1427961D01*
X1773651Y1428044D01*
X1773943Y1428211D01*
X1774151Y1428503D01*
X1774193Y1428836D01*
X1774109Y1429169D01*
X1773901Y1429378D01*
X1773609Y1429544D01*
X1773318Y1429586D01*
X1773026Y1429544D01*
X1772651Y1429378D01*
X1772776Y1430461D01*
X1773901D01*
G01X1775459Y1428461D02*
X1775709Y1428169D01*
X1776043Y1428003D01*
X1776418Y1427961D01*
X1776751Y1428003D01*
X1777084Y1428211D01*
X1777293Y1428461D01*
X1777334Y1428711D01*
X1777251Y1429003D01*
X1776959Y1429211D01*
X1776668Y1429294D01*
X1776293D01*
G01X1776668D02*
X1776918Y1429419D01*
X1777126Y1429628D01*
X1777209Y1429878D01*
X1777126Y1430128D01*
X1776918Y1430336D01*
X1776543Y1430461D01*
X1776168Y1430419D01*
X1775793Y1430253D01*
G01X1779393Y1427961D02*
X1779476Y1428503D01*
X1779601Y1428961D01*
X1779768Y1429378D01*
X1779976Y1429836D01*
X1780309Y1430461D01*
X1778643D01*
G01X1727776Y1402100D02*
X1727443Y1402142D01*
X1727151Y1402308D01*
X1726901Y1402558D01*
X1726734Y1402850D01*
X1726651Y1403183D01*
Y1403517D01*
X1726734Y1403850D01*
X1726901Y1404142D01*
X1727151Y1404392D01*
X1727443Y1404558D01*
X1727776Y1404600D01*
X1728109Y1404558D01*
X1728401Y1404392D01*
X1728651Y1404142D01*
X1728818Y1403850D01*
X1728901Y1403517D01*
Y1403183D01*
X1728818Y1402850D01*
X1728651Y1402558D01*
X1728401Y1402308D01*
X1728109Y1402142D01*
X1727776Y1402100D01*
G01X1728109Y1402767D02*
X1728609Y1402100D01*
G01X1730876D02*
Y1404600D01*
X1730376Y1404100D01*
G01Y1402100D02*
X1731376D01*
G01X1733059Y1402600D02*
X1733309Y1402308D01*
X1733643Y1402142D01*
X1734018Y1402100D01*
X1734351Y1402142D01*
X1734684Y1402350D01*
X1734893Y1402600D01*
X1734934Y1402850D01*
X1734851Y1403142D01*
X1734559Y1403350D01*
X1734268Y1403433D01*
X1733893D01*
G01X1734268D02*
X1734518Y1403558D01*
X1734726Y1403767D01*
X1734809Y1404017D01*
X1734726Y1404267D01*
X1734518Y1404475D01*
X1734143Y1404600D01*
X1733768Y1404558D01*
X1733393Y1404392D01*
G01X1736159Y1402600D02*
X1736409Y1402308D01*
X1736743Y1402142D01*
X1737118Y1402100D01*
X1737451Y1402142D01*
X1737784Y1402350D01*
X1737993Y1402600D01*
X1738034Y1402850D01*
X1737951Y1403142D01*
X1737659Y1403350D01*
X1737368Y1403433D01*
X1736993D01*
G01X1737368D02*
X1737618Y1403558D01*
X1737826Y1403767D01*
X1737909Y1404017D01*
X1737826Y1404267D01*
X1737618Y1404475D01*
X1737243Y1404600D01*
X1736868Y1404558D01*
X1736493Y1404392D01*
G01X1767393Y1422292D02*
X1767143Y1422417D01*
X1766851Y1422500D01*
X1766518D01*
X1766143Y1422375D01*
X1765851Y1422167D01*
X1765643Y1421917D01*
X1765476Y1421500D01*
X1765434Y1421125D01*
X1765518Y1420750D01*
X1765643Y1420500D01*
X1765893Y1420250D01*
X1766184Y1420083D01*
X1766476Y1420000D01*
X1766768D01*
X1767059Y1420083D01*
X1767309Y1420208D01*
X1767518Y1420375D01*
G01X1768659D02*
X1768909Y1420167D01*
X1769201Y1420042D01*
X1769576Y1420000D01*
X1769951Y1420083D01*
X1770243Y1420250D01*
X1770451Y1420542D01*
X1770493Y1420875D01*
X1770409Y1421208D01*
X1770201Y1421417D01*
X1769909Y1421583D01*
X1769618Y1421625D01*
X1769326Y1421583D01*
X1768951Y1421417D01*
X1769076Y1422500D01*
X1770201D01*
G01X1771759Y1420500D02*
X1772009Y1420208D01*
X1772343Y1420042D01*
X1772718Y1420000D01*
X1773051Y1420042D01*
X1773384Y1420250D01*
X1773593Y1420500D01*
X1773634Y1420750D01*
X1773551Y1421042D01*
X1773259Y1421250D01*
X1772968Y1421333D01*
X1772593D01*
G01X1772968D02*
X1773218Y1421458D01*
X1773426Y1421667D01*
X1773509Y1421917D01*
X1773426Y1422167D01*
X1773218Y1422375D01*
X1772843Y1422500D01*
X1772468Y1422458D01*
X1772093Y1422292D01*
G01X1774859Y1420375D02*
X1775109Y1420167D01*
X1775401Y1420042D01*
X1775776Y1420000D01*
X1776151Y1420083D01*
X1776443Y1420250D01*
X1776651Y1420542D01*
X1776693Y1420875D01*
X1776609Y1421208D01*
X1776401Y1421417D01*
X1776109Y1421583D01*
X1775818Y1421625D01*
X1775526Y1421583D01*
X1775151Y1421417D01*
X1775276Y1422500D01*
X1776401D01*
G01X1749640Y1427146D02*
X1743440D01*
Y1414746D01*
X1749640D01*
G01X1755640D02*
X1761840D01*
Y1427146D01*
X1755640D01*
G01X1770841Y1434362D02*
X1770591Y1434487D01*
X1770299Y1434570D01*
X1769966D01*
X1769591Y1434445D01*
X1769299Y1434237D01*
X1769091Y1433987D01*
X1768924Y1433570D01*
X1768882Y1433195D01*
X1768966Y1432820D01*
X1769091Y1432570D01*
X1769341Y1432320D01*
X1769632Y1432153D01*
X1769924Y1432070D01*
X1770216D01*
X1770507Y1432153D01*
X1770757Y1432278D01*
X1770966Y1432445D01*
G01X1772107D02*
X1772357Y1432237D01*
X1772649Y1432112D01*
X1773024Y1432070D01*
X1773399Y1432153D01*
X1773691Y1432320D01*
X1773899Y1432612D01*
X1773941Y1432945D01*
X1773857Y1433278D01*
X1773649Y1433487D01*
X1773357Y1433653D01*
X1773066Y1433695D01*
X1772774Y1433653D01*
X1772399Y1433487D01*
X1772524Y1434570D01*
X1773649D01*
G01X1775207Y1432570D02*
X1775457Y1432278D01*
X1775791Y1432112D01*
X1776166Y1432070D01*
X1776499Y1432112D01*
X1776832Y1432320D01*
X1777041Y1432570D01*
X1777082Y1432820D01*
X1776999Y1433112D01*
X1776707Y1433320D01*
X1776416Y1433403D01*
X1776041D01*
G01X1776416D02*
X1776666Y1433528D01*
X1776874Y1433737D01*
X1776957Y1433987D01*
X1776874Y1434237D01*
X1776666Y1434445D01*
X1776291Y1434570D01*
X1775916Y1434528D01*
X1775541Y1434362D01*
G01X1778432Y1433112D02*
X1778724Y1433403D01*
X1778974Y1433570D01*
X1779307Y1433653D01*
X1779599Y1433570D01*
X1779807Y1433403D01*
X1779974Y1433153D01*
X1780016Y1432862D01*
X1779974Y1432612D01*
X1779807Y1432362D01*
X1779557Y1432153D01*
X1779266Y1432070D01*
X1778932Y1432153D01*
X1778641Y1432403D01*
X1778474Y1432778D01*
X1778432Y1433195D01*
X1778516Y1433737D01*
X1778641Y1434028D01*
X1778849Y1434320D01*
X1779141Y1434528D01*
X1779432Y1434570D01*
X1779724Y1434487D01*
X1779932Y1434278D01*
G01X1784834Y1456867D02*
X1784709Y1456617D01*
X1784626Y1456325D01*
Y1455992D01*
X1784751Y1455617D01*
X1784959Y1455325D01*
X1785209Y1455117D01*
X1785626Y1454950D01*
X1786001Y1454908D01*
X1786376Y1454992D01*
X1786626Y1455117D01*
X1786876Y1455367D01*
X1787043Y1455658D01*
X1787126Y1455950D01*
Y1456242D01*
X1787043Y1456533D01*
X1786918Y1456783D01*
X1786751Y1456992D01*
G01X1787126Y1458967D02*
X1786584Y1459050D01*
X1786126Y1459175D01*
X1785709Y1459342D01*
X1785251Y1459550D01*
X1784626Y1459883D01*
Y1458217D01*
G01X1787126Y1462150D02*
X1784626D01*
X1785126Y1461650D01*
G01X1787126D02*
Y1462650D01*
G01X1786626Y1464333D02*
X1786918Y1464583D01*
X1787084Y1464917D01*
X1787126Y1465292D01*
X1787084Y1465625D01*
X1786876Y1465958D01*
X1786626Y1466167D01*
X1786376Y1466208D01*
X1786084Y1466125D01*
X1785876Y1465833D01*
X1785793Y1465542D01*
Y1465167D01*
G01Y1465542D02*
X1785668Y1465792D01*
X1785459Y1466000D01*
X1785209Y1466083D01*
X1784959Y1466000D01*
X1784751Y1465792D01*
X1784626Y1465417D01*
X1784668Y1465042D01*
X1784834Y1464667D01*
G01X1792426Y1475717D02*
X1789926D01*
Y1476758D01*
X1790051Y1477092D01*
X1790218Y1477300D01*
X1790551Y1477383D01*
X1790884Y1477300D01*
X1791093Y1477050D01*
X1791218Y1476758D01*
Y1475717D01*
G01Y1476758D02*
X1792426Y1477383D01*
G01Y1479650D02*
X1789926D01*
X1790426Y1479150D01*
G01X1792426D02*
Y1480150D01*
G01Y1482750D02*
X1792384Y1483042D01*
X1792259Y1483375D01*
X1792051Y1483583D01*
X1791759Y1483667D01*
X1791468Y1483583D01*
X1791218Y1483333D01*
X1791093Y1482958D01*
Y1482542D01*
X1791009Y1482292D01*
X1790801Y1482083D01*
X1790509Y1482000D01*
X1790218Y1482125D01*
X1790009Y1482417D01*
X1789926Y1482750D01*
X1790009Y1483083D01*
X1790218Y1483375D01*
X1790509Y1483500D01*
X1790801Y1483417D01*
X1791009Y1483208D01*
X1791093Y1482958D01*
Y1482542D01*
X1791218Y1482167D01*
X1791468Y1481917D01*
X1791759Y1481833D01*
X1792051Y1481917D01*
X1792259Y1482125D01*
X1792384Y1482458D01*
X1792426Y1482750D01*
G01Y1485850D02*
X1792384Y1486142D01*
X1792259Y1486475D01*
X1792051Y1486683D01*
X1791759Y1486767D01*
X1791468Y1486683D01*
X1791218Y1486433D01*
X1791093Y1486058D01*
Y1485642D01*
X1791009Y1485392D01*
X1790801Y1485183D01*
X1790509Y1485100D01*
X1790218Y1485225D01*
X1790009Y1485517D01*
X1789926Y1485850D01*
X1790009Y1486183D01*
X1790218Y1486475D01*
X1790509Y1486600D01*
X1790801Y1486517D01*
X1791009Y1486308D01*
X1791093Y1486058D01*
Y1485642D01*
X1791218Y1485267D01*
X1791468Y1485017D01*
X1791759Y1484933D01*
X1792051Y1485017D01*
X1792259Y1485225D01*
X1792384Y1485558D01*
X1792426Y1485850D01*
G01X1809676Y1483760D02*
X1805676D01*
Y1476360D01*
G01X1815826Y1472900D02*
Y1468900D01*
X1823226D01*
G01X1794593Y1493300D02*
Y1495800D01*
X1795634D01*
X1795968Y1495675D01*
X1796176Y1495508D01*
X1796259Y1495175D01*
X1796176Y1494842D01*
X1795926Y1494633D01*
X1795634Y1494508D01*
X1794593D01*
G01X1795634D02*
X1796259Y1493300D01*
G01X1798526D02*
Y1495800D01*
X1798026Y1495300D01*
G01Y1493300D02*
X1799026D01*
G01X1800709Y1493800D02*
X1800959Y1493508D01*
X1801293Y1493342D01*
X1801668Y1493300D01*
X1802001Y1493342D01*
X1802334Y1493550D01*
X1802543Y1493800D01*
X1802584Y1494050D01*
X1802501Y1494342D01*
X1802209Y1494550D01*
X1801918Y1494633D01*
X1801543D01*
G01X1801918D02*
X1802168Y1494758D01*
X1802376Y1494967D01*
X1802459Y1495217D01*
X1802376Y1495467D01*
X1802168Y1495675D01*
X1801793Y1495800D01*
X1801418Y1495758D01*
X1801043Y1495592D01*
G01X1804726Y1495800D02*
X1804393Y1495717D01*
X1804143Y1495508D01*
X1803976Y1495258D01*
X1803851Y1494925D01*
X1803809Y1494550D01*
X1803851Y1494175D01*
X1803976Y1493842D01*
X1804143Y1493592D01*
X1804393Y1493383D01*
X1804726Y1493300D01*
X1805059Y1493383D01*
X1805309Y1493592D01*
X1805476Y1493842D01*
X1805601Y1494175D01*
X1805643Y1494550D01*
X1805601Y1494925D01*
X1805476Y1495258D01*
X1805309Y1495508D01*
X1805059Y1495717D01*
X1804726Y1495800D01*
G01X1808326Y1493300D02*
Y1495800D01*
X1806784Y1494008D01*
X1808868D01*
G01X1808841Y1488100D02*
Y1492100D01*
X1801441D01*
G01X1811126Y1453667D02*
X1808626D01*
Y1454708D01*
X1808751Y1455042D01*
X1808918Y1455250D01*
X1809251Y1455333D01*
X1809584Y1455250D01*
X1809793Y1455000D01*
X1809918Y1454708D01*
Y1453667D01*
G01Y1454708D02*
X1811126Y1455333D01*
G01Y1457600D02*
X1808626D01*
X1809126Y1457100D01*
G01X1811126D02*
Y1458100D01*
G01X1810626Y1459783D02*
X1810918Y1460033D01*
X1811084Y1460367D01*
X1811126Y1460742D01*
X1811084Y1461075D01*
X1810876Y1461408D01*
X1810626Y1461617D01*
X1810376Y1461658D01*
X1810084Y1461575D01*
X1809876Y1461283D01*
X1809793Y1460992D01*
Y1460617D01*
G01Y1460992D02*
X1809668Y1461242D01*
X1809459Y1461450D01*
X1809209Y1461533D01*
X1808959Y1461450D01*
X1808751Y1461242D01*
X1808626Y1460867D01*
X1808668Y1460492D01*
X1808834Y1460117D01*
G01X1808626Y1463800D02*
X1808709Y1463467D01*
X1808918Y1463217D01*
X1809168Y1463050D01*
X1809501Y1462925D01*
X1809876Y1462883D01*
X1810251Y1462925D01*
X1810584Y1463050D01*
X1810834Y1463217D01*
X1811043Y1463467D01*
X1811126Y1463800D01*
X1811043Y1464133D01*
X1810834Y1464383D01*
X1810584Y1464550D01*
X1810251Y1464675D01*
X1809876Y1464717D01*
X1809501Y1464675D01*
X1809168Y1464550D01*
X1808918Y1464383D01*
X1808709Y1464133D01*
X1808626Y1463800D01*
G01X1811126Y1466900D02*
X1811084Y1467192D01*
X1810959Y1467525D01*
X1810751Y1467733D01*
X1810459Y1467817D01*
X1810168Y1467733D01*
X1809918Y1467483D01*
X1809793Y1467108D01*
Y1466692D01*
X1809709Y1466442D01*
X1809501Y1466233D01*
X1809209Y1466150D01*
X1808918Y1466275D01*
X1808709Y1466567D01*
X1808626Y1466900D01*
X1808709Y1467233D01*
X1808918Y1467525D01*
X1809209Y1467650D01*
X1809501Y1467567D01*
X1809709Y1467358D01*
X1809793Y1467108D01*
Y1466692D01*
X1809918Y1466317D01*
X1810168Y1466067D01*
X1810459Y1465983D01*
X1810751Y1466067D01*
X1810959Y1466275D01*
X1811084Y1466608D01*
X1811126Y1466900D01*
G01X1811811Y1469000D02*
Y1473000D01*
X1804411D01*
G01X1788326Y1476350D02*
X1788284Y1476017D01*
X1788118Y1475725D01*
X1787868Y1475475D01*
X1787576Y1475308D01*
X1787243Y1475225D01*
X1786909D01*
X1786576Y1475308D01*
X1786284Y1475475D01*
X1786034Y1475725D01*
X1785868Y1476017D01*
X1785826Y1476350D01*
X1785868Y1476683D01*
X1786034Y1476975D01*
X1786284Y1477225D01*
X1786576Y1477392D01*
X1786909Y1477475D01*
X1787243D01*
X1787576Y1477392D01*
X1787868Y1477225D01*
X1788118Y1476975D01*
X1788284Y1476683D01*
X1788326Y1476350D01*
G01X1787659Y1476683D02*
X1788326Y1477183D01*
G01X1786243Y1478658D02*
X1785993Y1478908D01*
X1785868Y1479200D01*
X1785826Y1479533D01*
X1785909Y1479950D01*
X1786118Y1480242D01*
X1786368Y1480325D01*
X1786618Y1480283D01*
X1786826Y1480117D01*
X1787243Y1479283D01*
X1787534Y1478908D01*
X1787951Y1478658D01*
X1788326Y1478575D01*
Y1480325D01*
G01Y1482550D02*
X1785826D01*
X1786326Y1482050D01*
G01X1788326D02*
Y1483050D01*
G01Y1485650D02*
X1788284Y1485942D01*
X1788159Y1486275D01*
X1787951Y1486483D01*
X1787659Y1486567D01*
X1787368Y1486483D01*
X1787118Y1486233D01*
X1786993Y1485858D01*
Y1485442D01*
X1786909Y1485192D01*
X1786701Y1484983D01*
X1786409Y1484900D01*
X1786118Y1485025D01*
X1785909Y1485317D01*
X1785826Y1485650D01*
X1785909Y1485983D01*
X1786118Y1486275D01*
X1786409Y1486400D01*
X1786701Y1486317D01*
X1786909Y1486108D01*
X1786993Y1485858D01*
Y1485442D01*
X1787118Y1485067D01*
X1787368Y1484817D01*
X1787659Y1484733D01*
X1787951Y1484817D01*
X1788159Y1485025D01*
X1788284Y1485358D01*
X1788326Y1485650D01*
G01X1804936Y1487390D02*
X1793536D01*
G01X1804936Y1473990D02*
Y1487390D01*
G01X1793536Y1473990D02*
X1804936D01*
G01X1793536Y1487390D02*
Y1473990D01*
G01X1783709Y1452900D02*
Y1451108D01*
X1783876Y1450733D01*
X1784209Y1450483D01*
X1784626Y1450400D01*
X1785043Y1450483D01*
X1785376Y1450733D01*
X1785543Y1451108D01*
Y1452900D01*
G01X1786809Y1450775D02*
X1787059Y1450567D01*
X1787351Y1450442D01*
X1787726Y1450400D01*
X1788101Y1450483D01*
X1788393Y1450650D01*
X1788601Y1450942D01*
X1788643Y1451275D01*
X1788559Y1451608D01*
X1788351Y1451817D01*
X1788059Y1451983D01*
X1787768Y1452025D01*
X1787476Y1451983D01*
X1787101Y1451817D01*
X1787226Y1452900D01*
X1788351D01*
G01X1790034Y1452483D02*
X1790284Y1452733D01*
X1790576Y1452858D01*
X1790909Y1452900D01*
X1791326Y1452817D01*
X1791618Y1452608D01*
X1791701Y1452358D01*
X1791659Y1452108D01*
X1791493Y1451900D01*
X1790659Y1451483D01*
X1790284Y1451192D01*
X1790034Y1450775D01*
X1789951Y1450400D01*
X1791701D01*
G01X1804226Y1466900D02*
Y1453500D01*
G01X1794226Y1466900D02*
X1804226D01*
G01X1794226Y1453500D02*
Y1466900D01*
G01X1804226Y1453500D02*
X1794226D01*
G01X1813087Y1491234D02*
X1812754Y1491276D01*
X1812462Y1491442D01*
X1812212Y1491692D01*
X1812045Y1491984D01*
X1811962Y1492317D01*
Y1492651D01*
X1812045Y1492984D01*
X1812212Y1493276D01*
X1812462Y1493526D01*
X1812754Y1493692D01*
X1813087Y1493734D01*
X1813420Y1493692D01*
X1813712Y1493526D01*
X1813962Y1493276D01*
X1814129Y1492984D01*
X1814212Y1492651D01*
Y1492317D01*
X1814129Y1491984D01*
X1813962Y1491692D01*
X1813712Y1491442D01*
X1813420Y1491276D01*
X1813087Y1491234D01*
G01X1813420Y1491901D02*
X1813920Y1491234D01*
G01X1815395Y1493317D02*
X1815645Y1493567D01*
X1815937Y1493692D01*
X1816270Y1493734D01*
X1816687Y1493651D01*
X1816979Y1493442D01*
X1817062Y1493192D01*
X1817020Y1492942D01*
X1816854Y1492734D01*
X1816020Y1492317D01*
X1815645Y1492026D01*
X1815395Y1491609D01*
X1815312Y1491234D01*
X1817062D01*
G01X1819287Y1493734D02*
X1818954Y1493651D01*
X1818704Y1493442D01*
X1818537Y1493192D01*
X1818412Y1492859D01*
X1818370Y1492484D01*
X1818412Y1492109D01*
X1818537Y1491776D01*
X1818704Y1491526D01*
X1818954Y1491317D01*
X1819287Y1491234D01*
X1819620Y1491317D01*
X1819870Y1491526D01*
X1820037Y1491776D01*
X1820162Y1492109D01*
X1820204Y1492484D01*
X1820162Y1492859D01*
X1820037Y1493192D01*
X1819870Y1493442D01*
X1819620Y1493651D01*
X1819287Y1493734D01*
G01X1822304Y1491234D02*
X1822387Y1491776D01*
X1822512Y1492234D01*
X1822679Y1492651D01*
X1822887Y1493109D01*
X1823220Y1493734D01*
X1821554D01*
G01X1810126Y1479265D02*
X1810386D01*
X1811821Y1480700D01*
X1810386Y1482135D01*
G01X1810126Y1479265D02*
Y1482135D01*
X1821126D01*
G01Y1479265D02*
X1810126D01*
G01X1885856Y107319D02*
X1890906D01*
Y206019D01*
X1915556D01*
Y21619D01*
X1890906D01*
Y80319D01*
X1885856D01*
Y107319D01*
G01X1867367Y61292D02*
X1867117Y61417D01*
X1866825Y61500D01*
X1866492D01*
X1866117Y61375D01*
X1865825Y61167D01*
X1865617Y60917D01*
X1865450Y60500D01*
X1865408Y60125D01*
X1865492Y59750D01*
X1865617Y59500D01*
X1865867Y59250D01*
X1866158Y59083D01*
X1866450Y59000D01*
X1866742D01*
X1867033Y59083D01*
X1867283Y59208D01*
X1867492Y59375D01*
G01X1870050Y59000D02*
Y61500D01*
X1868508Y59708D01*
X1870592D01*
G01X1872650Y59000D02*
X1872942Y59042D01*
X1873275Y59167D01*
X1873483Y59375D01*
X1873567Y59667D01*
X1873483Y59958D01*
X1873233Y60208D01*
X1872858Y60333D01*
X1872442D01*
X1872192Y60417D01*
X1871983Y60625D01*
X1871900Y60917D01*
X1872025Y61208D01*
X1872317Y61417D01*
X1872650Y61500D01*
X1872983Y61417D01*
X1873275Y61208D01*
X1873400Y60917D01*
X1873317Y60625D01*
X1873108Y60417D01*
X1872858Y60333D01*
X1872442D01*
X1872067Y60208D01*
X1871817Y59958D01*
X1871733Y59667D01*
X1871817Y59375D01*
X1872025Y59167D01*
X1872358Y59042D01*
X1872650Y59000D01*
G01X1876250D02*
Y61500D01*
X1874708Y59708D01*
X1876792D01*
G01X1867208Y64872D02*
X1866958Y64997D01*
X1866666Y65080D01*
X1866333D01*
X1865958Y64955D01*
X1865666Y64747D01*
X1865458Y64497D01*
X1865291Y64080D01*
X1865249Y63705D01*
X1865333Y63330D01*
X1865458Y63080D01*
X1865708Y62830D01*
X1865999Y62663D01*
X1866291Y62580D01*
X1866583D01*
X1866874Y62663D01*
X1867124Y62788D01*
X1867333Y62955D01*
G01X1869891Y62580D02*
Y65080D01*
X1868349Y63288D01*
X1870433D01*
G01X1872491Y62580D02*
X1872783Y62622D01*
X1873116Y62747D01*
X1873324Y62955D01*
X1873408Y63247D01*
X1873324Y63538D01*
X1873074Y63788D01*
X1872699Y63913D01*
X1872283D01*
X1872033Y63997D01*
X1871824Y64205D01*
X1871741Y64497D01*
X1871866Y64788D01*
X1872158Y64997D01*
X1872491Y65080D01*
X1872824Y64997D01*
X1873116Y64788D01*
X1873241Y64497D01*
X1873158Y64205D01*
X1872949Y63997D01*
X1872699Y63913D01*
X1872283D01*
X1871908Y63788D01*
X1871658Y63538D01*
X1871574Y63247D01*
X1871658Y62955D01*
X1871866Y62747D01*
X1872199Y62622D01*
X1872491Y62580D01*
G01X1874674Y63080D02*
X1874924Y62788D01*
X1875258Y62622D01*
X1875633Y62580D01*
X1875966Y62622D01*
X1876299Y62830D01*
X1876508Y63080D01*
X1876549Y63330D01*
X1876466Y63622D01*
X1876174Y63830D01*
X1875883Y63913D01*
X1875508D01*
G01X1875883D02*
X1876133Y64038D01*
X1876341Y64247D01*
X1876424Y64497D01*
X1876341Y64747D01*
X1876133Y64955D01*
X1875758Y65080D01*
X1875383Y65038D01*
X1875008Y64872D01*
G01X1879767Y74292D02*
X1879517Y74417D01*
X1879225Y74500D01*
X1878892D01*
X1878517Y74375D01*
X1878225Y74167D01*
X1878017Y73917D01*
X1877850Y73500D01*
X1877808Y73125D01*
X1877892Y72750D01*
X1878017Y72500D01*
X1878267Y72250D01*
X1878558Y72083D01*
X1878850Y72000D01*
X1879142D01*
X1879433Y72083D01*
X1879683Y72208D01*
X1879892Y72375D01*
G01X1882450Y72000D02*
Y74500D01*
X1880908Y72708D01*
X1882992D01*
G01X1884342Y72292D02*
X1884633Y72083D01*
X1884967Y72000D01*
X1885300Y72083D01*
X1885592Y72333D01*
X1885800Y72708D01*
X1885883Y73083D01*
Y73542D01*
X1885800Y73917D01*
X1885592Y74250D01*
X1885342Y74417D01*
X1885050Y74500D01*
X1884717Y74417D01*
X1884467Y74250D01*
X1884300Y74000D01*
X1884217Y73667D01*
X1884300Y73375D01*
X1884508Y73083D01*
X1884758Y72917D01*
X1885050Y72875D01*
X1885383Y72958D01*
X1885633Y73167D01*
X1885883Y73542D01*
G01X1887358Y74083D02*
X1887608Y74333D01*
X1887900Y74458D01*
X1888233Y74500D01*
X1888650Y74417D01*
X1888942Y74208D01*
X1889025Y73958D01*
X1888983Y73708D01*
X1888817Y73500D01*
X1887983Y73083D01*
X1887608Y72792D01*
X1887358Y72375D01*
X1887275Y72000D01*
X1889025D01*
G01X1849767Y80792D02*
X1849517Y80917D01*
X1849225Y81000D01*
X1848892D01*
X1848517Y80875D01*
X1848225Y80667D01*
X1848017Y80417D01*
X1847850Y80000D01*
X1847808Y79625D01*
X1847892Y79250D01*
X1848017Y79000D01*
X1848267Y78750D01*
X1848558Y78583D01*
X1848850Y78500D01*
X1849142D01*
X1849433Y78583D01*
X1849683Y78708D01*
X1849892Y78875D01*
G01X1852450Y78500D02*
Y81000D01*
X1850908Y79208D01*
X1852992D01*
G01X1854342Y78792D02*
X1854633Y78583D01*
X1854967Y78500D01*
X1855300Y78583D01*
X1855592Y78833D01*
X1855800Y79208D01*
X1855883Y79583D01*
Y80042D01*
X1855800Y80417D01*
X1855592Y80750D01*
X1855342Y80917D01*
X1855050Y81000D01*
X1854717Y80917D01*
X1854467Y80750D01*
X1854300Y80500D01*
X1854217Y80167D01*
X1854300Y79875D01*
X1854508Y79583D01*
X1854758Y79417D01*
X1855050Y79375D01*
X1855383Y79458D01*
X1855633Y79667D01*
X1855883Y80042D01*
G01X1857233Y79000D02*
X1857483Y78708D01*
X1857817Y78542D01*
X1858192Y78500D01*
X1858525Y78542D01*
X1858858Y78750D01*
X1859067Y79000D01*
X1859108Y79250D01*
X1859025Y79542D01*
X1858733Y79750D01*
X1858442Y79833D01*
X1858067D01*
G01X1858442D02*
X1858692Y79958D01*
X1858900Y80167D01*
X1858983Y80417D01*
X1858900Y80667D01*
X1858692Y80875D01*
X1858317Y81000D01*
X1857942Y80958D01*
X1857567Y80792D01*
G01X1851767Y35292D02*
X1851517Y35417D01*
X1851225Y35500D01*
X1850892D01*
X1850517Y35375D01*
X1850225Y35167D01*
X1850017Y34917D01*
X1849850Y34500D01*
X1849808Y34125D01*
X1849892Y33750D01*
X1850017Y33500D01*
X1850267Y33250D01*
X1850558Y33083D01*
X1850850Y33000D01*
X1851142D01*
X1851433Y33083D01*
X1851683Y33208D01*
X1851892Y33375D01*
G01X1854450Y33000D02*
Y35500D01*
X1852908Y33708D01*
X1854992D01*
G01X1856342Y33292D02*
X1856633Y33083D01*
X1856967Y33000D01*
X1857300Y33083D01*
X1857592Y33333D01*
X1857800Y33708D01*
X1857883Y34083D01*
Y34542D01*
X1857800Y34917D01*
X1857592Y35250D01*
X1857342Y35417D01*
X1857050Y35500D01*
X1856717Y35417D01*
X1856467Y35250D01*
X1856300Y35000D01*
X1856217Y34667D01*
X1856300Y34375D01*
X1856508Y34083D01*
X1856758Y33917D01*
X1857050Y33875D01*
X1857383Y33958D01*
X1857633Y34167D01*
X1857883Y34542D01*
G01X1860650Y33000D02*
Y35500D01*
X1859108Y33708D01*
X1861192D01*
G01X1826017Y79500D02*
Y82000D01*
X1827058D01*
X1827392Y81875D01*
X1827600Y81708D01*
X1827683Y81375D01*
X1827600Y81042D01*
X1827350Y80833D01*
X1827058Y80708D01*
X1826017D01*
G01X1827058D02*
X1827683Y79500D01*
G01X1829950D02*
X1830242Y79542D01*
X1830575Y79667D01*
X1830783Y79875D01*
X1830867Y80167D01*
X1830783Y80458D01*
X1830533Y80708D01*
X1830158Y80833D01*
X1829742D01*
X1829492Y80917D01*
X1829283Y81125D01*
X1829200Y81417D01*
X1829325Y81708D01*
X1829617Y81917D01*
X1829950Y82000D01*
X1830283Y81917D01*
X1830575Y81708D01*
X1830700Y81417D01*
X1830617Y81125D01*
X1830408Y80917D01*
X1830158Y80833D01*
X1829742D01*
X1829367Y80708D01*
X1829117Y80458D01*
X1829033Y80167D01*
X1829117Y79875D01*
X1829325Y79667D01*
X1829658Y79542D01*
X1829950Y79500D01*
G01X1832258Y80542D02*
X1832550Y80833D01*
X1832800Y81000D01*
X1833133Y81083D01*
X1833425Y81000D01*
X1833633Y80833D01*
X1833800Y80583D01*
X1833842Y80292D01*
X1833800Y80042D01*
X1833633Y79792D01*
X1833383Y79583D01*
X1833092Y79500D01*
X1832758Y79583D01*
X1832467Y79833D01*
X1832300Y80208D01*
X1832258Y80625D01*
X1832342Y81167D01*
X1832467Y81458D01*
X1832675Y81750D01*
X1832967Y81958D01*
X1833258Y82000D01*
X1833550Y81917D01*
X1833758Y81708D01*
G01X1836067Y79500D02*
X1836150Y80042D01*
X1836275Y80500D01*
X1836442Y80917D01*
X1836650Y81375D01*
X1836983Y82000D01*
X1835317D01*
G01X1824378Y83039D02*
Y87039D01*
X1816978D01*
G01X1825625Y87087D02*
Y89587D01*
X1826666D01*
X1827000Y89462D01*
X1827208Y89295D01*
X1827291Y88962D01*
X1827208Y88629D01*
X1826958Y88420D01*
X1826666Y88295D01*
X1825625D01*
G01X1826666D02*
X1827291Y87087D01*
G01X1829558D02*
X1829850Y87129D01*
X1830183Y87254D01*
X1830391Y87462D01*
X1830475Y87754D01*
X1830391Y88045D01*
X1830141Y88295D01*
X1829766Y88420D01*
X1829350D01*
X1829100Y88504D01*
X1828891Y88712D01*
X1828808Y89004D01*
X1828933Y89295D01*
X1829225Y89504D01*
X1829558Y89587D01*
X1829891Y89504D01*
X1830183Y89295D01*
X1830308Y89004D01*
X1830225Y88712D01*
X1830016Y88504D01*
X1829766Y88420D01*
X1829350D01*
X1828975Y88295D01*
X1828725Y88045D01*
X1828641Y87754D01*
X1828725Y87462D01*
X1828933Y87254D01*
X1829266Y87129D01*
X1829558Y87087D01*
G01X1831866Y88129D02*
X1832158Y88420D01*
X1832408Y88587D01*
X1832741Y88670D01*
X1833033Y88587D01*
X1833241Y88420D01*
X1833408Y88170D01*
X1833450Y87879D01*
X1833408Y87629D01*
X1833241Y87379D01*
X1832991Y87170D01*
X1832700Y87087D01*
X1832366Y87170D01*
X1832075Y87420D01*
X1831908Y87795D01*
X1831866Y88212D01*
X1831950Y88754D01*
X1832075Y89045D01*
X1832283Y89337D01*
X1832575Y89545D01*
X1832866Y89587D01*
X1833158Y89504D01*
X1833366Y89295D01*
G01X1835758Y87087D02*
X1836050Y87129D01*
X1836383Y87254D01*
X1836591Y87462D01*
X1836675Y87754D01*
X1836591Y88045D01*
X1836341Y88295D01*
X1835966Y88420D01*
X1835550D01*
X1835300Y88504D01*
X1835091Y88712D01*
X1835008Y89004D01*
X1835133Y89295D01*
X1835425Y89504D01*
X1835758Y89587D01*
X1836091Y89504D01*
X1836383Y89295D01*
X1836508Y89004D01*
X1836425Y88712D01*
X1836216Y88504D01*
X1835966Y88420D01*
X1835550D01*
X1835175Y88295D01*
X1834925Y88045D01*
X1834841Y87754D01*
X1834925Y87462D01*
X1835133Y87254D01*
X1835466Y87129D01*
X1835758Y87087D01*
G01X1826017Y75500D02*
Y78000D01*
X1827058D01*
X1827392Y77875D01*
X1827600Y77708D01*
X1827683Y77375D01*
X1827600Y77042D01*
X1827350Y76833D01*
X1827058Y76708D01*
X1826017D01*
G01X1827058D02*
X1827683Y75500D01*
G01X1829950D02*
X1830242Y75542D01*
X1830575Y75667D01*
X1830783Y75875D01*
X1830867Y76167D01*
X1830783Y76458D01*
X1830533Y76708D01*
X1830158Y76833D01*
X1829742D01*
X1829492Y76917D01*
X1829283Y77125D01*
X1829200Y77417D01*
X1829325Y77708D01*
X1829617Y77917D01*
X1829950Y78000D01*
X1830283Y77917D01*
X1830575Y77708D01*
X1830700Y77417D01*
X1830617Y77125D01*
X1830408Y76917D01*
X1830158Y76833D01*
X1829742D01*
X1829367Y76708D01*
X1829117Y76458D01*
X1829033Y76167D01*
X1829117Y75875D01*
X1829325Y75667D01*
X1829658Y75542D01*
X1829950Y75500D01*
G01X1832258Y76542D02*
X1832550Y76833D01*
X1832800Y77000D01*
X1833133Y77083D01*
X1833425Y77000D01*
X1833633Y76833D01*
X1833800Y76583D01*
X1833842Y76292D01*
X1833800Y76042D01*
X1833633Y75792D01*
X1833383Y75583D01*
X1833092Y75500D01*
X1832758Y75583D01*
X1832467Y75833D01*
X1832300Y76208D01*
X1832258Y76625D01*
X1832342Y77167D01*
X1832467Y77458D01*
X1832675Y77750D01*
X1832967Y77958D01*
X1833258Y78000D01*
X1833550Y77917D01*
X1833758Y77708D01*
G01X1835442Y75792D02*
X1835733Y75583D01*
X1836067Y75500D01*
X1836400Y75583D01*
X1836692Y75833D01*
X1836900Y76208D01*
X1836983Y76583D01*
Y77042D01*
X1836900Y77417D01*
X1836692Y77750D01*
X1836442Y77917D01*
X1836150Y78000D01*
X1835817Y77917D01*
X1835567Y77750D01*
X1835400Y77500D01*
X1835317Y77167D01*
X1835400Y76875D01*
X1835608Y76583D01*
X1835858Y76417D01*
X1836150Y76375D01*
X1836483Y76458D01*
X1836733Y76667D01*
X1836983Y77042D01*
G01X1824378Y78939D02*
Y82939D01*
X1816978D01*
G01X1878517Y63500D02*
Y66000D01*
X1879558D01*
X1879892Y65875D01*
X1880100Y65708D01*
X1880183Y65375D01*
X1880100Y65042D01*
X1879850Y64833D01*
X1879558Y64708D01*
X1878517D01*
G01X1879558D02*
X1880183Y63500D01*
G01X1882450D02*
X1882742Y63542D01*
X1883075Y63667D01*
X1883283Y63875D01*
X1883367Y64167D01*
X1883283Y64458D01*
X1883033Y64708D01*
X1882658Y64833D01*
X1882242D01*
X1881992Y64917D01*
X1881783Y65125D01*
X1881700Y65417D01*
X1881825Y65708D01*
X1882117Y65917D01*
X1882450Y66000D01*
X1882783Y65917D01*
X1883075Y65708D01*
X1883200Y65417D01*
X1883117Y65125D01*
X1882908Y64917D01*
X1882658Y64833D01*
X1882242D01*
X1881867Y64708D01*
X1881617Y64458D01*
X1881533Y64167D01*
X1881617Y63875D01*
X1881825Y63667D01*
X1882158Y63542D01*
X1882450Y63500D01*
G01X1885467D02*
X1885550Y64042D01*
X1885675Y64500D01*
X1885842Y64917D01*
X1886050Y65375D01*
X1886383Y66000D01*
X1884717D01*
G01X1887733Y63875D02*
X1887983Y63667D01*
X1888275Y63542D01*
X1888650Y63500D01*
X1889025Y63583D01*
X1889317Y63750D01*
X1889525Y64042D01*
X1889567Y64375D01*
X1889483Y64708D01*
X1889275Y64917D01*
X1888983Y65083D01*
X1888692Y65125D01*
X1888400Y65083D01*
X1888025Y64917D01*
X1888150Y66000D01*
X1889275D01*
G01X1883700Y75500D02*
Y79500D01*
X1876300D01*
G01X1848517Y73800D02*
Y76300D01*
X1849558D01*
X1849892Y76175D01*
X1850100Y76008D01*
X1850183Y75675D01*
X1850100Y75342D01*
X1849850Y75133D01*
X1849558Y75008D01*
X1848517D01*
G01X1849558D02*
X1850183Y73800D01*
G01X1852450D02*
X1852742Y73842D01*
X1853075Y73967D01*
X1853283Y74175D01*
X1853367Y74467D01*
X1853283Y74758D01*
X1853033Y75008D01*
X1852658Y75133D01*
X1852242D01*
X1851992Y75217D01*
X1851783Y75425D01*
X1851700Y75717D01*
X1851825Y76008D01*
X1852117Y76217D01*
X1852450Y76300D01*
X1852783Y76217D01*
X1853075Y76008D01*
X1853200Y75717D01*
X1853117Y75425D01*
X1852908Y75217D01*
X1852658Y75133D01*
X1852242D01*
X1851867Y75008D01*
X1851617Y74758D01*
X1851533Y74467D01*
X1851617Y74175D01*
X1851825Y73967D01*
X1852158Y73842D01*
X1852450Y73800D01*
G01X1855550D02*
X1855842Y73842D01*
X1856175Y73967D01*
X1856383Y74175D01*
X1856467Y74467D01*
X1856383Y74758D01*
X1856133Y75008D01*
X1855758Y75133D01*
X1855342D01*
X1855092Y75217D01*
X1854883Y75425D01*
X1854800Y75717D01*
X1854925Y76008D01*
X1855217Y76217D01*
X1855550Y76300D01*
X1855883Y76217D01*
X1856175Y76008D01*
X1856300Y75717D01*
X1856217Y75425D01*
X1856008Y75217D01*
X1855758Y75133D01*
X1855342D01*
X1854967Y75008D01*
X1854717Y74758D01*
X1854633Y74467D01*
X1854717Y74175D01*
X1854925Y73967D01*
X1855258Y73842D01*
X1855550Y73800D01*
G01X1857858Y75883D02*
X1858108Y76133D01*
X1858400Y76258D01*
X1858733Y76300D01*
X1859150Y76217D01*
X1859442Y76008D01*
X1859525Y75758D01*
X1859483Y75508D01*
X1859317Y75300D01*
X1858483Y74883D01*
X1858108Y74592D01*
X1857858Y74175D01*
X1857775Y73800D01*
X1859525D01*
G01X1868200Y76000D02*
Y80000D01*
X1860800D01*
G01X1867700Y46517D02*
X1865200D01*
Y47558D01*
X1865325Y47892D01*
X1865492Y48100D01*
X1865825Y48183D01*
X1866158Y48100D01*
X1866367Y47850D01*
X1866492Y47558D01*
Y46517D01*
G01Y47558D02*
X1867700Y48183D01*
G01Y50450D02*
X1867658Y50742D01*
X1867533Y51075D01*
X1867325Y51283D01*
X1867033Y51367D01*
X1866742Y51283D01*
X1866492Y51033D01*
X1866367Y50658D01*
Y50242D01*
X1866283Y49992D01*
X1866075Y49783D01*
X1865783Y49700D01*
X1865492Y49825D01*
X1865283Y50117D01*
X1865200Y50450D01*
X1865283Y50783D01*
X1865492Y51075D01*
X1865783Y51200D01*
X1866075Y51117D01*
X1866283Y50908D01*
X1866367Y50658D01*
Y50242D01*
X1866492Y49867D01*
X1866742Y49617D01*
X1867033Y49533D01*
X1867325Y49617D01*
X1867533Y49825D01*
X1867658Y50158D01*
X1867700Y50450D01*
G01Y53550D02*
X1867658Y53842D01*
X1867533Y54175D01*
X1867325Y54383D01*
X1867033Y54467D01*
X1866742Y54383D01*
X1866492Y54133D01*
X1866367Y53758D01*
Y53342D01*
X1866283Y53092D01*
X1866075Y52883D01*
X1865783Y52800D01*
X1865492Y52925D01*
X1865283Y53217D01*
X1865200Y53550D01*
X1865283Y53883D01*
X1865492Y54175D01*
X1865783Y54300D01*
X1866075Y54217D01*
X1866283Y54008D01*
X1866367Y53758D01*
Y53342D01*
X1866492Y52967D01*
X1866742Y52717D01*
X1867033Y52633D01*
X1867325Y52717D01*
X1867533Y52925D01*
X1867658Y53258D01*
X1867700Y53550D01*
G01X1867200Y55733D02*
X1867492Y55983D01*
X1867658Y56317D01*
X1867700Y56692D01*
X1867658Y57025D01*
X1867450Y57358D01*
X1867200Y57567D01*
X1866950Y57608D01*
X1866658Y57525D01*
X1866450Y57233D01*
X1866367Y56942D01*
Y56567D01*
G01Y56942D02*
X1866242Y57192D01*
X1866033Y57400D01*
X1865783Y57483D01*
X1865533Y57400D01*
X1865325Y57192D01*
X1865200Y56817D01*
X1865242Y56442D01*
X1865408Y56067D01*
G01X1882500Y47700D02*
X1878500D01*
Y40300D01*
G01X1864200Y46817D02*
X1861700D01*
Y47858D01*
X1861825Y48192D01*
X1861992Y48400D01*
X1862325Y48483D01*
X1862658Y48400D01*
X1862867Y48150D01*
X1862992Y47858D01*
Y46817D01*
G01Y47858D02*
X1864200Y48483D01*
G01Y50750D02*
X1864158Y51042D01*
X1864033Y51375D01*
X1863825Y51583D01*
X1863533Y51667D01*
X1863242Y51583D01*
X1862992Y51333D01*
X1862867Y50958D01*
Y50542D01*
X1862783Y50292D01*
X1862575Y50083D01*
X1862283Y50000D01*
X1861992Y50125D01*
X1861783Y50417D01*
X1861700Y50750D01*
X1861783Y51083D01*
X1861992Y51375D01*
X1862283Y51500D01*
X1862575Y51417D01*
X1862783Y51208D01*
X1862867Y50958D01*
Y50542D01*
X1862992Y50167D01*
X1863242Y49917D01*
X1863533Y49833D01*
X1863825Y49917D01*
X1864033Y50125D01*
X1864158Y50458D01*
X1864200Y50750D01*
G01Y53850D02*
X1864158Y54142D01*
X1864033Y54475D01*
X1863825Y54683D01*
X1863533Y54767D01*
X1863242Y54683D01*
X1862992Y54433D01*
X1862867Y54058D01*
Y53642D01*
X1862783Y53392D01*
X1862575Y53183D01*
X1862283Y53100D01*
X1861992Y53225D01*
X1861783Y53517D01*
X1861700Y53850D01*
X1861783Y54183D01*
X1861992Y54475D01*
X1862283Y54600D01*
X1862575Y54517D01*
X1862783Y54308D01*
X1862867Y54058D01*
Y53642D01*
X1862992Y53267D01*
X1863242Y53017D01*
X1863533Y52933D01*
X1863825Y53017D01*
X1864033Y53225D01*
X1864158Y53558D01*
X1864200Y53850D01*
G01X1863825Y56033D02*
X1864033Y56283D01*
X1864158Y56575D01*
X1864200Y56950D01*
X1864117Y57325D01*
X1863950Y57617D01*
X1863658Y57825D01*
X1863325Y57867D01*
X1862992Y57783D01*
X1862783Y57575D01*
X1862617Y57283D01*
X1862575Y56992D01*
X1862617Y56700D01*
X1862783Y56325D01*
X1861700Y56450D01*
Y57575D01*
G01X1874900Y47700D02*
X1870900D01*
Y40300D01*
G01X1890100Y40417D02*
X1887600D01*
Y41458D01*
X1887725Y41792D01*
X1887892Y42000D01*
X1888225Y42083D01*
X1888558Y42000D01*
X1888767Y41750D01*
X1888892Y41458D01*
Y40417D01*
G01Y41458D02*
X1890100Y42083D01*
G01Y44350D02*
X1890058Y44642D01*
X1889933Y44975D01*
X1889725Y45183D01*
X1889433Y45267D01*
X1889142Y45183D01*
X1888892Y44933D01*
X1888767Y44558D01*
Y44142D01*
X1888683Y43892D01*
X1888475Y43683D01*
X1888183Y43600D01*
X1887892Y43725D01*
X1887683Y44017D01*
X1887600Y44350D01*
X1887683Y44683D01*
X1887892Y44975D01*
X1888183Y45100D01*
X1888475Y45017D01*
X1888683Y44808D01*
X1888767Y44558D01*
Y44142D01*
X1888892Y43767D01*
X1889142Y43517D01*
X1889433Y43433D01*
X1889725Y43517D01*
X1889933Y43725D01*
X1890058Y44058D01*
X1890100Y44350D01*
G01Y47450D02*
X1890058Y47742D01*
X1889933Y48075D01*
X1889725Y48283D01*
X1889433Y48367D01*
X1889142Y48283D01*
X1888892Y48033D01*
X1888767Y47658D01*
Y47242D01*
X1888683Y46992D01*
X1888475Y46783D01*
X1888183Y46700D01*
X1887892Y46825D01*
X1887683Y47117D01*
X1887600Y47450D01*
X1887683Y47783D01*
X1887892Y48075D01*
X1888183Y48200D01*
X1888475Y48117D01*
X1888683Y47908D01*
X1888767Y47658D01*
Y47242D01*
X1888892Y46867D01*
X1889142Y46617D01*
X1889433Y46533D01*
X1889725Y46617D01*
X1889933Y46825D01*
X1890058Y47158D01*
X1890100Y47450D01*
G01Y50467D02*
X1889558Y50550D01*
X1889100Y50675D01*
X1888683Y50842D01*
X1888225Y51050D01*
X1887600Y51383D01*
Y49717D01*
G01X1882600Y40300D02*
X1886600D01*
Y47700D01*
G01X1854017Y14500D02*
Y17000D01*
X1855058D01*
X1855392Y16875D01*
X1855600Y16708D01*
X1855683Y16375D01*
X1855600Y16042D01*
X1855350Y15833D01*
X1855058Y15708D01*
X1854017D01*
G01X1855058D02*
X1855683Y14500D01*
G01X1857950D02*
X1858242Y14542D01*
X1858575Y14667D01*
X1858783Y14875D01*
X1858867Y15167D01*
X1858783Y15458D01*
X1858533Y15708D01*
X1858158Y15833D01*
X1857742D01*
X1857492Y15917D01*
X1857283Y16125D01*
X1857200Y16417D01*
X1857325Y16708D01*
X1857617Y16917D01*
X1857950Y17000D01*
X1858283Y16917D01*
X1858575Y16708D01*
X1858700Y16417D01*
X1858617Y16125D01*
X1858408Y15917D01*
X1858158Y15833D01*
X1857742D01*
X1857367Y15708D01*
X1857117Y15458D01*
X1857033Y15167D01*
X1857117Y14875D01*
X1857325Y14667D01*
X1857658Y14542D01*
X1857950Y14500D01*
G01X1861050D02*
X1861342Y14542D01*
X1861675Y14667D01*
X1861883Y14875D01*
X1861967Y15167D01*
X1861883Y15458D01*
X1861633Y15708D01*
X1861258Y15833D01*
X1860842D01*
X1860592Y15917D01*
X1860383Y16125D01*
X1860300Y16417D01*
X1860425Y16708D01*
X1860717Y16917D01*
X1861050Y17000D01*
X1861383Y16917D01*
X1861675Y16708D01*
X1861800Y16417D01*
X1861717Y16125D01*
X1861508Y15917D01*
X1861258Y15833D01*
X1860842D01*
X1860467Y15708D01*
X1860217Y15458D01*
X1860133Y15167D01*
X1860217Y14875D01*
X1860425Y14667D01*
X1860758Y14542D01*
X1861050Y14500D01*
G01X1863442Y14792D02*
X1863733Y14583D01*
X1864067Y14500D01*
X1864400Y14583D01*
X1864692Y14833D01*
X1864900Y15208D01*
X1864983Y15583D01*
Y16042D01*
X1864900Y16417D01*
X1864692Y16750D01*
X1864442Y16917D01*
X1864150Y17000D01*
X1863817Y16917D01*
X1863567Y16750D01*
X1863400Y16500D01*
X1863317Y16167D01*
X1863400Y15875D01*
X1863608Y15583D01*
X1863858Y15417D01*
X1864150Y15375D01*
X1864483Y15458D01*
X1864733Y15667D01*
X1864983Y16042D01*
G01X1857100Y24300D02*
Y20300D01*
X1864500D01*
G01X1849017Y29100D02*
Y31600D01*
X1850058D01*
X1850392Y31475D01*
X1850600Y31308D01*
X1850683Y30975D01*
X1850600Y30642D01*
X1850350Y30433D01*
X1850058Y30308D01*
X1849017D01*
G01X1850058D02*
X1850683Y29100D01*
G01X1852950D02*
X1853242Y29142D01*
X1853575Y29267D01*
X1853783Y29475D01*
X1853867Y29767D01*
X1853783Y30058D01*
X1853533Y30308D01*
X1853158Y30433D01*
X1852742D01*
X1852492Y30517D01*
X1852283Y30725D01*
X1852200Y31017D01*
X1852325Y31308D01*
X1852617Y31517D01*
X1852950Y31600D01*
X1853283Y31517D01*
X1853575Y31308D01*
X1853700Y31017D01*
X1853617Y30725D01*
X1853408Y30517D01*
X1853158Y30433D01*
X1852742D01*
X1852367Y30308D01*
X1852117Y30058D01*
X1852033Y29767D01*
X1852117Y29475D01*
X1852325Y29267D01*
X1852658Y29142D01*
X1852950Y29100D01*
G01X1855342Y29392D02*
X1855633Y29183D01*
X1855967Y29100D01*
X1856300Y29183D01*
X1856592Y29433D01*
X1856800Y29808D01*
X1856883Y30183D01*
Y30642D01*
X1856800Y31017D01*
X1856592Y31350D01*
X1856342Y31517D01*
X1856050Y31600D01*
X1855717Y31517D01*
X1855467Y31350D01*
X1855300Y31100D01*
X1855217Y30767D01*
X1855300Y30475D01*
X1855508Y30183D01*
X1855758Y30017D01*
X1856050Y29975D01*
X1856383Y30058D01*
X1856633Y30267D01*
X1856883Y30642D01*
G01X1859150Y31600D02*
X1858817Y31517D01*
X1858567Y31308D01*
X1858400Y31058D01*
X1858275Y30725D01*
X1858233Y30350D01*
X1858275Y29975D01*
X1858400Y29642D01*
X1858567Y29392D01*
X1858817Y29183D01*
X1859150Y29100D01*
X1859483Y29183D01*
X1859733Y29392D01*
X1859900Y29642D01*
X1860025Y29975D01*
X1860067Y30350D01*
X1860025Y30725D01*
X1859900Y31058D01*
X1859733Y31308D01*
X1859483Y31517D01*
X1859150Y31600D01*
G01X1869400Y36100D02*
Y40100D01*
X1862000D01*
G01X1848917Y25400D02*
Y27900D01*
X1849958D01*
X1850292Y27775D01*
X1850500Y27608D01*
X1850583Y27275D01*
X1850500Y26942D01*
X1850250Y26733D01*
X1849958Y26608D01*
X1848917D01*
G01X1849958D02*
X1850583Y25400D01*
G01X1852850D02*
X1853142Y25442D01*
X1853475Y25567D01*
X1853683Y25775D01*
X1853767Y26067D01*
X1853683Y26358D01*
X1853433Y26608D01*
X1853058Y26733D01*
X1852642D01*
X1852392Y26817D01*
X1852183Y27025D01*
X1852100Y27317D01*
X1852225Y27608D01*
X1852517Y27817D01*
X1852850Y27900D01*
X1853183Y27817D01*
X1853475Y27608D01*
X1853600Y27317D01*
X1853517Y27025D01*
X1853308Y26817D01*
X1853058Y26733D01*
X1852642D01*
X1852267Y26608D01*
X1852017Y26358D01*
X1851933Y26067D01*
X1852017Y25775D01*
X1852225Y25567D01*
X1852558Y25442D01*
X1852850Y25400D01*
G01X1855242Y25692D02*
X1855533Y25483D01*
X1855867Y25400D01*
X1856200Y25483D01*
X1856492Y25733D01*
X1856700Y26108D01*
X1856783Y26483D01*
Y26942D01*
X1856700Y27317D01*
X1856492Y27650D01*
X1856242Y27817D01*
X1855950Y27900D01*
X1855617Y27817D01*
X1855367Y27650D01*
X1855200Y27400D01*
X1855117Y27067D01*
X1855200Y26775D01*
X1855408Y26483D01*
X1855658Y26317D01*
X1855950Y26275D01*
X1856283Y26358D01*
X1856533Y26567D01*
X1856783Y26942D01*
G01X1859050Y25400D02*
Y27900D01*
X1858550Y27400D01*
G01Y25400D02*
X1859550D01*
G01X1860300Y24600D02*
X1864300D01*
Y32000D01*
G01X1872517Y13100D02*
Y15600D01*
X1873558D01*
X1873892Y15475D01*
X1874100Y15308D01*
X1874183Y14975D01*
X1874100Y14642D01*
X1873850Y14433D01*
X1873558Y14308D01*
X1872517D01*
G01X1873558D02*
X1874183Y13100D01*
G01X1876450D02*
X1876742Y13142D01*
X1877075Y13267D01*
X1877283Y13475D01*
X1877367Y13767D01*
X1877283Y14058D01*
X1877033Y14308D01*
X1876658Y14433D01*
X1876242D01*
X1875992Y14517D01*
X1875783Y14725D01*
X1875700Y15017D01*
X1875825Y15308D01*
X1876117Y15517D01*
X1876450Y15600D01*
X1876783Y15517D01*
X1877075Y15308D01*
X1877200Y15017D01*
X1877117Y14725D01*
X1876908Y14517D01*
X1876658Y14433D01*
X1876242D01*
X1875867Y14308D01*
X1875617Y14058D01*
X1875533Y13767D01*
X1875617Y13475D01*
X1875825Y13267D01*
X1876158Y13142D01*
X1876450Y13100D01*
G01X1878842Y13392D02*
X1879133Y13183D01*
X1879467Y13100D01*
X1879800Y13183D01*
X1880092Y13433D01*
X1880300Y13808D01*
X1880383Y14183D01*
Y14642D01*
X1880300Y15017D01*
X1880092Y15350D01*
X1879842Y15517D01*
X1879550Y15600D01*
X1879217Y15517D01*
X1878967Y15350D01*
X1878800Y15100D01*
X1878717Y14767D01*
X1878800Y14475D01*
X1879008Y14183D01*
X1879258Y14017D01*
X1879550Y13975D01*
X1879883Y14058D01*
X1880133Y14267D01*
X1880383Y14642D01*
G01X1881858Y15183D02*
X1882108Y15433D01*
X1882400Y15558D01*
X1882733Y15600D01*
X1883150Y15517D01*
X1883442Y15308D01*
X1883525Y15058D01*
X1883483Y14808D01*
X1883317Y14600D01*
X1882483Y14183D01*
X1882108Y13892D01*
X1881858Y13475D01*
X1881775Y13100D01*
X1883525D01*
G01X1876900Y27200D02*
X1872900D01*
Y19800D01*
G01X1827300Y30000D02*
Y34000D01*
X1819900D01*
G01X1821230Y15422D02*
Y17922D01*
X1822271D01*
X1822605Y17797D01*
X1822813Y17630D01*
X1822896Y17297D01*
X1822813Y16964D01*
X1822563Y16755D01*
X1822271Y16630D01*
X1821230D01*
G01X1822271D02*
X1822896Y15422D01*
G01X1825163D02*
Y17922D01*
X1824663Y17422D01*
G01Y15422D02*
X1825663D01*
G01X1828763D02*
Y17922D01*
X1827221Y16130D01*
X1829305D01*
G01X1831363Y17922D02*
X1831030Y17839D01*
X1830780Y17630D01*
X1830613Y17380D01*
X1830488Y17047D01*
X1830446Y16672D01*
X1830488Y16297D01*
X1830613Y15964D01*
X1830780Y15714D01*
X1831030Y15505D01*
X1831363Y15422D01*
X1831696Y15505D01*
X1831946Y15714D01*
X1832113Y15964D01*
X1832238Y16297D01*
X1832280Y16672D01*
X1832238Y17047D01*
X1832113Y17380D01*
X1831946Y17630D01*
X1831696Y17839D01*
X1831363Y17922D01*
G01X1832900Y23100D02*
Y27100D01*
X1825500D01*
G01X1821030Y11122D02*
Y13622D01*
X1822071D01*
X1822405Y13497D01*
X1822613Y13330D01*
X1822696Y12997D01*
X1822613Y12664D01*
X1822363Y12455D01*
X1822071Y12330D01*
X1821030D01*
G01X1822071D02*
X1822696Y11122D01*
G01X1824963D02*
Y13622D01*
X1824463Y13122D01*
G01Y11122D02*
X1825463D01*
G01X1827146Y11622D02*
X1827396Y11330D01*
X1827730Y11164D01*
X1828105Y11122D01*
X1828438Y11164D01*
X1828771Y11372D01*
X1828980Y11622D01*
X1829021Y11872D01*
X1828938Y12164D01*
X1828646Y12372D01*
X1828355Y12455D01*
X1827980D01*
G01X1828355D02*
X1828605Y12580D01*
X1828813Y12789D01*
X1828896Y13039D01*
X1828813Y13289D01*
X1828605Y13497D01*
X1828230Y13622D01*
X1827855Y13580D01*
X1827480Y13414D01*
G01X1830455Y11414D02*
X1830746Y11205D01*
X1831080Y11122D01*
X1831413Y11205D01*
X1831705Y11455D01*
X1831913Y11830D01*
X1831996Y12205D01*
Y12664D01*
X1831913Y13039D01*
X1831705Y13372D01*
X1831455Y13539D01*
X1831163Y13622D01*
X1830830Y13539D01*
X1830580Y13372D01*
X1830413Y13122D01*
X1830330Y12789D01*
X1830413Y12497D01*
X1830621Y12205D01*
X1830871Y12039D01*
X1831163Y11997D01*
X1831496Y12080D01*
X1831746Y12289D01*
X1831996Y12664D01*
G01X1832900Y18900D02*
Y22900D01*
X1825500D01*
G01X1833517Y32400D02*
Y34900D01*
X1834558D01*
X1834892Y34775D01*
X1835100Y34608D01*
X1835183Y34275D01*
X1835100Y33942D01*
X1834850Y33733D01*
X1834558Y33608D01*
X1833517D01*
G01X1834558D02*
X1835183Y32400D01*
G01X1837450D02*
Y34900D01*
X1836950Y34400D01*
G01Y32400D02*
X1837950D01*
G01X1839633Y32900D02*
X1839883Y32608D01*
X1840217Y32442D01*
X1840592Y32400D01*
X1840925Y32442D01*
X1841258Y32650D01*
X1841467Y32900D01*
X1841508Y33150D01*
X1841425Y33442D01*
X1841133Y33650D01*
X1840842Y33733D01*
X1840467D01*
G01X1840842D02*
X1841092Y33858D01*
X1841300Y34067D01*
X1841383Y34317D01*
X1841300Y34567D01*
X1841092Y34775D01*
X1840717Y34900D01*
X1840342Y34858D01*
X1839967Y34692D01*
G01X1842858Y33442D02*
X1843150Y33733D01*
X1843400Y33900D01*
X1843733Y33983D01*
X1844025Y33900D01*
X1844233Y33733D01*
X1844400Y33483D01*
X1844442Y33192D01*
X1844400Y32942D01*
X1844233Y32692D01*
X1843983Y32483D01*
X1843692Y32400D01*
X1843358Y32483D01*
X1843067Y32733D01*
X1842900Y33108D01*
X1842858Y33525D01*
X1842942Y34067D01*
X1843067Y34358D01*
X1843275Y34650D01*
X1843567Y34858D01*
X1843858Y34900D01*
X1844150Y34817D01*
X1844358Y34608D01*
G01X1840400Y27300D02*
Y31300D01*
X1833000D01*
G01X1835211Y15406D02*
Y17906D01*
X1836252D01*
X1836586Y17781D01*
X1836794Y17614D01*
X1836877Y17281D01*
X1836794Y16948D01*
X1836544Y16739D01*
X1836252Y16614D01*
X1835211D01*
G01X1836252D02*
X1836877Y15406D01*
G01X1839144D02*
Y17906D01*
X1838644Y17406D01*
G01Y15406D02*
X1839644D01*
G01X1841327Y15906D02*
X1841577Y15614D01*
X1841911Y15448D01*
X1842286Y15406D01*
X1842619Y15448D01*
X1842952Y15656D01*
X1843161Y15906D01*
X1843202Y16156D01*
X1843119Y16448D01*
X1842827Y16656D01*
X1842536Y16739D01*
X1842161D01*
G01X1842536D02*
X1842786Y16864D01*
X1842994Y17073D01*
X1843077Y17323D01*
X1842994Y17573D01*
X1842786Y17781D01*
X1842411Y17906D01*
X1842036Y17864D01*
X1841661Y17698D01*
G01X1844427Y15781D02*
X1844677Y15573D01*
X1844969Y15448D01*
X1845344Y15406D01*
X1845719Y15489D01*
X1846011Y15656D01*
X1846219Y15948D01*
X1846261Y16281D01*
X1846177Y16614D01*
X1845969Y16823D01*
X1845677Y16989D01*
X1845386Y17031D01*
X1845094Y16989D01*
X1844719Y16823D01*
X1844844Y17906D01*
X1845969D01*
G01X1844300Y23200D02*
Y27200D01*
X1836900D01*
G01X1835311Y11206D02*
Y13706D01*
X1836352D01*
X1836686Y13581D01*
X1836894Y13414D01*
X1836977Y13081D01*
X1836894Y12748D01*
X1836644Y12539D01*
X1836352Y12414D01*
X1835311D01*
G01X1836352D02*
X1836977Y11206D01*
G01X1839244D02*
Y13706D01*
X1838744Y13206D01*
G01Y11206D02*
X1839744D01*
G01X1841427Y11706D02*
X1841677Y11414D01*
X1842011Y11248D01*
X1842386Y11206D01*
X1842719Y11248D01*
X1843052Y11456D01*
X1843261Y11706D01*
X1843302Y11956D01*
X1843219Y12248D01*
X1842927Y12456D01*
X1842636Y12539D01*
X1842261D01*
G01X1842636D02*
X1842886Y12664D01*
X1843094Y12873D01*
X1843177Y13123D01*
X1843094Y13373D01*
X1842886Y13581D01*
X1842511Y13706D01*
X1842136Y13664D01*
X1841761Y13498D01*
G01X1845944Y11206D02*
Y13706D01*
X1844402Y11914D01*
X1846486D01*
G01X1844300Y19100D02*
Y23100D01*
X1836900D01*
G01X1837700Y89900D02*
X1856900D01*
Y101100D01*
X1837700D01*
Y89900D01*
X1838100D01*
G01X1856017Y68500D02*
Y71000D01*
X1857058D01*
X1857392Y70875D01*
X1857600Y70708D01*
X1857683Y70375D01*
X1857600Y70042D01*
X1857350Y69833D01*
X1857058Y69708D01*
X1856017D01*
G01X1857058D02*
X1857683Y68500D01*
G01X1859950D02*
X1860242Y68542D01*
X1860575Y68667D01*
X1860783Y68875D01*
X1860867Y69167D01*
X1860783Y69458D01*
X1860533Y69708D01*
X1860158Y69833D01*
X1859742D01*
X1859492Y69917D01*
X1859283Y70125D01*
X1859200Y70417D01*
X1859325Y70708D01*
X1859617Y70917D01*
X1859950Y71000D01*
X1860283Y70917D01*
X1860575Y70708D01*
X1860700Y70417D01*
X1860617Y70125D01*
X1860408Y69917D01*
X1860158Y69833D01*
X1859742D01*
X1859367Y69708D01*
X1859117Y69458D01*
X1859033Y69167D01*
X1859117Y68875D01*
X1859325Y68667D01*
X1859658Y68542D01*
X1859950Y68500D01*
G01X1862967D02*
X1863050Y69042D01*
X1863175Y69500D01*
X1863342Y69917D01*
X1863550Y70375D01*
X1863883Y71000D01*
X1862217D01*
G01X1865442Y68792D02*
X1865733Y68583D01*
X1866067Y68500D01*
X1866400Y68583D01*
X1866692Y68833D01*
X1866900Y69208D01*
X1866983Y69583D01*
Y70042D01*
X1866900Y70417D01*
X1866692Y70750D01*
X1866442Y70917D01*
X1866150Y71000D01*
X1865817Y70917D01*
X1865567Y70750D01*
X1865400Y70500D01*
X1865317Y70167D01*
X1865400Y69875D01*
X1865608Y69583D01*
X1865858Y69417D01*
X1866150Y69375D01*
X1866483Y69458D01*
X1866733Y69667D01*
X1866983Y70042D01*
G01X1827983Y83500D02*
Y86000D01*
X1828817D01*
X1829150Y85875D01*
X1829400Y85708D01*
X1829608Y85458D01*
X1829775Y85167D01*
X1829817Y84750D01*
X1829775Y84333D01*
X1829608Y84042D01*
X1829400Y83792D01*
X1829150Y83625D01*
X1828817Y83500D01*
X1827983D01*
G01X1831083Y84000D02*
X1831333Y83708D01*
X1831667Y83542D01*
X1832042Y83500D01*
X1832375Y83542D01*
X1832708Y83750D01*
X1832917Y84000D01*
X1832958Y84250D01*
X1832875Y84542D01*
X1832583Y84750D01*
X1832292Y84833D01*
X1831917D01*
G01X1832292D02*
X1832542Y84958D01*
X1832750Y85167D01*
X1832833Y85417D01*
X1832750Y85667D01*
X1832542Y85875D01*
X1832167Y86000D01*
X1831792Y85958D01*
X1831417Y85792D01*
G01X1835600Y83500D02*
Y86000D01*
X1834058Y84208D01*
X1836142D01*
G01X1831900Y97900D02*
Y90900D01*
G01X1869388Y9922D02*
X1866888D01*
Y10756D01*
X1867013Y11089D01*
X1867180Y11339D01*
X1867430Y11547D01*
X1867721Y11714D01*
X1868138Y11756D01*
X1868555Y11714D01*
X1868846Y11547D01*
X1869096Y11339D01*
X1869263Y11089D01*
X1869388Y10756D01*
Y9922D01*
G01X1868888Y13022D02*
X1869180Y13272D01*
X1869346Y13606D01*
X1869388Y13981D01*
X1869346Y14314D01*
X1869138Y14647D01*
X1868888Y14856D01*
X1868638Y14897D01*
X1868346Y14814D01*
X1868138Y14522D01*
X1868055Y14231D01*
Y13856D01*
G01Y14231D02*
X1867930Y14481D01*
X1867721Y14689D01*
X1867471Y14772D01*
X1867221Y14689D01*
X1867013Y14481D01*
X1866888Y14106D01*
X1866930Y13731D01*
X1867096Y13356D01*
G01X1869013Y16122D02*
X1869221Y16372D01*
X1869346Y16664D01*
X1869388Y17039D01*
X1869305Y17414D01*
X1869138Y17706D01*
X1868846Y17914D01*
X1868513Y17956D01*
X1868180Y17872D01*
X1867971Y17664D01*
X1867805Y17372D01*
X1867763Y17081D01*
X1867805Y16789D01*
X1867971Y16414D01*
X1866888Y16539D01*
Y17664D01*
G01X1872300Y35300D02*
Y19200D01*
G01X1865300Y35300D02*
X1872300D01*
G01X1865300Y19200D02*
Y35300D01*
G01X1872300Y19200D02*
X1865300D01*
G01X1819000Y67000D02*
Y78400D01*
G01X1888500Y14850D02*
X1888458Y14517D01*
X1888292Y14225D01*
X1888042Y13975D01*
X1887750Y13808D01*
X1887417Y13725D01*
X1887083D01*
X1886750Y13808D01*
X1886458Y13975D01*
X1886208Y14225D01*
X1886042Y14517D01*
X1886000Y14850D01*
X1886042Y15183D01*
X1886208Y15475D01*
X1886458Y15725D01*
X1886750Y15892D01*
X1887083Y15975D01*
X1887417D01*
X1887750Y15892D01*
X1888042Y15725D01*
X1888292Y15475D01*
X1888458Y15183D01*
X1888500Y14850D01*
G01X1887833Y15183D02*
X1888500Y15683D01*
G01Y17950D02*
X1886000D01*
X1886500Y17450D01*
G01X1888500D02*
Y18450D01*
G01Y21050D02*
X1888458Y21342D01*
X1888333Y21675D01*
X1888125Y21883D01*
X1887833Y21967D01*
X1887542Y21883D01*
X1887292Y21633D01*
X1887167Y21258D01*
Y20842D01*
X1887083Y20592D01*
X1886875Y20383D01*
X1886583Y20300D01*
X1886292Y20425D01*
X1886083Y20717D01*
X1886000Y21050D01*
X1886083Y21383D01*
X1886292Y21675D01*
X1886583Y21800D01*
X1886875Y21717D01*
X1887083Y21508D01*
X1887167Y21258D01*
Y20842D01*
X1887292Y20467D01*
X1887542Y20217D01*
X1887833Y20133D01*
X1888125Y20217D01*
X1888333Y20425D01*
X1888458Y20758D01*
X1888500Y21050D01*
G01X1888125Y23233D02*
X1888333Y23483D01*
X1888458Y23775D01*
X1888500Y24150D01*
X1888417Y24525D01*
X1888250Y24817D01*
X1887958Y25025D01*
X1887625Y25067D01*
X1887292Y24983D01*
X1887083Y24775D01*
X1886917Y24483D01*
X1886875Y24192D01*
X1886917Y23900D01*
X1887083Y23525D01*
X1886000Y23650D01*
Y24775D01*
G01X1889200Y39700D02*
X1877800D01*
G01X1889200Y26300D02*
Y39700D01*
G01X1877800Y26300D02*
X1889200D01*
G01X1877800Y39700D02*
Y26300D01*
G01X1835567Y114292D02*
X1835317Y114417D01*
X1835025Y114500D01*
X1834692D01*
X1834317Y114375D01*
X1834025Y114167D01*
X1833817Y113917D01*
X1833650Y113500D01*
X1833608Y113125D01*
X1833692Y112750D01*
X1833817Y112500D01*
X1834067Y112250D01*
X1834358Y112083D01*
X1834650Y112000D01*
X1834942D01*
X1835233Y112083D01*
X1835483Y112208D01*
X1835692Y112375D01*
G01X1838250Y112000D02*
Y114500D01*
X1836708Y112708D01*
X1838792D01*
G01X1840850Y112000D02*
X1841142Y112042D01*
X1841475Y112167D01*
X1841683Y112375D01*
X1841767Y112667D01*
X1841683Y112958D01*
X1841433Y113208D01*
X1841058Y113333D01*
X1840642D01*
X1840392Y113417D01*
X1840183Y113625D01*
X1840100Y113917D01*
X1840225Y114208D01*
X1840517Y114417D01*
X1840850Y114500D01*
X1841183Y114417D01*
X1841475Y114208D01*
X1841600Y113917D01*
X1841517Y113625D01*
X1841308Y113417D01*
X1841058Y113333D01*
X1840642D01*
X1840267Y113208D01*
X1840017Y112958D01*
X1839933Y112667D01*
X1840017Y112375D01*
X1840225Y112167D01*
X1840558Y112042D01*
X1840850Y112000D01*
G01X1843950D02*
Y114500D01*
X1843450Y114000D01*
G01Y112000D02*
X1844450D01*
G01X1819315Y104026D02*
Y106526D01*
X1820356D01*
X1820690Y106401D01*
X1820898Y106234D01*
X1820981Y105901D01*
X1820898Y105568D01*
X1820648Y105359D01*
X1820356Y105234D01*
X1819315D01*
G01X1820356D02*
X1820981Y104026D01*
G01X1823248D02*
X1823540Y104068D01*
X1823873Y104193D01*
X1824081Y104401D01*
X1824165Y104693D01*
X1824081Y104984D01*
X1823831Y105234D01*
X1823456Y105359D01*
X1823040D01*
X1822790Y105443D01*
X1822581Y105651D01*
X1822498Y105943D01*
X1822623Y106234D01*
X1822915Y106443D01*
X1823248Y106526D01*
X1823581Y106443D01*
X1823873Y106234D01*
X1823998Y105943D01*
X1823915Y105651D01*
X1823706Y105443D01*
X1823456Y105359D01*
X1823040D01*
X1822665Y105234D01*
X1822415Y104984D01*
X1822331Y104693D01*
X1822415Y104401D01*
X1822623Y104193D01*
X1822956Y104068D01*
X1823248Y104026D01*
G01X1825556Y105068D02*
X1825848Y105359D01*
X1826098Y105526D01*
X1826431Y105609D01*
X1826723Y105526D01*
X1826931Y105359D01*
X1827098Y105109D01*
X1827140Y104818D01*
X1827098Y104568D01*
X1826931Y104318D01*
X1826681Y104109D01*
X1826390Y104026D01*
X1826056Y104109D01*
X1825765Y104359D01*
X1825598Y104734D01*
X1825556Y105151D01*
X1825640Y105693D01*
X1825765Y105984D01*
X1825973Y106276D01*
X1826265Y106484D01*
X1826556Y106526D01*
X1826848Y106443D01*
X1827056Y106234D01*
G01X1828531Y104401D02*
X1828781Y104193D01*
X1829073Y104068D01*
X1829448Y104026D01*
X1829823Y104109D01*
X1830115Y104276D01*
X1830323Y104568D01*
X1830365Y104901D01*
X1830281Y105234D01*
X1830073Y105443D01*
X1829781Y105609D01*
X1829490Y105651D01*
X1829198Y105609D01*
X1828823Y105443D01*
X1828948Y106526D01*
X1830073D01*
G01X1832700Y107500D02*
Y111500D01*
X1825300D01*
G01X1820200Y102800D02*
Y98800D01*
X1827600D01*
G01X1862667Y155953D02*
X1862417Y156078D01*
X1862125Y156161D01*
X1861792D01*
X1861417Y156036D01*
X1861125Y155828D01*
X1860917Y155578D01*
X1860750Y155161D01*
X1860708Y154786D01*
X1860792Y154411D01*
X1860917Y154161D01*
X1861167Y153911D01*
X1861458Y153744D01*
X1861750Y153661D01*
X1862042D01*
X1862333Y153744D01*
X1862583Y153869D01*
X1862792Y154036D01*
G01X1865350Y153661D02*
Y156161D01*
X1863808Y154369D01*
X1865892D01*
G01X1867950Y153661D02*
X1868242Y153703D01*
X1868575Y153828D01*
X1868783Y154036D01*
X1868867Y154328D01*
X1868783Y154619D01*
X1868533Y154869D01*
X1868158Y154994D01*
X1867742D01*
X1867492Y155078D01*
X1867283Y155286D01*
X1867200Y155578D01*
X1867325Y155869D01*
X1867617Y156078D01*
X1867950Y156161D01*
X1868283Y156078D01*
X1868575Y155869D01*
X1868700Y155578D01*
X1868617Y155286D01*
X1868408Y155078D01*
X1868158Y154994D01*
X1867742D01*
X1867367Y154869D01*
X1867117Y154619D01*
X1867033Y154328D01*
X1867117Y154036D01*
X1867325Y153828D01*
X1867658Y153703D01*
X1867950Y153661D01*
G01X1870133Y154036D02*
X1870383Y153828D01*
X1870675Y153703D01*
X1871050Y153661D01*
X1871425Y153744D01*
X1871717Y153911D01*
X1871925Y154203D01*
X1871967Y154536D01*
X1871883Y154869D01*
X1871675Y155078D01*
X1871383Y155244D01*
X1871092Y155286D01*
X1870800Y155244D01*
X1870425Y155078D01*
X1870550Y156161D01*
X1871675D01*
G01X1878708Y180267D02*
X1878583Y180017D01*
X1878500Y179725D01*
Y179392D01*
X1878625Y179017D01*
X1878833Y178725D01*
X1879083Y178517D01*
X1879500Y178350D01*
X1879875Y178308D01*
X1880250Y178392D01*
X1880500Y178517D01*
X1880750Y178767D01*
X1880917Y179058D01*
X1881000Y179350D01*
Y179642D01*
X1880917Y179933D01*
X1880792Y180183D01*
X1880625Y180392D01*
G01X1881000Y182950D02*
X1878500D01*
X1880292Y181408D01*
Y183492D01*
G01X1880708Y184842D02*
X1880917Y185133D01*
X1881000Y185467D01*
X1880917Y185800D01*
X1880667Y186092D01*
X1880292Y186300D01*
X1879917Y186383D01*
X1879458D01*
X1879083Y186300D01*
X1878750Y186092D01*
X1878583Y185842D01*
X1878500Y185550D01*
X1878583Y185217D01*
X1878750Y184967D01*
X1879000Y184800D01*
X1879333Y184717D01*
X1879625Y184800D01*
X1879917Y185008D01*
X1880083Y185258D01*
X1880125Y185550D01*
X1880042Y185883D01*
X1879833Y186133D01*
X1879458Y186383D01*
G01X1881000Y188650D02*
X1878500D01*
X1879000Y188150D01*
G01X1881000D02*
Y189150D01*
G01X1875541Y156188D02*
Y153688D01*
G01X1874583Y156188D02*
X1876499D01*
G01X1877808Y153688D02*
Y156188D01*
X1878808D01*
X1879141Y156063D01*
X1879391Y155771D01*
X1879474Y155438D01*
X1879391Y155105D01*
X1879183Y154855D01*
X1878808Y154730D01*
X1877808D01*
G01X1881741Y153688D02*
Y156188D01*
X1881241Y155688D01*
G01Y153688D02*
X1882241D01*
G01X1884133Y153980D02*
X1884424Y153771D01*
X1884758Y153688D01*
X1885091Y153771D01*
X1885383Y154021D01*
X1885591Y154396D01*
X1885674Y154771D01*
Y155230D01*
X1885591Y155605D01*
X1885383Y155938D01*
X1885133Y156105D01*
X1884841Y156188D01*
X1884508Y156105D01*
X1884258Y155938D01*
X1884091Y155688D01*
X1884008Y155355D01*
X1884091Y155063D01*
X1884299Y154771D01*
X1884549Y154605D01*
X1884841Y154563D01*
X1885174Y154646D01*
X1885424Y154855D01*
X1885674Y155230D01*
G01X1887149Y154730D02*
X1887441Y155021D01*
X1887691Y155188D01*
X1888024Y155271D01*
X1888316Y155188D01*
X1888524Y155021D01*
X1888691Y154771D01*
X1888733Y154480D01*
X1888691Y154230D01*
X1888524Y153980D01*
X1888274Y153771D01*
X1887983Y153688D01*
X1887649Y153771D01*
X1887358Y154021D01*
X1887191Y154396D01*
X1887149Y154813D01*
X1887233Y155355D01*
X1887358Y155646D01*
X1887566Y155938D01*
X1887858Y156146D01*
X1888149Y156188D01*
X1888441Y156105D01*
X1888649Y155896D01*
G01X1887500Y110350D02*
X1887458Y110017D01*
X1887292Y109725D01*
X1887042Y109475D01*
X1886750Y109308D01*
X1886417Y109225D01*
X1886083D01*
X1885750Y109308D01*
X1885458Y109475D01*
X1885208Y109725D01*
X1885042Y110017D01*
X1885000Y110350D01*
X1885042Y110683D01*
X1885208Y110975D01*
X1885458Y111225D01*
X1885750Y111392D01*
X1886083Y111475D01*
X1886417D01*
X1886750Y111392D01*
X1887042Y111225D01*
X1887292Y110975D01*
X1887458Y110683D01*
X1887500Y110350D01*
G01X1886833Y110683D02*
X1887500Y111183D01*
G01Y113450D02*
X1885000D01*
X1885500Y112950D01*
G01X1887500D02*
Y113950D01*
G01Y116550D02*
X1887458Y116842D01*
X1887333Y117175D01*
X1887125Y117383D01*
X1886833Y117467D01*
X1886542Y117383D01*
X1886292Y117133D01*
X1886167Y116758D01*
Y116342D01*
X1886083Y116092D01*
X1885875Y115883D01*
X1885583Y115800D01*
X1885292Y115925D01*
X1885083Y116217D01*
X1885000Y116550D01*
X1885083Y116883D01*
X1885292Y117175D01*
X1885583Y117300D01*
X1885875Y117217D01*
X1886083Y117008D01*
X1886167Y116758D01*
Y116342D01*
X1886292Y115967D01*
X1886542Y115717D01*
X1886833Y115633D01*
X1887125Y115717D01*
X1887333Y115925D01*
X1887458Y116258D01*
X1887500Y116550D01*
G01X1887000Y118733D02*
X1887292Y118983D01*
X1887458Y119317D01*
X1887500Y119692D01*
X1887458Y120025D01*
X1887250Y120358D01*
X1887000Y120567D01*
X1886750Y120608D01*
X1886458Y120525D01*
X1886250Y120233D01*
X1886167Y119942D01*
Y119567D01*
G01Y119942D02*
X1886042Y120192D01*
X1885833Y120400D01*
X1885583Y120483D01*
X1885333Y120400D01*
X1885125Y120192D01*
X1885000Y119817D01*
X1885042Y119442D01*
X1885208Y119067D01*
G01X1883700Y101000D02*
X1881600Y102800D01*
X1883700Y105000D01*
G01X1883800Y108600D02*
X1864600D01*
Y97400D01*
X1883800D01*
Y108600D01*
X1883400D01*
G01X1822850Y145500D02*
X1822517Y145542D01*
X1822225Y145708D01*
X1821975Y145958D01*
X1821808Y146250D01*
X1821725Y146583D01*
Y146917D01*
X1821808Y147250D01*
X1821975Y147542D01*
X1822225Y147792D01*
X1822517Y147958D01*
X1822850Y148000D01*
X1823183Y147958D01*
X1823475Y147792D01*
X1823725Y147542D01*
X1823892Y147250D01*
X1823975Y146917D01*
Y146583D01*
X1823892Y146250D01*
X1823725Y145958D01*
X1823475Y145708D01*
X1823183Y145542D01*
X1822850Y145500D01*
G01X1823183Y146167D02*
X1823683Y145500D01*
G01X1825950D02*
Y148000D01*
X1825450Y147500D01*
G01Y145500D02*
X1826450D01*
G01X1829050D02*
X1829342Y145542D01*
X1829675Y145667D01*
X1829883Y145875D01*
X1829967Y146167D01*
X1829883Y146458D01*
X1829633Y146708D01*
X1829258Y146833D01*
X1828842D01*
X1828592Y146917D01*
X1828383Y147125D01*
X1828300Y147417D01*
X1828425Y147708D01*
X1828717Y147917D01*
X1829050Y148000D01*
X1829383Y147917D01*
X1829675Y147708D01*
X1829800Y147417D01*
X1829717Y147125D01*
X1829508Y146917D01*
X1829258Y146833D01*
X1828842D01*
X1828467Y146708D01*
X1828217Y146458D01*
X1828133Y146167D01*
X1828217Y145875D01*
X1828425Y145667D01*
X1828758Y145542D01*
X1829050Y145500D01*
G01X1832150Y148000D02*
X1831817Y147917D01*
X1831567Y147708D01*
X1831400Y147458D01*
X1831275Y147125D01*
X1831233Y146750D01*
X1831275Y146375D01*
X1831400Y146042D01*
X1831567Y145792D01*
X1831817Y145583D01*
X1832150Y145500D01*
X1832483Y145583D01*
X1832733Y145792D01*
X1832900Y146042D01*
X1833025Y146375D01*
X1833067Y146750D01*
X1833025Y147125D01*
X1832900Y147458D01*
X1832733Y147708D01*
X1832483Y147917D01*
X1832150Y148000D01*
G01X1836117Y96799D02*
X1836075Y96466D01*
X1835909Y96174D01*
X1835659Y95924D01*
X1835367Y95757D01*
X1835034Y95674D01*
X1834700D01*
X1834367Y95757D01*
X1834075Y95924D01*
X1833825Y96174D01*
X1833659Y96466D01*
X1833617Y96799D01*
X1833659Y97132D01*
X1833825Y97424D01*
X1834075Y97674D01*
X1834367Y97841D01*
X1834700Y97924D01*
X1835034D01*
X1835367Y97841D01*
X1835659Y97674D01*
X1835909Y97424D01*
X1836075Y97132D01*
X1836117Y96799D01*
G01X1835450Y97132D02*
X1836117Y97632D01*
G01Y99899D02*
X1833617D01*
X1834117Y99399D01*
G01X1836117D02*
Y100399D01*
G01Y102999D02*
X1836075Y103291D01*
X1835950Y103624D01*
X1835742Y103832D01*
X1835450Y103916D01*
X1835159Y103832D01*
X1834909Y103582D01*
X1834784Y103207D01*
Y102791D01*
X1834700Y102541D01*
X1834492Y102332D01*
X1834200Y102249D01*
X1833909Y102374D01*
X1833700Y102666D01*
X1833617Y102999D01*
X1833700Y103332D01*
X1833909Y103624D01*
X1834200Y103749D01*
X1834492Y103666D01*
X1834700Y103457D01*
X1834784Y103207D01*
Y102791D01*
X1834909Y102416D01*
X1835159Y102166D01*
X1835450Y102082D01*
X1835742Y102166D01*
X1835950Y102374D01*
X1836075Y102707D01*
X1836117Y102999D01*
G01X1835075Y105307D02*
X1834784Y105599D01*
X1834617Y105849D01*
X1834534Y106182D01*
X1834617Y106474D01*
X1834784Y106682D01*
X1835034Y106849D01*
X1835325Y106891D01*
X1835575Y106849D01*
X1835825Y106682D01*
X1836034Y106432D01*
X1836117Y106141D01*
X1836034Y105807D01*
X1835784Y105516D01*
X1835409Y105349D01*
X1834992Y105307D01*
X1834450Y105391D01*
X1834159Y105516D01*
X1833867Y105724D01*
X1833659Y106016D01*
X1833617Y106307D01*
X1833700Y106599D01*
X1833909Y106807D01*
G01X1837800Y97500D02*
X1839900Y95700D01*
X1837800Y93500D01*
G01X1862767Y151792D02*
X1862517Y151917D01*
X1862225Y152000D01*
X1861892D01*
X1861517Y151875D01*
X1861225Y151667D01*
X1861017Y151417D01*
X1860850Y151000D01*
X1860808Y150625D01*
X1860892Y150250D01*
X1861017Y150000D01*
X1861267Y149750D01*
X1861558Y149583D01*
X1861850Y149500D01*
X1862142D01*
X1862433Y149583D01*
X1862683Y149708D01*
X1862892Y149875D01*
G01X1865450Y149500D02*
Y152000D01*
X1863908Y150208D01*
X1865992D01*
G01X1868050Y149500D02*
X1868342Y149542D01*
X1868675Y149667D01*
X1868883Y149875D01*
X1868967Y150167D01*
X1868883Y150458D01*
X1868633Y150708D01*
X1868258Y150833D01*
X1867842D01*
X1867592Y150917D01*
X1867383Y151125D01*
X1867300Y151417D01*
X1867425Y151708D01*
X1867717Y151917D01*
X1868050Y152000D01*
X1868383Y151917D01*
X1868675Y151708D01*
X1868800Y151417D01*
X1868717Y151125D01*
X1868508Y150917D01*
X1868258Y150833D01*
X1867842D01*
X1867467Y150708D01*
X1867217Y150458D01*
X1867133Y150167D01*
X1867217Y149875D01*
X1867425Y149667D01*
X1867758Y149542D01*
X1868050Y149500D01*
G01X1870358Y150542D02*
X1870650Y150833D01*
X1870900Y151000D01*
X1871233Y151083D01*
X1871525Y151000D01*
X1871733Y150833D01*
X1871900Y150583D01*
X1871942Y150292D01*
X1871900Y150042D01*
X1871733Y149792D01*
X1871483Y149583D01*
X1871192Y149500D01*
X1870858Y149583D01*
X1870567Y149833D01*
X1870400Y150208D01*
X1870358Y150625D01*
X1870442Y151167D01*
X1870567Y151458D01*
X1870775Y151750D01*
X1871067Y151958D01*
X1871358Y152000D01*
X1871650Y151917D01*
X1871858Y151708D01*
G01X1879300Y121500D02*
X1873800D01*
G01X1879300Y129500D02*
Y121500D01*
G01X1873800Y129500D02*
X1879300D01*
G01X1861700D02*
X1867200D01*
G01X1861700Y121500D02*
Y129500D01*
G01X1867200Y121500D02*
X1861700D01*
G01X1877517Y140500D02*
Y143000D01*
X1878558D01*
X1878892Y142875D01*
X1879100Y142708D01*
X1879183Y142375D01*
X1879100Y142042D01*
X1878850Y141833D01*
X1878558Y141708D01*
X1877517D01*
G01X1878558D02*
X1879183Y140500D01*
G01X1881450D02*
X1881742Y140542D01*
X1882075Y140667D01*
X1882283Y140875D01*
X1882367Y141167D01*
X1882283Y141458D01*
X1882033Y141708D01*
X1881658Y141833D01*
X1881242D01*
X1880992Y141917D01*
X1880783Y142125D01*
X1880700Y142417D01*
X1880825Y142708D01*
X1881117Y142917D01*
X1881450Y143000D01*
X1881783Y142917D01*
X1882075Y142708D01*
X1882200Y142417D01*
X1882117Y142125D01*
X1881908Y141917D01*
X1881658Y141833D01*
X1881242D01*
X1880867Y141708D01*
X1880617Y141458D01*
X1880533Y141167D01*
X1880617Y140875D01*
X1880825Y140667D01*
X1881158Y140542D01*
X1881450Y140500D01*
G01X1884467D02*
X1884550Y141042D01*
X1884675Y141500D01*
X1884842Y141917D01*
X1885050Y142375D01*
X1885383Y143000D01*
X1883717D01*
G01X1888150Y140500D02*
Y143000D01*
X1886608Y141208D01*
X1888692D01*
G01X1881000Y139300D02*
X1889000D01*
Y121700D01*
X1881000D01*
Y139300D01*
G01X1861517Y157500D02*
Y160000D01*
X1862558D01*
X1862892Y159875D01*
X1863100Y159708D01*
X1863183Y159375D01*
X1863100Y159042D01*
X1862850Y158833D01*
X1862558Y158708D01*
X1861517D01*
G01X1862558D02*
X1863183Y157500D01*
G01X1865450D02*
X1865742Y157542D01*
X1866075Y157667D01*
X1866283Y157875D01*
X1866367Y158167D01*
X1866283Y158458D01*
X1866033Y158708D01*
X1865658Y158833D01*
X1865242D01*
X1864992Y158917D01*
X1864783Y159125D01*
X1864700Y159417D01*
X1864825Y159708D01*
X1865117Y159917D01*
X1865450Y160000D01*
X1865783Y159917D01*
X1866075Y159708D01*
X1866200Y159417D01*
X1866117Y159125D01*
X1865908Y158917D01*
X1865658Y158833D01*
X1865242D01*
X1864867Y158708D01*
X1864617Y158458D01*
X1864533Y158167D01*
X1864617Y157875D01*
X1864825Y157667D01*
X1865158Y157542D01*
X1865450Y157500D01*
G01X1868467D02*
X1868550Y158042D01*
X1868675Y158500D01*
X1868842Y158917D01*
X1869050Y159375D01*
X1869383Y160000D01*
X1867717D01*
G01X1870858Y158542D02*
X1871150Y158833D01*
X1871400Y159000D01*
X1871733Y159083D01*
X1872025Y159000D01*
X1872233Y158833D01*
X1872400Y158583D01*
X1872442Y158292D01*
X1872400Y158042D01*
X1872233Y157792D01*
X1871983Y157583D01*
X1871692Y157500D01*
X1871358Y157583D01*
X1871067Y157833D01*
X1870900Y158208D01*
X1870858Y158625D01*
X1870942Y159167D01*
X1871067Y159458D01*
X1871275Y159750D01*
X1871567Y159958D01*
X1871858Y160000D01*
X1872150Y159917D01*
X1872358Y159708D01*
G01X1857200Y136000D02*
Y144000D01*
X1874800D01*
Y136000D01*
X1857200D01*
G01X1845267Y147292D02*
X1845017Y147417D01*
X1844725Y147500D01*
X1844392D01*
X1844017Y147375D01*
X1843725Y147167D01*
X1843517Y146917D01*
X1843350Y146500D01*
X1843308Y146125D01*
X1843392Y145750D01*
X1843517Y145500D01*
X1843767Y145250D01*
X1844058Y145083D01*
X1844350Y145000D01*
X1844642D01*
X1844933Y145083D01*
X1845183Y145208D01*
X1845392Y145375D01*
G01X1847950Y145000D02*
Y147500D01*
X1846408Y145708D01*
X1848492D01*
G01X1850550Y145000D02*
X1850842Y145042D01*
X1851175Y145167D01*
X1851383Y145375D01*
X1851467Y145667D01*
X1851383Y145958D01*
X1851133Y146208D01*
X1850758Y146333D01*
X1850342D01*
X1850092Y146417D01*
X1849883Y146625D01*
X1849800Y146917D01*
X1849925Y147208D01*
X1850217Y147417D01*
X1850550Y147500D01*
X1850883Y147417D01*
X1851175Y147208D01*
X1851300Y146917D01*
X1851217Y146625D01*
X1851008Y146417D01*
X1850758Y146333D01*
X1850342D01*
X1849967Y146208D01*
X1849717Y145958D01*
X1849633Y145667D01*
X1849717Y145375D01*
X1849925Y145167D01*
X1850258Y145042D01*
X1850550Y145000D01*
G01X1852942Y145292D02*
X1853233Y145083D01*
X1853567Y145000D01*
X1853900Y145083D01*
X1854192Y145333D01*
X1854400Y145708D01*
X1854483Y146083D01*
Y146542D01*
X1854400Y146917D01*
X1854192Y147250D01*
X1853942Y147417D01*
X1853650Y147500D01*
X1853317Y147417D01*
X1853067Y147250D01*
X1852900Y147000D01*
X1852817Y146667D01*
X1852900Y146375D01*
X1853108Y146083D01*
X1853358Y145917D01*
X1853650Y145875D01*
X1853983Y145958D01*
X1854233Y146167D01*
X1854483Y146542D01*
G01X1878708Y166267D02*
X1878583Y166017D01*
X1878500Y165725D01*
Y165392D01*
X1878625Y165017D01*
X1878833Y164725D01*
X1879083Y164517D01*
X1879500Y164350D01*
X1879875Y164308D01*
X1880250Y164392D01*
X1880500Y164517D01*
X1880750Y164767D01*
X1880917Y165058D01*
X1881000Y165350D01*
Y165642D01*
X1880917Y165933D01*
X1880792Y166183D01*
X1880625Y166392D01*
G01X1881000Y168950D02*
X1878500D01*
X1880292Y167408D01*
Y169492D01*
G01X1880708Y170842D02*
X1880917Y171133D01*
X1881000Y171467D01*
X1880917Y171800D01*
X1880667Y172092D01*
X1880292Y172300D01*
X1879917Y172383D01*
X1879458D01*
X1879083Y172300D01*
X1878750Y172092D01*
X1878583Y171842D01*
X1878500Y171550D01*
X1878583Y171217D01*
X1878750Y170967D01*
X1879000Y170800D01*
X1879333Y170717D01*
X1879625Y170800D01*
X1879917Y171008D01*
X1880083Y171258D01*
X1880125Y171550D01*
X1880042Y171883D01*
X1879833Y172133D01*
X1879458Y172383D01*
G01X1878500Y174650D02*
X1878583Y174317D01*
X1878792Y174067D01*
X1879042Y173900D01*
X1879375Y173775D01*
X1879750Y173733D01*
X1880125Y173775D01*
X1880458Y173900D01*
X1880708Y174067D01*
X1880917Y174317D01*
X1881000Y174650D01*
X1880917Y174983D01*
X1880708Y175233D01*
X1880458Y175400D01*
X1880125Y175525D01*
X1879750Y175567D01*
X1879375Y175525D01*
X1879042Y175400D01*
X1878792Y175233D01*
X1878583Y174983D01*
X1878500Y174650D01*
G01X1891275Y209000D02*
Y211500D01*
G01X1893025D02*
Y209000D01*
G01Y210250D02*
X1891275D01*
G01X1894333Y209000D02*
Y211500D01*
X1895167D01*
X1895500Y211375D01*
X1895750Y211208D01*
X1895958Y210958D01*
X1896125Y210667D01*
X1896167Y210250D01*
X1896125Y209833D01*
X1895958Y209542D01*
X1895750Y209292D01*
X1895500Y209125D01*
X1895167Y209000D01*
X1894333D01*
G01X1897433D02*
Y211500D01*
X1898267D01*
X1898600Y211375D01*
X1898850Y211208D01*
X1899058Y210958D01*
X1899225Y210667D01*
X1899267Y210250D01*
X1899225Y209833D01*
X1899058Y209542D01*
X1898850Y209292D01*
X1898600Y209125D01*
X1898267Y209000D01*
X1897433D01*
G01X1900575Y209333D02*
X1900908Y209125D01*
X1901283Y209000D01*
X1901617D01*
X1901950Y209125D01*
X1902200Y209333D01*
X1902325Y209625D01*
X1902242Y209917D01*
X1902033Y210167D01*
X1901658Y210333D01*
X1901158Y210417D01*
X1900867Y210583D01*
X1900742Y210875D01*
X1900825Y211167D01*
X1901033Y211375D01*
X1901325Y211500D01*
X1901617D01*
X1901908Y211417D01*
X1902158Y211208D01*
G01X1903508Y209000D02*
X1904550Y211500D01*
X1905592Y209000D01*
G01X1905217Y209875D02*
X1903883D01*
G01X1906775Y209333D02*
X1907108Y209125D01*
X1907483Y209000D01*
X1907817D01*
X1908150Y209125D01*
X1908400Y209333D01*
X1908525Y209625D01*
X1908442Y209917D01*
X1908233Y210167D01*
X1907858Y210333D01*
X1907358Y210417D01*
X1907067Y210583D01*
X1906942Y210875D01*
X1907025Y211167D01*
X1907233Y211375D01*
X1907525Y211500D01*
X1907817D01*
X1908108Y211417D01*
X1908358Y211208D01*
G01X1909833Y209500D02*
X1910083Y209208D01*
X1910417Y209042D01*
X1910792Y209000D01*
X1911125Y209042D01*
X1911458Y209250D01*
X1911667Y209500D01*
X1911708Y209750D01*
X1911625Y210042D01*
X1911333Y210250D01*
X1911042Y210333D01*
X1910667D01*
G01X1911042D02*
X1911292Y210458D01*
X1911500Y210667D01*
X1911583Y210917D01*
X1911500Y211167D01*
X1911292Y211375D01*
X1910917Y211500D01*
X1910542Y211458D01*
X1910167Y211292D01*
G01X1912933Y209375D02*
X1913183Y209167D01*
X1913475Y209042D01*
X1913850Y209000D01*
X1914225Y209083D01*
X1914517Y209250D01*
X1914725Y209542D01*
X1914767Y209875D01*
X1914683Y210208D01*
X1914475Y210417D01*
X1914183Y210583D01*
X1913892Y210625D01*
X1913600Y210583D01*
X1913225Y210417D01*
X1913350Y211500D01*
X1914475D01*
G01X1855967Y268500D02*
Y266000D01*
X1857633D01*
G01X1860733D02*
X1859067D01*
Y268500D01*
X1860733D01*
G01X1860067Y267292D02*
X1859067D01*
G01X1862083Y266000D02*
Y268500D01*
X1862917D01*
X1863250Y268375D01*
X1863500Y268208D01*
X1863708Y267958D01*
X1863875Y267667D01*
X1863917Y267250D01*
X1863875Y266833D01*
X1863708Y266542D01*
X1863500Y266292D01*
X1863250Y266125D01*
X1862917Y266000D01*
X1862083D01*
G01X1865308Y268083D02*
X1865558Y268333D01*
X1865850Y268458D01*
X1866183Y268500D01*
X1866600Y268417D01*
X1866892Y268208D01*
X1866975Y267958D01*
X1866933Y267708D01*
X1866767Y267500D01*
X1865933Y267083D01*
X1865558Y266792D01*
X1865308Y266375D01*
X1865225Y266000D01*
X1866975D01*
G01X1869700D02*
Y268500D01*
X1868158Y266708D01*
X1870242D01*
G01X1857411Y251880D02*
Y263080D01*
X1866211D01*
Y251880D01*
X1857411D01*
G01X1885856Y560075D02*
X1890906D01*
Y658775D01*
X1915556D01*
Y474375D01*
X1890906D01*
Y533075D01*
X1885856D01*
Y560075D01*
G01X1832700Y400717D02*
X1830200D01*
Y401758D01*
X1830325Y402092D01*
X1830492Y402300D01*
X1830825Y402383D01*
X1831158Y402300D01*
X1831367Y402050D01*
X1831492Y401758D01*
Y400717D01*
G01Y401758D02*
X1832700Y402383D01*
G01Y405150D02*
X1830200D01*
X1831992Y403608D01*
Y405692D01*
G01X1832325Y406833D02*
X1832533Y407083D01*
X1832658Y407375D01*
X1832700Y407750D01*
X1832617Y408125D01*
X1832450Y408417D01*
X1832158Y408625D01*
X1831825Y408667D01*
X1831492Y408583D01*
X1831283Y408375D01*
X1831117Y408083D01*
X1831075Y407792D01*
X1831117Y407500D01*
X1831283Y407125D01*
X1830200Y407250D01*
Y408375D01*
G01X1832700Y410850D02*
X1832658Y411142D01*
X1832533Y411475D01*
X1832325Y411683D01*
X1832033Y411767D01*
X1831742Y411683D01*
X1831492Y411433D01*
X1831367Y411058D01*
Y410642D01*
X1831283Y410392D01*
X1831075Y410183D01*
X1830783Y410100D01*
X1830492Y410225D01*
X1830283Y410517D01*
X1830200Y410850D01*
X1830283Y411183D01*
X1830492Y411475D01*
X1830783Y411600D01*
X1831075Y411517D01*
X1831283Y411308D01*
X1831367Y411058D01*
Y410642D01*
X1831492Y410267D01*
X1831742Y410017D01*
X1832033Y409933D01*
X1832325Y410017D01*
X1832533Y410225D01*
X1832658Y410558D01*
X1832700Y410850D01*
G01X1828700Y400717D02*
X1826200D01*
Y401758D01*
X1826325Y402092D01*
X1826492Y402300D01*
X1826825Y402383D01*
X1827158Y402300D01*
X1827367Y402050D01*
X1827492Y401758D01*
Y400717D01*
G01Y401758D02*
X1828700Y402383D01*
G01Y405150D02*
X1826200D01*
X1827992Y403608D01*
Y405692D01*
G01X1828325Y406833D02*
X1828533Y407083D01*
X1828658Y407375D01*
X1828700Y407750D01*
X1828617Y408125D01*
X1828450Y408417D01*
X1828158Y408625D01*
X1827825Y408667D01*
X1827492Y408583D01*
X1827283Y408375D01*
X1827117Y408083D01*
X1827075Y407792D01*
X1827117Y407500D01*
X1827283Y407125D01*
X1826200Y407250D01*
Y408375D01*
G01X1828408Y410142D02*
X1828617Y410433D01*
X1828700Y410767D01*
X1828617Y411100D01*
X1828367Y411392D01*
X1827992Y411600D01*
X1827617Y411683D01*
X1827158D01*
X1826783Y411600D01*
X1826450Y411392D01*
X1826283Y411142D01*
X1826200Y410850D01*
X1826283Y410517D01*
X1826450Y410267D01*
X1826700Y410100D01*
X1827033Y410017D01*
X1827325Y410100D01*
X1827617Y410308D01*
X1827783Y410558D01*
X1827825Y410850D01*
X1827742Y411183D01*
X1827533Y411433D01*
X1827158Y411683D01*
G01X1822500Y386100D02*
Y400100D01*
G01X1879660Y498686D02*
X1879410Y498811D01*
X1879118Y498894D01*
X1878785D01*
X1878410Y498769D01*
X1878118Y498561D01*
X1877910Y498311D01*
X1877743Y497894D01*
X1877701Y497519D01*
X1877785Y497144D01*
X1877910Y496894D01*
X1878160Y496644D01*
X1878451Y496477D01*
X1878743Y496394D01*
X1879035D01*
X1879326Y496477D01*
X1879576Y496602D01*
X1879785Y496769D01*
G01X1880926Y496894D02*
X1881176Y496602D01*
X1881510Y496436D01*
X1881885Y496394D01*
X1882218Y496436D01*
X1882551Y496644D01*
X1882760Y496894D01*
X1882801Y497144D01*
X1882718Y497436D01*
X1882426Y497644D01*
X1882135Y497727D01*
X1881760D01*
G01X1882135D02*
X1882385Y497852D01*
X1882593Y498061D01*
X1882676Y498311D01*
X1882593Y498561D01*
X1882385Y498769D01*
X1882010Y498894D01*
X1881635Y498852D01*
X1881260Y498686D01*
G01X1884151Y498477D02*
X1884401Y498727D01*
X1884693Y498852D01*
X1885026Y498894D01*
X1885443Y498811D01*
X1885735Y498602D01*
X1885818Y498352D01*
X1885776Y498102D01*
X1885610Y497894D01*
X1884776Y497477D01*
X1884401Y497186D01*
X1884151Y496769D01*
X1884068Y496394D01*
X1885818D01*
G01X1888043D02*
X1888335Y496436D01*
X1888668Y496561D01*
X1888876Y496769D01*
X1888960Y497061D01*
X1888876Y497352D01*
X1888626Y497602D01*
X1888251Y497727D01*
X1887835D01*
X1887585Y497811D01*
X1887376Y498019D01*
X1887293Y498311D01*
X1887418Y498602D01*
X1887710Y498811D01*
X1888043Y498894D01*
X1888376Y498811D01*
X1888668Y498602D01*
X1888793Y498311D01*
X1888710Y498019D01*
X1888501Y497811D01*
X1888251Y497727D01*
X1887835D01*
X1887460Y497602D01*
X1887210Y497352D01*
X1887126Y497061D01*
X1887210Y496769D01*
X1887418Y496561D01*
X1887751Y496436D01*
X1888043Y496394D01*
G01X1879501Y503022D02*
X1879251Y503147D01*
X1878959Y503230D01*
X1878626D01*
X1878251Y503105D01*
X1877959Y502897D01*
X1877751Y502647D01*
X1877584Y502230D01*
X1877542Y501855D01*
X1877626Y501480D01*
X1877751Y501230D01*
X1878001Y500980D01*
X1878292Y500813D01*
X1878584Y500730D01*
X1878876D01*
X1879167Y500813D01*
X1879417Y500938D01*
X1879626Y501105D01*
G01X1880767Y501230D02*
X1881017Y500938D01*
X1881351Y500772D01*
X1881726Y500730D01*
X1882059Y500772D01*
X1882392Y500980D01*
X1882601Y501230D01*
X1882642Y501480D01*
X1882559Y501772D01*
X1882267Y501980D01*
X1881976Y502063D01*
X1881601D01*
G01X1881976D02*
X1882226Y502188D01*
X1882434Y502397D01*
X1882517Y502647D01*
X1882434Y502897D01*
X1882226Y503105D01*
X1881851Y503230D01*
X1881476Y503188D01*
X1881101Y503022D01*
G01X1883992Y502813D02*
X1884242Y503063D01*
X1884534Y503188D01*
X1884867Y503230D01*
X1885284Y503147D01*
X1885576Y502938D01*
X1885659Y502688D01*
X1885617Y502438D01*
X1885451Y502230D01*
X1884617Y501813D01*
X1884242Y501522D01*
X1883992Y501105D01*
X1883909Y500730D01*
X1885659D01*
G01X1887801D02*
X1887884Y501272D01*
X1888009Y501730D01*
X1888176Y502147D01*
X1888384Y502605D01*
X1888717Y503230D01*
X1887051D01*
G01X1864267Y531792D02*
X1864017Y531917D01*
X1863725Y532000D01*
X1863392D01*
X1863017Y531875D01*
X1862725Y531667D01*
X1862517Y531417D01*
X1862350Y531000D01*
X1862308Y530625D01*
X1862392Y530250D01*
X1862517Y530000D01*
X1862767Y529750D01*
X1863058Y529583D01*
X1863350Y529500D01*
X1863642D01*
X1863933Y529583D01*
X1864183Y529708D01*
X1864392Y529875D01*
G01X1865533Y530000D02*
X1865783Y529708D01*
X1866117Y529542D01*
X1866492Y529500D01*
X1866825Y529542D01*
X1867158Y529750D01*
X1867367Y530000D01*
X1867408Y530250D01*
X1867325Y530542D01*
X1867033Y530750D01*
X1866742Y530833D01*
X1866367D01*
G01X1866742D02*
X1866992Y530958D01*
X1867200Y531167D01*
X1867283Y531417D01*
X1867200Y531667D01*
X1866992Y531875D01*
X1866617Y532000D01*
X1866242Y531958D01*
X1865867Y531792D01*
G01X1868633Y530000D02*
X1868883Y529708D01*
X1869217Y529542D01*
X1869592Y529500D01*
X1869925Y529542D01*
X1870258Y529750D01*
X1870467Y530000D01*
X1870508Y530250D01*
X1870425Y530542D01*
X1870133Y530750D01*
X1869842Y530833D01*
X1869467D01*
G01X1869842D02*
X1870092Y530958D01*
X1870300Y531167D01*
X1870383Y531417D01*
X1870300Y531667D01*
X1870092Y531875D01*
X1869717Y532000D01*
X1869342Y531958D01*
X1868967Y531792D01*
G01X1871733Y529875D02*
X1871983Y529667D01*
X1872275Y529542D01*
X1872650Y529500D01*
X1873025Y529583D01*
X1873317Y529750D01*
X1873525Y530042D01*
X1873567Y530375D01*
X1873483Y530708D01*
X1873275Y530917D01*
X1872983Y531083D01*
X1872692Y531125D01*
X1872400Y531083D01*
X1872025Y530917D01*
X1872150Y532000D01*
X1873275D01*
G01X1858767Y538792D02*
X1858517Y538917D01*
X1858225Y539000D01*
X1857892D01*
X1857517Y538875D01*
X1857225Y538667D01*
X1857017Y538417D01*
X1856850Y538000D01*
X1856808Y537625D01*
X1856892Y537250D01*
X1857017Y537000D01*
X1857267Y536750D01*
X1857558Y536583D01*
X1857850Y536500D01*
X1858142D01*
X1858433Y536583D01*
X1858683Y536708D01*
X1858892Y536875D01*
G01X1860033Y537000D02*
X1860283Y536708D01*
X1860617Y536542D01*
X1860992Y536500D01*
X1861325Y536542D01*
X1861658Y536750D01*
X1861867Y537000D01*
X1861908Y537250D01*
X1861825Y537542D01*
X1861533Y537750D01*
X1861242Y537833D01*
X1860867D01*
G01X1861242D02*
X1861492Y537958D01*
X1861700Y538167D01*
X1861783Y538417D01*
X1861700Y538667D01*
X1861492Y538875D01*
X1861117Y539000D01*
X1860742Y538958D01*
X1860367Y538792D01*
G01X1863133Y537000D02*
X1863383Y536708D01*
X1863717Y536542D01*
X1864092Y536500D01*
X1864425Y536542D01*
X1864758Y536750D01*
X1864967Y537000D01*
X1865008Y537250D01*
X1864925Y537542D01*
X1864633Y537750D01*
X1864342Y537833D01*
X1863967D01*
G01X1864342D02*
X1864592Y537958D01*
X1864800Y538167D01*
X1864883Y538417D01*
X1864800Y538667D01*
X1864592Y538875D01*
X1864217Y539000D01*
X1863842Y538958D01*
X1863467Y538792D01*
G01X1867067Y536500D02*
X1867150Y537042D01*
X1867275Y537500D01*
X1867442Y537917D01*
X1867650Y538375D01*
X1867983Y539000D01*
X1866317D01*
G01X1835767Y555792D02*
X1835517Y555917D01*
X1835225Y556000D01*
X1834892D01*
X1834517Y555875D01*
X1834225Y555667D01*
X1834017Y555417D01*
X1833850Y555000D01*
X1833808Y554625D01*
X1833892Y554250D01*
X1834017Y554000D01*
X1834267Y553750D01*
X1834558Y553583D01*
X1834850Y553500D01*
X1835142D01*
X1835433Y553583D01*
X1835683Y553708D01*
X1835892Y553875D01*
G01X1837033Y554000D02*
X1837283Y553708D01*
X1837617Y553542D01*
X1837992Y553500D01*
X1838325Y553542D01*
X1838658Y553750D01*
X1838867Y554000D01*
X1838908Y554250D01*
X1838825Y554542D01*
X1838533Y554750D01*
X1838242Y554833D01*
X1837867D01*
G01X1838242D02*
X1838492Y554958D01*
X1838700Y555167D01*
X1838783Y555417D01*
X1838700Y555667D01*
X1838492Y555875D01*
X1838117Y556000D01*
X1837742Y555958D01*
X1837367Y555792D01*
G01X1840133Y554000D02*
X1840383Y553708D01*
X1840717Y553542D01*
X1841092Y553500D01*
X1841425Y553542D01*
X1841758Y553750D01*
X1841967Y554000D01*
X1842008Y554250D01*
X1841925Y554542D01*
X1841633Y554750D01*
X1841342Y554833D01*
X1840967D01*
G01X1841342D02*
X1841592Y554958D01*
X1841800Y555167D01*
X1841883Y555417D01*
X1841800Y555667D01*
X1841592Y555875D01*
X1841217Y556000D01*
X1840842Y555958D01*
X1840467Y555792D01*
G01X1844150Y553500D02*
X1844442Y553542D01*
X1844775Y553667D01*
X1844983Y553875D01*
X1845067Y554167D01*
X1844983Y554458D01*
X1844733Y554708D01*
X1844358Y554833D01*
X1843942D01*
X1843692Y554917D01*
X1843483Y555125D01*
X1843400Y555417D01*
X1843525Y555708D01*
X1843817Y555917D01*
X1844150Y556000D01*
X1844483Y555917D01*
X1844775Y555708D01*
X1844900Y555417D01*
X1844817Y555125D01*
X1844608Y554917D01*
X1844358Y554833D01*
X1843942D01*
X1843567Y554708D01*
X1843317Y554458D01*
X1843233Y554167D01*
X1843317Y553875D01*
X1843525Y553667D01*
X1843858Y553542D01*
X1844150Y553500D01*
G01X1826500Y500017D02*
X1824000D01*
Y501058D01*
X1824125Y501392D01*
X1824292Y501600D01*
X1824625Y501683D01*
X1824958Y501600D01*
X1825167Y501350D01*
X1825292Y501058D01*
Y500017D01*
G01Y501058D02*
X1826500Y501683D01*
G01X1826125Y503033D02*
X1826333Y503283D01*
X1826458Y503575D01*
X1826500Y503950D01*
X1826417Y504325D01*
X1826250Y504617D01*
X1825958Y504825D01*
X1825625Y504867D01*
X1825292Y504783D01*
X1825083Y504575D01*
X1824917Y504283D01*
X1824875Y503992D01*
X1824917Y503700D01*
X1825083Y503325D01*
X1824000Y503450D01*
Y504575D01*
G01X1826500Y507050D02*
X1826458Y507342D01*
X1826333Y507675D01*
X1826125Y507883D01*
X1825833Y507967D01*
X1825542Y507883D01*
X1825292Y507633D01*
X1825167Y507258D01*
Y506842D01*
X1825083Y506592D01*
X1824875Y506383D01*
X1824583Y506300D01*
X1824292Y506425D01*
X1824083Y506717D01*
X1824000Y507050D01*
X1824083Y507383D01*
X1824292Y507675D01*
X1824583Y507800D01*
X1824875Y507717D01*
X1825083Y507508D01*
X1825167Y507258D01*
Y506842D01*
X1825292Y506467D01*
X1825542Y506217D01*
X1825833Y506133D01*
X1826125Y506217D01*
X1826333Y506425D01*
X1826458Y506758D01*
X1826500Y507050D01*
G01Y510067D02*
X1825958Y510150D01*
X1825500Y510275D01*
X1825083Y510442D01*
X1824625Y510650D01*
X1824000Y510983D01*
Y509317D01*
G01X1834000Y511017D02*
X1831500D01*
Y512058D01*
X1831625Y512392D01*
X1831792Y512600D01*
X1832125Y512683D01*
X1832458Y512600D01*
X1832667Y512350D01*
X1832792Y512058D01*
Y511017D01*
G01Y512058D02*
X1834000Y512683D01*
G01X1833625Y514033D02*
X1833833Y514283D01*
X1833958Y514575D01*
X1834000Y514950D01*
X1833917Y515325D01*
X1833750Y515617D01*
X1833458Y515825D01*
X1833125Y515867D01*
X1832792Y515783D01*
X1832583Y515575D01*
X1832417Y515283D01*
X1832375Y514992D01*
X1832417Y514700D01*
X1832583Y514325D01*
X1831500Y514450D01*
Y515575D01*
G01X1833708Y517342D02*
X1833917Y517633D01*
X1834000Y517967D01*
X1833917Y518300D01*
X1833667Y518592D01*
X1833292Y518800D01*
X1832917Y518883D01*
X1832458D01*
X1832083Y518800D01*
X1831750Y518592D01*
X1831583Y518342D01*
X1831500Y518050D01*
X1831583Y517717D01*
X1831750Y517467D01*
X1832000Y517300D01*
X1832333Y517217D01*
X1832625Y517300D01*
X1832917Y517508D01*
X1833083Y517758D01*
X1833125Y518050D01*
X1833042Y518383D01*
X1832833Y518633D01*
X1832458Y518883D01*
G01X1831500Y521150D02*
X1831583Y520817D01*
X1831792Y520567D01*
X1832042Y520400D01*
X1832375Y520275D01*
X1832750Y520233D01*
X1833125Y520275D01*
X1833458Y520400D01*
X1833708Y520567D01*
X1833917Y520817D01*
X1834000Y521150D01*
X1833917Y521483D01*
X1833708Y521733D01*
X1833458Y521900D01*
X1833125Y522025D01*
X1832750Y522067D01*
X1832375Y522025D01*
X1832042Y521900D01*
X1831792Y521733D01*
X1831583Y521483D01*
X1831500Y521150D01*
G01X1821000Y515300D02*
X1825000D01*
Y522700D01*
G01X1833700Y560500D02*
Y564500D01*
X1826300D01*
G01X1823800Y535500D02*
Y531500D01*
X1831200D01*
G01X1830500Y511017D02*
X1828000D01*
Y512058D01*
X1828125Y512392D01*
X1828292Y512600D01*
X1828625Y512683D01*
X1828958Y512600D01*
X1829167Y512350D01*
X1829292Y512058D01*
Y511017D01*
G01Y512058D02*
X1830500Y512683D01*
G01X1830125Y514033D02*
X1830333Y514283D01*
X1830458Y514575D01*
X1830500Y514950D01*
X1830417Y515325D01*
X1830250Y515617D01*
X1829958Y515825D01*
X1829625Y515867D01*
X1829292Y515783D01*
X1829083Y515575D01*
X1828917Y515283D01*
X1828875Y514992D01*
X1828917Y514700D01*
X1829083Y514325D01*
X1828000Y514450D01*
Y515575D01*
G01X1830208Y517342D02*
X1830417Y517633D01*
X1830500Y517967D01*
X1830417Y518300D01*
X1830167Y518592D01*
X1829792Y518800D01*
X1829417Y518883D01*
X1828958D01*
X1828583Y518800D01*
X1828250Y518592D01*
X1828083Y518342D01*
X1828000Y518050D01*
X1828083Y517717D01*
X1828250Y517467D01*
X1828500Y517300D01*
X1828833Y517217D01*
X1829125Y517300D01*
X1829417Y517508D01*
X1829583Y517758D01*
X1829625Y518050D01*
X1829542Y518383D01*
X1829333Y518633D01*
X1828958Y518883D01*
G01X1830000Y520233D02*
X1830292Y520483D01*
X1830458Y520817D01*
X1830500Y521192D01*
X1830458Y521525D01*
X1830250Y521858D01*
X1830000Y522067D01*
X1829750Y522108D01*
X1829458Y522025D01*
X1829250Y521733D01*
X1829167Y521442D01*
Y521067D01*
G01Y521442D02*
X1829042Y521692D01*
X1828833Y521900D01*
X1828583Y521983D01*
X1828333Y521900D01*
X1828125Y521692D01*
X1828000Y521317D01*
X1828042Y520942D01*
X1828208Y520567D01*
G01X1863017Y526000D02*
Y528500D01*
X1864058D01*
X1864392Y528375D01*
X1864600Y528208D01*
X1864683Y527875D01*
X1864600Y527542D01*
X1864350Y527333D01*
X1864058Y527208D01*
X1863017D01*
G01X1864058D02*
X1864683Y526000D01*
G01X1866033Y526375D02*
X1866283Y526167D01*
X1866575Y526042D01*
X1866950Y526000D01*
X1867325Y526083D01*
X1867617Y526250D01*
X1867825Y526542D01*
X1867867Y526875D01*
X1867783Y527208D01*
X1867575Y527417D01*
X1867283Y527583D01*
X1866992Y527625D01*
X1866700Y527583D01*
X1866325Y527417D01*
X1866450Y528500D01*
X1867575D01*
G01X1869342Y526292D02*
X1869633Y526083D01*
X1869967Y526000D01*
X1870300Y526083D01*
X1870592Y526333D01*
X1870800Y526708D01*
X1870883Y527083D01*
Y527542D01*
X1870800Y527917D01*
X1870592Y528250D01*
X1870342Y528417D01*
X1870050Y528500D01*
X1869717Y528417D01*
X1869467Y528250D01*
X1869300Y528000D01*
X1869217Y527667D01*
X1869300Y527375D01*
X1869508Y527083D01*
X1869758Y526917D01*
X1870050Y526875D01*
X1870383Y526958D01*
X1870633Y527167D01*
X1870883Y527542D01*
G01X1872442Y526292D02*
X1872733Y526083D01*
X1873067Y526000D01*
X1873400Y526083D01*
X1873692Y526333D01*
X1873900Y526708D01*
X1873983Y527083D01*
Y527542D01*
X1873900Y527917D01*
X1873692Y528250D01*
X1873442Y528417D01*
X1873150Y528500D01*
X1872817Y528417D01*
X1872567Y528250D01*
X1872400Y528000D01*
X1872317Y527667D01*
X1872400Y527375D01*
X1872608Y527083D01*
X1872858Y526917D01*
X1873150Y526875D01*
X1873483Y526958D01*
X1873733Y527167D01*
X1873983Y527542D01*
G01X1881600Y528600D02*
Y532600D01*
X1874200D01*
G01X1854543Y533045D02*
Y535545D01*
X1855584D01*
X1855918Y535420D01*
X1856126Y535253D01*
X1856209Y534920D01*
X1856126Y534587D01*
X1855876Y534378D01*
X1855584Y534253D01*
X1854543D01*
G01X1855584D02*
X1856209Y533045D01*
G01X1857684Y534087D02*
X1857976Y534378D01*
X1858226Y534545D01*
X1858559Y534628D01*
X1858851Y534545D01*
X1859059Y534378D01*
X1859226Y534128D01*
X1859268Y533837D01*
X1859226Y533587D01*
X1859059Y533337D01*
X1858809Y533128D01*
X1858518Y533045D01*
X1858184Y533128D01*
X1857893Y533378D01*
X1857726Y533753D01*
X1857684Y534170D01*
X1857768Y534712D01*
X1857893Y535003D01*
X1858101Y535295D01*
X1858393Y535503D01*
X1858684Y535545D01*
X1858976Y535462D01*
X1859184Y535253D01*
G01X1861576Y535545D02*
X1861243Y535462D01*
X1860993Y535253D01*
X1860826Y535003D01*
X1860701Y534670D01*
X1860659Y534295D01*
X1860701Y533920D01*
X1860826Y533587D01*
X1860993Y533337D01*
X1861243Y533128D01*
X1861576Y533045D01*
X1861909Y533128D01*
X1862159Y533337D01*
X1862326Y533587D01*
X1862451Y533920D01*
X1862493Y534295D01*
X1862451Y534670D01*
X1862326Y535003D01*
X1862159Y535253D01*
X1861909Y535462D01*
X1861576Y535545D01*
G01X1863884Y534087D02*
X1864176Y534378D01*
X1864426Y534545D01*
X1864759Y534628D01*
X1865051Y534545D01*
X1865259Y534378D01*
X1865426Y534128D01*
X1865468Y533837D01*
X1865426Y533587D01*
X1865259Y533337D01*
X1865009Y533128D01*
X1864718Y533045D01*
X1864384Y533128D01*
X1864093Y533378D01*
X1863926Y533753D01*
X1863884Y534170D01*
X1863968Y534712D01*
X1864093Y535003D01*
X1864301Y535295D01*
X1864593Y535503D01*
X1864884Y535545D01*
X1865176Y535462D01*
X1865384Y535253D01*
G01X1853800Y545500D02*
Y541500D01*
X1861200D01*
G01X1845000Y502517D02*
X1842500D01*
Y503558D01*
X1842625Y503892D01*
X1842792Y504100D01*
X1843125Y504183D01*
X1843458Y504100D01*
X1843667Y503850D01*
X1843792Y503558D01*
Y502517D01*
G01Y503558D02*
X1845000Y504183D01*
G01X1843958Y505658D02*
X1843667Y505950D01*
X1843500Y506200D01*
X1843417Y506533D01*
X1843500Y506825D01*
X1843667Y507033D01*
X1843917Y507200D01*
X1844208Y507242D01*
X1844458Y507200D01*
X1844708Y507033D01*
X1844917Y506783D01*
X1845000Y506492D01*
X1844917Y506158D01*
X1844667Y505867D01*
X1844292Y505700D01*
X1843875Y505658D01*
X1843333Y505742D01*
X1843042Y505867D01*
X1842750Y506075D01*
X1842542Y506367D01*
X1842500Y506658D01*
X1842583Y506950D01*
X1842792Y507158D01*
G01X1842500Y509550D02*
X1842583Y509217D01*
X1842792Y508967D01*
X1843042Y508800D01*
X1843375Y508675D01*
X1843750Y508633D01*
X1844125Y508675D01*
X1844458Y508800D01*
X1844708Y508967D01*
X1844917Y509217D01*
X1845000Y509550D01*
X1844917Y509883D01*
X1844708Y510133D01*
X1844458Y510300D01*
X1844125Y510425D01*
X1843750Y510467D01*
X1843375Y510425D01*
X1843042Y510300D01*
X1842792Y510133D01*
X1842583Y509883D01*
X1842500Y509550D01*
G01X1845000Y512567D02*
X1844458Y512650D01*
X1844000Y512775D01*
X1843583Y512942D01*
X1843125Y513150D01*
X1842500Y513483D01*
Y511817D01*
G01X1851000Y505300D02*
X1855000D01*
Y512700D01*
G01X1841000Y502517D02*
X1838500D01*
Y503558D01*
X1838625Y503892D01*
X1838792Y504100D01*
X1839125Y504183D01*
X1839458Y504100D01*
X1839667Y503850D01*
X1839792Y503558D01*
Y502517D01*
G01Y503558D02*
X1841000Y504183D01*
G01X1839958Y505658D02*
X1839667Y505950D01*
X1839500Y506200D01*
X1839417Y506533D01*
X1839500Y506825D01*
X1839667Y507033D01*
X1839917Y507200D01*
X1840208Y507242D01*
X1840458Y507200D01*
X1840708Y507033D01*
X1840917Y506783D01*
X1841000Y506492D01*
X1840917Y506158D01*
X1840667Y505867D01*
X1840292Y505700D01*
X1839875Y505658D01*
X1839333Y505742D01*
X1839042Y505867D01*
X1838750Y506075D01*
X1838542Y506367D01*
X1838500Y506658D01*
X1838583Y506950D01*
X1838792Y507158D01*
G01X1838500Y509550D02*
X1838583Y509217D01*
X1838792Y508967D01*
X1839042Y508800D01*
X1839375Y508675D01*
X1839750Y508633D01*
X1840125Y508675D01*
X1840458Y508800D01*
X1840708Y508967D01*
X1840917Y509217D01*
X1841000Y509550D01*
X1840917Y509883D01*
X1840708Y510133D01*
X1840458Y510300D01*
X1840125Y510425D01*
X1839750Y510467D01*
X1839375Y510425D01*
X1839042Y510300D01*
X1838792Y510133D01*
X1838583Y509883D01*
X1838500Y509550D01*
G01X1840708Y511942D02*
X1840917Y512233D01*
X1841000Y512567D01*
X1840917Y512900D01*
X1840667Y513192D01*
X1840292Y513400D01*
X1839917Y513483D01*
X1839458D01*
X1839083Y513400D01*
X1838750Y513192D01*
X1838583Y512942D01*
X1838500Y512650D01*
X1838583Y512317D01*
X1838750Y512067D01*
X1839000Y511900D01*
X1839333Y511817D01*
X1839625Y511900D01*
X1839917Y512108D01*
X1840083Y512358D01*
X1840125Y512650D01*
X1840042Y512983D01*
X1839833Y513233D01*
X1839458Y513483D01*
G01X1846500Y505300D02*
X1850500D01*
Y512700D01*
G01X1871000Y500017D02*
X1868500D01*
Y501058D01*
X1868625Y501392D01*
X1868792Y501600D01*
X1869125Y501683D01*
X1869458Y501600D01*
X1869667Y501350D01*
X1869792Y501058D01*
Y500017D01*
G01Y501058D02*
X1871000Y501683D01*
G01X1869958Y503158D02*
X1869667Y503450D01*
X1869500Y503700D01*
X1869417Y504033D01*
X1869500Y504325D01*
X1869667Y504533D01*
X1869917Y504700D01*
X1870208Y504742D01*
X1870458Y504700D01*
X1870708Y504533D01*
X1870917Y504283D01*
X1871000Y503992D01*
X1870917Y503658D01*
X1870667Y503367D01*
X1870292Y503200D01*
X1869875Y503158D01*
X1869333Y503242D01*
X1869042Y503367D01*
X1868750Y503575D01*
X1868542Y503867D01*
X1868500Y504158D01*
X1868583Y504450D01*
X1868792Y504658D01*
G01X1871000Y507050D02*
X1868500D01*
X1869000Y506550D01*
G01X1871000D02*
Y507550D01*
G01Y510150D02*
X1868500D01*
X1869000Y509650D01*
G01X1871000D02*
Y510650D01*
G01X1865000Y512700D02*
X1861000D01*
Y505300D01*
G01X1834517Y526242D02*
Y528742D01*
X1835558D01*
X1835892Y528617D01*
X1836100Y528450D01*
X1836183Y528117D01*
X1836100Y527784D01*
X1835850Y527575D01*
X1835558Y527450D01*
X1834517D01*
G01X1835558D02*
X1836183Y526242D01*
G01X1837658Y527284D02*
X1837950Y527575D01*
X1838200Y527742D01*
X1838533Y527825D01*
X1838825Y527742D01*
X1839033Y527575D01*
X1839200Y527325D01*
X1839242Y527034D01*
X1839200Y526784D01*
X1839033Y526534D01*
X1838783Y526325D01*
X1838492Y526242D01*
X1838158Y526325D01*
X1837867Y526575D01*
X1837700Y526950D01*
X1837658Y527367D01*
X1837742Y527909D01*
X1837867Y528200D01*
X1838075Y528492D01*
X1838367Y528700D01*
X1838658Y528742D01*
X1838950Y528659D01*
X1839158Y528450D01*
G01X1841550Y526242D02*
Y528742D01*
X1841050Y528242D01*
G01Y526242D02*
X1842050D01*
G01X1843733Y526742D02*
X1843983Y526450D01*
X1844317Y526284D01*
X1844692Y526242D01*
X1845025Y526284D01*
X1845358Y526492D01*
X1845567Y526742D01*
X1845608Y526992D01*
X1845525Y527284D01*
X1845233Y527492D01*
X1844942Y527575D01*
X1844567D01*
G01X1844942D02*
X1845192Y527700D01*
X1845400Y527909D01*
X1845483Y528159D01*
X1845400Y528409D01*
X1845192Y528617D01*
X1844817Y528742D01*
X1844442Y528700D01*
X1844067Y528534D01*
G01X1837800Y535500D02*
Y531500D01*
X1845200D01*
G01X1834517Y549500D02*
Y552000D01*
X1835558D01*
X1835892Y551875D01*
X1836100Y551708D01*
X1836183Y551375D01*
X1836100Y551042D01*
X1835850Y550833D01*
X1835558Y550708D01*
X1834517D01*
G01X1835558D02*
X1836183Y549500D01*
G01X1837658Y550542D02*
X1837950Y550833D01*
X1838200Y551000D01*
X1838533Y551083D01*
X1838825Y551000D01*
X1839033Y550833D01*
X1839200Y550583D01*
X1839242Y550292D01*
X1839200Y550042D01*
X1839033Y549792D01*
X1838783Y549583D01*
X1838492Y549500D01*
X1838158Y549583D01*
X1837867Y549833D01*
X1837700Y550208D01*
X1837658Y550625D01*
X1837742Y551167D01*
X1837867Y551458D01*
X1838075Y551750D01*
X1838367Y551958D01*
X1838658Y552000D01*
X1838950Y551917D01*
X1839158Y551708D01*
G01X1841550Y549500D02*
Y552000D01*
X1841050Y551500D01*
G01Y549500D02*
X1842050D01*
G01X1845150D02*
Y552000D01*
X1843608Y550208D01*
X1845692D01*
G01X1853700Y547000D02*
Y551000D01*
X1846300D01*
G01X1836000Y536517D02*
X1833500D01*
Y537558D01*
X1833625Y537892D01*
X1833792Y538100D01*
X1834125Y538183D01*
X1834458Y538100D01*
X1834667Y537850D01*
X1834792Y537558D01*
Y536517D01*
G01Y537558D02*
X1836000Y538183D01*
G01X1834958Y539658D02*
X1834667Y539950D01*
X1834500Y540200D01*
X1834417Y540533D01*
X1834500Y540825D01*
X1834667Y541033D01*
X1834917Y541200D01*
X1835208Y541242D01*
X1835458Y541200D01*
X1835708Y541033D01*
X1835917Y540783D01*
X1836000Y540492D01*
X1835917Y540158D01*
X1835667Y539867D01*
X1835292Y539700D01*
X1834875Y539658D01*
X1834333Y539742D01*
X1834042Y539867D01*
X1833750Y540075D01*
X1833542Y540367D01*
X1833500Y540658D01*
X1833583Y540950D01*
X1833792Y541158D01*
G01X1836000Y543550D02*
X1833500D01*
X1834000Y543050D01*
G01X1836000D02*
Y544050D01*
G01X1835625Y545733D02*
X1835833Y545983D01*
X1835958Y546275D01*
X1836000Y546650D01*
X1835917Y547025D01*
X1835750Y547317D01*
X1835458Y547525D01*
X1835125Y547567D01*
X1834792Y547483D01*
X1834583Y547275D01*
X1834417Y546983D01*
X1834375Y546692D01*
X1834417Y546400D01*
X1834583Y546025D01*
X1833500Y546150D01*
Y547275D01*
G01X1841000Y535800D02*
X1845000D01*
Y543200D01*
G01X1839017Y521242D02*
Y523742D01*
X1840058D01*
X1840392Y523617D01*
X1840600Y523450D01*
X1840683Y523117D01*
X1840600Y522784D01*
X1840350Y522575D01*
X1840058Y522450D01*
X1839017D01*
G01X1840058D02*
X1840683Y521242D01*
G01X1842158Y522284D02*
X1842450Y522575D01*
X1842700Y522742D01*
X1843033Y522825D01*
X1843325Y522742D01*
X1843533Y522575D01*
X1843700Y522325D01*
X1843742Y522034D01*
X1843700Y521784D01*
X1843533Y521534D01*
X1843283Y521325D01*
X1842992Y521242D01*
X1842658Y521325D01*
X1842367Y521575D01*
X1842200Y521950D01*
X1842158Y522367D01*
X1842242Y522909D01*
X1842367Y523200D01*
X1842575Y523492D01*
X1842867Y523700D01*
X1843158Y523742D01*
X1843450Y523659D01*
X1843658Y523450D01*
G01X1846050Y521242D02*
Y523742D01*
X1845550Y523242D01*
G01Y521242D02*
X1846550D01*
G01X1848358Y522284D02*
X1848650Y522575D01*
X1848900Y522742D01*
X1849233Y522825D01*
X1849525Y522742D01*
X1849733Y522575D01*
X1849900Y522325D01*
X1849942Y522034D01*
X1849900Y521784D01*
X1849733Y521534D01*
X1849483Y521325D01*
X1849192Y521242D01*
X1848858Y521325D01*
X1848567Y521575D01*
X1848400Y521950D01*
X1848358Y522367D01*
X1848442Y522909D01*
X1848567Y523200D01*
X1848775Y523492D01*
X1849067Y523700D01*
X1849358Y523742D01*
X1849650Y523659D01*
X1849858Y523450D01*
G01X1855200Y525000D02*
Y529000D01*
X1847800D01*
G01X1869350Y571000D02*
X1869017Y571042D01*
X1868725Y571208D01*
X1868475Y571458D01*
X1868308Y571750D01*
X1868225Y572083D01*
Y572417D01*
X1868308Y572750D01*
X1868475Y573042D01*
X1868725Y573292D01*
X1869017Y573458D01*
X1869350Y573500D01*
X1869683Y573458D01*
X1869975Y573292D01*
X1870225Y573042D01*
X1870392Y572750D01*
X1870475Y572417D01*
Y572083D01*
X1870392Y571750D01*
X1870225Y571458D01*
X1869975Y571208D01*
X1869683Y571042D01*
X1869350Y571000D01*
G01X1869683Y571667D02*
X1870183Y571000D01*
G01X1872450D02*
Y573500D01*
X1871950Y573000D01*
G01Y571000D02*
X1872950D01*
G01X1875550D02*
Y573500D01*
X1875050Y573000D01*
G01Y571000D02*
X1876050D01*
G01X1878650D02*
Y573500D01*
X1878150Y573000D01*
G01Y571000D02*
X1879150D01*
G01X1883700Y554000D02*
X1881600Y555800D01*
X1883700Y558000D01*
G01X1883800Y561600D02*
X1864600D01*
Y550400D01*
X1883800D01*
Y561600D01*
X1883400D01*
G01X1839200Y568400D02*
X1858400D01*
Y579600D01*
X1839200D01*
Y568400D01*
X1839600D01*
G01X1882000Y514517D02*
X1879500D01*
Y515558D01*
X1879625Y515892D01*
X1879792Y516100D01*
X1880125Y516183D01*
X1880458Y516100D01*
X1880667Y515850D01*
X1880792Y515558D01*
Y514517D01*
G01Y515558D02*
X1882000Y516183D01*
G01X1880958Y517658D02*
X1880667Y517950D01*
X1880500Y518200D01*
X1880417Y518533D01*
X1880500Y518825D01*
X1880667Y519033D01*
X1880917Y519200D01*
X1881208Y519242D01*
X1881458Y519200D01*
X1881708Y519033D01*
X1881917Y518783D01*
X1882000Y518492D01*
X1881917Y518158D01*
X1881667Y517867D01*
X1881292Y517700D01*
X1880875Y517658D01*
X1880333Y517742D01*
X1880042Y517867D01*
X1879750Y518075D01*
X1879542Y518367D01*
X1879500Y518658D01*
X1879583Y518950D01*
X1879792Y519158D01*
G01X1879500Y521550D02*
X1879583Y521217D01*
X1879792Y520967D01*
X1880042Y520800D01*
X1880375Y520675D01*
X1880750Y520633D01*
X1881125Y520675D01*
X1881458Y520800D01*
X1881708Y520967D01*
X1881917Y521217D01*
X1882000Y521550D01*
X1881917Y521883D01*
X1881708Y522133D01*
X1881458Y522300D01*
X1881125Y522425D01*
X1880750Y522467D01*
X1880375Y522425D01*
X1880042Y522300D01*
X1879792Y522133D01*
X1879583Y521883D01*
X1879500Y521550D01*
G01X1881500Y523733D02*
X1881792Y523983D01*
X1881958Y524317D01*
X1882000Y524692D01*
X1881958Y525025D01*
X1881750Y525358D01*
X1881500Y525567D01*
X1881250Y525608D01*
X1880958Y525525D01*
X1880750Y525233D01*
X1880667Y524942D01*
Y524567D01*
G01Y524942D02*
X1880542Y525192D01*
X1880333Y525400D01*
X1880083Y525483D01*
X1879833Y525400D01*
X1879625Y525192D01*
X1879500Y524817D01*
X1879542Y524442D01*
X1879708Y524067D01*
G01X1833000Y530500D02*
Y523500D01*
G01X1840000Y536483D02*
X1837500D01*
Y537317D01*
X1837625Y537650D01*
X1837792Y537900D01*
X1838042Y538108D01*
X1838333Y538275D01*
X1838750Y538317D01*
X1839167Y538275D01*
X1839458Y538108D01*
X1839708Y537900D01*
X1839875Y537650D01*
X1840000Y537317D01*
Y536483D01*
G01X1837917Y539708D02*
X1837667Y539958D01*
X1837542Y540250D01*
X1837500Y540583D01*
X1837583Y541000D01*
X1837792Y541292D01*
X1838042Y541375D01*
X1838292Y541333D01*
X1838500Y541167D01*
X1838917Y540333D01*
X1839208Y539958D01*
X1839625Y539708D01*
X1840000Y539625D01*
Y541375D01*
G01X1839500Y542683D02*
X1839792Y542933D01*
X1839958Y543267D01*
X1840000Y543642D01*
X1839958Y543975D01*
X1839750Y544308D01*
X1839500Y544517D01*
X1839250Y544558D01*
X1838958Y544475D01*
X1838750Y544183D01*
X1838667Y543892D01*
Y543517D01*
G01Y543892D02*
X1838542Y544142D01*
X1838333Y544350D01*
X1838083Y544433D01*
X1837833Y544350D01*
X1837625Y544142D01*
X1837500Y543767D01*
X1837542Y543392D01*
X1837708Y543017D01*
G01X1853000Y546000D02*
Y529900D01*
G01X1846000Y546000D02*
X1853000D01*
G01X1846000Y529900D02*
Y546000D01*
G01X1853000Y529900D02*
X1846000D01*
G01X1873000Y513350D02*
X1872958Y513017D01*
X1872792Y512725D01*
X1872542Y512475D01*
X1872250Y512308D01*
X1871917Y512225D01*
X1871583D01*
X1871250Y512308D01*
X1870958Y512475D01*
X1870708Y512725D01*
X1870542Y513017D01*
X1870500Y513350D01*
X1870542Y513683D01*
X1870708Y513975D01*
X1870958Y514225D01*
X1871250Y514392D01*
X1871583Y514475D01*
X1871917D01*
X1872250Y514392D01*
X1872542Y514225D01*
X1872792Y513975D01*
X1872958Y513683D01*
X1873000Y513350D01*
G01X1872333Y513683D02*
X1873000Y514183D01*
G01Y516450D02*
X1870500D01*
X1871000Y515950D01*
G01X1873000D02*
Y516950D01*
G01Y519550D02*
X1870500D01*
X1871000Y519050D01*
G01X1873000D02*
Y520050D01*
G01X1872500Y521733D02*
X1872792Y521983D01*
X1872958Y522317D01*
X1873000Y522692D01*
X1872958Y523025D01*
X1872750Y523358D01*
X1872500Y523567D01*
X1872250Y523608D01*
X1871958Y523525D01*
X1871750Y523233D01*
X1871667Y522942D01*
Y522567D01*
G01Y522942D02*
X1871542Y523192D01*
X1871333Y523400D01*
X1871083Y523483D01*
X1870833Y523400D01*
X1870625Y523192D01*
X1870500Y522817D01*
X1870542Y522442D01*
X1870708Y522067D01*
G01X1869700Y513300D02*
Y524700D01*
G01X1856300Y513300D02*
X1869700D01*
G01X1856300Y524700D02*
Y513300D01*
G01X1869700Y524700D02*
X1856300D01*
G01X1891275Y662000D02*
Y664500D01*
G01X1893025D02*
Y662000D01*
G01Y663250D02*
X1891275D01*
G01X1894333Y662000D02*
Y664500D01*
X1895167D01*
X1895500Y664375D01*
X1895750Y664208D01*
X1895958Y663958D01*
X1896125Y663667D01*
X1896167Y663250D01*
X1896125Y662833D01*
X1895958Y662542D01*
X1895750Y662292D01*
X1895500Y662125D01*
X1895167Y662000D01*
X1894333D01*
G01X1897433D02*
Y664500D01*
X1898267D01*
X1898600Y664375D01*
X1898850Y664208D01*
X1899058Y663958D01*
X1899225Y663667D01*
X1899267Y663250D01*
X1899225Y662833D01*
X1899058Y662542D01*
X1898850Y662292D01*
X1898600Y662125D01*
X1898267Y662000D01*
X1897433D01*
G01X1900575Y662333D02*
X1900908Y662125D01*
X1901283Y662000D01*
X1901617D01*
X1901950Y662125D01*
X1902200Y662333D01*
X1902325Y662625D01*
X1902242Y662917D01*
X1902033Y663167D01*
X1901658Y663333D01*
X1901158Y663417D01*
X1900867Y663583D01*
X1900742Y663875D01*
X1900825Y664167D01*
X1901033Y664375D01*
X1901325Y664500D01*
X1901617D01*
X1901908Y664417D01*
X1902158Y664208D01*
G01X1903508Y662000D02*
X1904550Y664500D01*
X1905592Y662000D01*
G01X1905217Y662875D02*
X1903883D01*
G01X1906775Y662333D02*
X1907108Y662125D01*
X1907483Y662000D01*
X1907817D01*
X1908150Y662125D01*
X1908400Y662333D01*
X1908525Y662625D01*
X1908442Y662917D01*
X1908233Y663167D01*
X1907858Y663333D01*
X1907358Y663417D01*
X1907067Y663583D01*
X1906942Y663875D01*
X1907025Y664167D01*
X1907233Y664375D01*
X1907525Y664500D01*
X1907817D01*
X1908108Y664417D01*
X1908358Y664208D01*
G01X1909958Y664083D02*
X1910208Y664333D01*
X1910500Y664458D01*
X1910833Y664500D01*
X1911250Y664417D01*
X1911542Y664208D01*
X1911625Y663958D01*
X1911583Y663708D01*
X1911417Y663500D01*
X1910583Y663083D01*
X1910208Y662792D01*
X1909958Y662375D01*
X1909875Y662000D01*
X1911625D01*
G01X1912933Y662500D02*
X1913183Y662208D01*
X1913517Y662042D01*
X1913892Y662000D01*
X1914225Y662042D01*
X1914558Y662250D01*
X1914767Y662500D01*
X1914808Y662750D01*
X1914725Y663042D01*
X1914433Y663250D01*
X1914142Y663333D01*
X1913767D01*
G01X1914142D02*
X1914392Y663458D01*
X1914600Y663667D01*
X1914683Y663917D01*
X1914600Y664167D01*
X1914392Y664375D01*
X1914017Y664500D01*
X1913642Y664458D01*
X1913267Y664292D01*
G01X1862267Y609792D02*
X1862017Y609917D01*
X1861725Y610000D01*
X1861392D01*
X1861017Y609875D01*
X1860725Y609667D01*
X1860517Y609417D01*
X1860350Y609000D01*
X1860308Y608625D01*
X1860392Y608250D01*
X1860517Y608000D01*
X1860767Y607750D01*
X1861058Y607583D01*
X1861350Y607500D01*
X1861642D01*
X1861933Y607583D01*
X1862183Y607708D01*
X1862392Y607875D01*
G01X1863533Y608000D02*
X1863783Y607708D01*
X1864117Y607542D01*
X1864492Y607500D01*
X1864825Y607542D01*
X1865158Y607750D01*
X1865367Y608000D01*
X1865408Y608250D01*
X1865325Y608542D01*
X1865033Y608750D01*
X1864742Y608833D01*
X1864367D01*
G01X1864742D02*
X1864992Y608958D01*
X1865200Y609167D01*
X1865283Y609417D01*
X1865200Y609667D01*
X1864992Y609875D01*
X1864617Y610000D01*
X1864242Y609958D01*
X1863867Y609792D01*
G01X1866758Y609583D02*
X1867008Y609833D01*
X1867300Y609958D01*
X1867633Y610000D01*
X1868050Y609917D01*
X1868342Y609708D01*
X1868425Y609458D01*
X1868383Y609208D01*
X1868217Y609000D01*
X1867383Y608583D01*
X1867008Y608292D01*
X1866758Y607875D01*
X1866675Y607500D01*
X1868425D01*
G01X1869942Y607792D02*
X1870233Y607583D01*
X1870567Y607500D01*
X1870900Y607583D01*
X1871192Y607833D01*
X1871400Y608208D01*
X1871483Y608583D01*
Y609042D01*
X1871400Y609417D01*
X1871192Y609750D01*
X1870942Y609917D01*
X1870650Y610000D01*
X1870317Y609917D01*
X1870067Y609750D01*
X1869900Y609500D01*
X1869817Y609167D01*
X1869900Y608875D01*
X1870108Y608583D01*
X1870358Y608417D01*
X1870650Y608375D01*
X1870983Y608458D01*
X1871233Y608667D01*
X1871483Y609042D01*
G01X1880708Y633267D02*
X1880583Y633017D01*
X1880500Y632725D01*
Y632392D01*
X1880625Y632017D01*
X1880833Y631725D01*
X1881083Y631517D01*
X1881500Y631350D01*
X1881875Y631308D01*
X1882250Y631392D01*
X1882500Y631517D01*
X1882750Y631767D01*
X1882917Y632058D01*
X1883000Y632350D01*
Y632642D01*
X1882917Y632933D01*
X1882792Y633183D01*
X1882625Y633392D01*
G01X1882500Y634533D02*
X1882792Y634783D01*
X1882958Y635117D01*
X1883000Y635492D01*
X1882958Y635825D01*
X1882750Y636158D01*
X1882500Y636367D01*
X1882250Y636408D01*
X1881958Y636325D01*
X1881750Y636033D01*
X1881667Y635742D01*
Y635367D01*
G01Y635742D02*
X1881542Y635992D01*
X1881333Y636200D01*
X1881083Y636283D01*
X1880833Y636200D01*
X1880625Y635992D01*
X1880500Y635617D01*
X1880542Y635242D01*
X1880708Y634867D01*
G01X1882500Y637633D02*
X1882792Y637883D01*
X1882958Y638217D01*
X1883000Y638592D01*
X1882958Y638925D01*
X1882750Y639258D01*
X1882500Y639467D01*
X1882250Y639508D01*
X1881958Y639425D01*
X1881750Y639133D01*
X1881667Y638842D01*
Y638467D01*
G01Y638842D02*
X1881542Y639092D01*
X1881333Y639300D01*
X1881083Y639383D01*
X1880833Y639300D01*
X1880625Y639092D01*
X1880500Y638717D01*
X1880542Y638342D01*
X1880708Y637967D01*
G01X1881958Y640858D02*
X1881667Y641150D01*
X1881500Y641400D01*
X1881417Y641733D01*
X1881500Y642025D01*
X1881667Y642233D01*
X1881917Y642400D01*
X1882208Y642442D01*
X1882458Y642400D01*
X1882708Y642233D01*
X1882917Y641983D01*
X1883000Y641692D01*
X1882917Y641358D01*
X1882667Y641067D01*
X1882292Y640900D01*
X1881875Y640858D01*
X1881333Y640942D01*
X1881042Y641067D01*
X1880750Y641275D01*
X1880542Y641567D01*
X1880500Y641858D01*
X1880583Y642150D01*
X1880792Y642358D01*
G01X1875800Y609500D02*
Y607000D01*
G01X1874842Y609500D02*
X1876758D01*
G01X1878067Y607000D02*
Y609500D01*
X1879067D01*
X1879400Y609375D01*
X1879650Y609083D01*
X1879733Y608750D01*
X1879650Y608417D01*
X1879442Y608167D01*
X1879067Y608042D01*
X1878067D01*
G01X1882000Y607000D02*
Y609500D01*
X1881500Y609000D01*
G01Y607000D02*
X1882500D01*
G01X1884183Y607500D02*
X1884433Y607208D01*
X1884767Y607042D01*
X1885142Y607000D01*
X1885475Y607042D01*
X1885808Y607250D01*
X1886017Y607500D01*
X1886058Y607750D01*
X1885975Y608042D01*
X1885683Y608250D01*
X1885392Y608333D01*
X1885017D01*
G01X1885392D02*
X1885642Y608458D01*
X1885850Y608667D01*
X1885933Y608917D01*
X1885850Y609167D01*
X1885642Y609375D01*
X1885267Y609500D01*
X1884892Y609458D01*
X1884517Y609292D01*
G01X1887408Y608042D02*
X1887700Y608333D01*
X1887950Y608500D01*
X1888283Y608583D01*
X1888575Y608500D01*
X1888783Y608333D01*
X1888950Y608083D01*
X1888992Y607792D01*
X1888950Y607542D01*
X1888783Y607292D01*
X1888533Y607083D01*
X1888242Y607000D01*
X1887908Y607083D01*
X1887617Y607333D01*
X1887450Y607708D01*
X1887408Y608125D01*
X1887492Y608667D01*
X1887617Y608958D01*
X1887825Y609250D01*
X1888117Y609458D01*
X1888408Y609500D01*
X1888700Y609417D01*
X1888908Y609208D01*
G01X1825050Y599000D02*
X1824717Y599042D01*
X1824425Y599208D01*
X1824175Y599458D01*
X1824008Y599750D01*
X1823925Y600083D01*
Y600417D01*
X1824008Y600750D01*
X1824175Y601042D01*
X1824425Y601292D01*
X1824717Y601458D01*
X1825050Y601500D01*
X1825383Y601458D01*
X1825675Y601292D01*
X1825925Y601042D01*
X1826092Y600750D01*
X1826175Y600417D01*
Y600083D01*
X1826092Y599750D01*
X1825925Y599458D01*
X1825675Y599208D01*
X1825383Y599042D01*
X1825050Y599000D01*
G01X1825383Y599667D02*
X1825883Y599000D01*
G01X1828150D02*
Y601500D01*
X1827650Y601000D01*
G01Y599000D02*
X1828650D01*
G01X1831250Y601500D02*
X1830917Y601417D01*
X1830667Y601208D01*
X1830500Y600958D01*
X1830375Y600625D01*
X1830333Y600250D01*
X1830375Y599875D01*
X1830500Y599542D01*
X1830667Y599292D01*
X1830917Y599083D01*
X1831250Y599000D01*
X1831583Y599083D01*
X1831833Y599292D01*
X1832000Y599542D01*
X1832125Y599875D01*
X1832167Y600250D01*
X1832125Y600625D01*
X1832000Y600958D01*
X1831833Y601208D01*
X1831583Y601417D01*
X1831250Y601500D01*
G01X1834350Y599000D02*
X1834642Y599042D01*
X1834975Y599167D01*
X1835183Y599375D01*
X1835267Y599667D01*
X1835183Y599958D01*
X1834933Y600208D01*
X1834558Y600333D01*
X1834142D01*
X1833892Y600417D01*
X1833683Y600625D01*
X1833600Y600917D01*
X1833725Y601208D01*
X1834017Y601417D01*
X1834350Y601500D01*
X1834683Y601417D01*
X1834975Y601208D01*
X1835100Y600917D01*
X1835017Y600625D01*
X1834808Y600417D01*
X1834558Y600333D01*
X1834142D01*
X1833767Y600208D01*
X1833517Y599958D01*
X1833433Y599667D01*
X1833517Y599375D01*
X1833725Y599167D01*
X1834058Y599042D01*
X1834350Y599000D01*
G01X1838000Y578850D02*
X1837958Y578517D01*
X1837792Y578225D01*
X1837542Y577975D01*
X1837250Y577808D01*
X1836917Y577725D01*
X1836583D01*
X1836250Y577808D01*
X1835958Y577975D01*
X1835708Y578225D01*
X1835542Y578517D01*
X1835500Y578850D01*
X1835542Y579183D01*
X1835708Y579475D01*
X1835958Y579725D01*
X1836250Y579892D01*
X1836583Y579975D01*
X1836917D01*
X1837250Y579892D01*
X1837542Y579725D01*
X1837792Y579475D01*
X1837958Y579183D01*
X1838000Y578850D01*
G01X1837333Y579183D02*
X1838000Y579683D01*
G01Y581950D02*
X1835500D01*
X1836000Y581450D01*
G01X1838000D02*
Y582450D01*
G01Y585050D02*
X1835500D01*
X1836000Y584550D01*
G01X1838000D02*
Y585550D01*
G01Y588650D02*
X1835500D01*
X1837292Y587108D01*
Y589192D01*
G01X1839300Y576000D02*
X1841400Y574200D01*
X1839300Y572000D01*
G01X1862767Y605453D02*
X1862517Y605578D01*
X1862225Y605661D01*
X1861892D01*
X1861517Y605536D01*
X1861225Y605328D01*
X1861017Y605078D01*
X1860850Y604661D01*
X1860808Y604286D01*
X1860892Y603911D01*
X1861017Y603661D01*
X1861267Y603411D01*
X1861558Y603244D01*
X1861850Y603161D01*
X1862142D01*
X1862433Y603244D01*
X1862683Y603369D01*
X1862892Y603536D01*
G01X1864033Y603661D02*
X1864283Y603369D01*
X1864617Y603203D01*
X1864992Y603161D01*
X1865325Y603203D01*
X1865658Y603411D01*
X1865867Y603661D01*
X1865908Y603911D01*
X1865825Y604203D01*
X1865533Y604411D01*
X1865242Y604494D01*
X1864867D01*
G01X1865242D02*
X1865492Y604619D01*
X1865700Y604828D01*
X1865783Y605078D01*
X1865700Y605328D01*
X1865492Y605536D01*
X1865117Y605661D01*
X1864742Y605619D01*
X1864367Y605453D01*
G01X1867133Y603661D02*
X1867383Y603369D01*
X1867717Y603203D01*
X1868092Y603161D01*
X1868425Y603203D01*
X1868758Y603411D01*
X1868967Y603661D01*
X1869008Y603911D01*
X1868925Y604203D01*
X1868633Y604411D01*
X1868342Y604494D01*
X1867967D01*
G01X1868342D02*
X1868592Y604619D01*
X1868800Y604828D01*
X1868883Y605078D01*
X1868800Y605328D01*
X1868592Y605536D01*
X1868217Y605661D01*
X1867842Y605619D01*
X1867467Y605453D01*
G01X1871150Y605661D02*
X1870817Y605578D01*
X1870567Y605369D01*
X1870400Y605119D01*
X1870275Y604786D01*
X1870233Y604411D01*
X1870275Y604036D01*
X1870400Y603703D01*
X1870567Y603453D01*
X1870817Y603244D01*
X1871150Y603161D01*
X1871483Y603244D01*
X1871733Y603453D01*
X1871900Y603703D01*
X1872025Y604036D01*
X1872067Y604411D01*
X1872025Y604786D01*
X1871900Y605119D01*
X1871733Y605369D01*
X1871483Y605578D01*
X1871150Y605661D01*
G01X1879300Y574500D02*
X1873800D01*
G01X1879300Y582500D02*
Y574500D01*
G01X1873800Y582500D02*
X1879300D01*
G01X1861700D02*
X1867200D01*
G01X1861700Y574500D02*
Y582500D01*
G01X1867200Y574500D02*
X1861700D01*
G01X1878017Y593500D02*
Y596000D01*
X1879058D01*
X1879392Y595875D01*
X1879600Y595708D01*
X1879683Y595375D01*
X1879600Y595042D01*
X1879350Y594833D01*
X1879058Y594708D01*
X1878017D01*
G01X1879058D02*
X1879683Y593500D01*
G01X1881033Y593875D02*
X1881283Y593667D01*
X1881575Y593542D01*
X1881950Y593500D01*
X1882325Y593583D01*
X1882617Y593750D01*
X1882825Y594042D01*
X1882867Y594375D01*
X1882783Y594708D01*
X1882575Y594917D01*
X1882283Y595083D01*
X1881992Y595125D01*
X1881700Y595083D01*
X1881325Y594917D01*
X1881450Y596000D01*
X1882575D01*
G01X1884342Y593792D02*
X1884633Y593583D01*
X1884967Y593500D01*
X1885300Y593583D01*
X1885592Y593833D01*
X1885800Y594208D01*
X1885883Y594583D01*
Y595042D01*
X1885800Y595417D01*
X1885592Y595750D01*
X1885342Y595917D01*
X1885050Y596000D01*
X1884717Y595917D01*
X1884467Y595750D01*
X1884300Y595500D01*
X1884217Y595167D01*
X1884300Y594875D01*
X1884508Y594583D01*
X1884758Y594417D01*
X1885050Y594375D01*
X1885383Y594458D01*
X1885633Y594667D01*
X1885883Y595042D01*
G01X1888150Y593500D02*
X1888442Y593542D01*
X1888775Y593667D01*
X1888983Y593875D01*
X1889067Y594167D01*
X1888983Y594458D01*
X1888733Y594708D01*
X1888358Y594833D01*
X1887942D01*
X1887692Y594917D01*
X1887483Y595125D01*
X1887400Y595417D01*
X1887525Y595708D01*
X1887817Y595917D01*
X1888150Y596000D01*
X1888483Y595917D01*
X1888775Y595708D01*
X1888900Y595417D01*
X1888817Y595125D01*
X1888608Y594917D01*
X1888358Y594833D01*
X1887942D01*
X1887567Y594708D01*
X1887317Y594458D01*
X1887233Y594167D01*
X1887317Y593875D01*
X1887525Y593667D01*
X1887858Y593542D01*
X1888150Y593500D01*
G01X1881000Y592300D02*
X1889000D01*
Y574700D01*
X1881000D01*
Y592300D01*
G01X1861017Y612000D02*
Y614500D01*
X1862058D01*
X1862392Y614375D01*
X1862600Y614208D01*
X1862683Y613875D01*
X1862600Y613542D01*
X1862350Y613333D01*
X1862058Y613208D01*
X1861017D01*
G01X1862058D02*
X1862683Y612000D01*
G01X1864158Y613042D02*
X1864450Y613333D01*
X1864700Y613500D01*
X1865033Y613583D01*
X1865325Y613500D01*
X1865533Y613333D01*
X1865700Y613083D01*
X1865742Y612792D01*
X1865700Y612542D01*
X1865533Y612292D01*
X1865283Y612083D01*
X1864992Y612000D01*
X1864658Y612083D01*
X1864367Y612333D01*
X1864200Y612708D01*
X1864158Y613125D01*
X1864242Y613667D01*
X1864367Y613958D01*
X1864575Y614250D01*
X1864867Y614458D01*
X1865158Y614500D01*
X1865450Y614417D01*
X1865658Y614208D01*
G01X1868050Y614500D02*
X1867717Y614417D01*
X1867467Y614208D01*
X1867300Y613958D01*
X1867175Y613625D01*
X1867133Y613250D01*
X1867175Y612875D01*
X1867300Y612542D01*
X1867467Y612292D01*
X1867717Y612083D01*
X1868050Y612000D01*
X1868383Y612083D01*
X1868633Y612292D01*
X1868800Y612542D01*
X1868925Y612875D01*
X1868967Y613250D01*
X1868925Y613625D01*
X1868800Y613958D01*
X1868633Y614208D01*
X1868383Y614417D01*
X1868050Y614500D01*
G01X1871150D02*
X1870817Y614417D01*
X1870567Y614208D01*
X1870400Y613958D01*
X1870275Y613625D01*
X1870233Y613250D01*
X1870275Y612875D01*
X1870400Y612542D01*
X1870567Y612292D01*
X1870817Y612083D01*
X1871150Y612000D01*
X1871483Y612083D01*
X1871733Y612292D01*
X1871900Y612542D01*
X1872025Y612875D01*
X1872067Y613250D01*
X1872025Y613625D01*
X1871900Y613958D01*
X1871733Y614208D01*
X1871483Y614417D01*
X1871150Y614500D01*
G01X1857200Y589000D02*
Y597000D01*
X1874800D01*
Y589000D01*
X1857200D01*
G01X1845767Y600292D02*
X1845517Y600417D01*
X1845225Y600500D01*
X1844892D01*
X1844517Y600375D01*
X1844225Y600167D01*
X1844017Y599917D01*
X1843850Y599500D01*
X1843808Y599125D01*
X1843892Y598750D01*
X1844017Y598500D01*
X1844267Y598250D01*
X1844558Y598083D01*
X1844850Y598000D01*
X1845142D01*
X1845433Y598083D01*
X1845683Y598208D01*
X1845892Y598375D01*
G01X1847033Y598500D02*
X1847283Y598208D01*
X1847617Y598042D01*
X1847992Y598000D01*
X1848325Y598042D01*
X1848658Y598250D01*
X1848867Y598500D01*
X1848908Y598750D01*
X1848825Y599042D01*
X1848533Y599250D01*
X1848242Y599333D01*
X1847867D01*
G01X1848242D02*
X1848492Y599458D01*
X1848700Y599667D01*
X1848783Y599917D01*
X1848700Y600167D01*
X1848492Y600375D01*
X1848117Y600500D01*
X1847742Y600458D01*
X1847367Y600292D01*
G01X1850133Y598500D02*
X1850383Y598208D01*
X1850717Y598042D01*
X1851092Y598000D01*
X1851425Y598042D01*
X1851758Y598250D01*
X1851967Y598500D01*
X1852008Y598750D01*
X1851925Y599042D01*
X1851633Y599250D01*
X1851342Y599333D01*
X1850967D01*
G01X1851342D02*
X1851592Y599458D01*
X1851800Y599667D01*
X1851883Y599917D01*
X1851800Y600167D01*
X1851592Y600375D01*
X1851217Y600500D01*
X1850842Y600458D01*
X1850467Y600292D01*
G01X1853233Y598500D02*
X1853483Y598208D01*
X1853817Y598042D01*
X1854192Y598000D01*
X1854525Y598042D01*
X1854858Y598250D01*
X1855067Y598500D01*
X1855108Y598750D01*
X1855025Y599042D01*
X1854733Y599250D01*
X1854442Y599333D01*
X1854067D01*
G01X1854442D02*
X1854692Y599458D01*
X1854900Y599667D01*
X1854983Y599917D01*
X1854900Y600167D01*
X1854692Y600375D01*
X1854317Y600500D01*
X1853942Y600458D01*
X1853567Y600292D01*
G01X1878847Y619767D02*
X1878722Y619517D01*
X1878639Y619225D01*
Y618892D01*
X1878764Y618517D01*
X1878972Y618225D01*
X1879222Y618017D01*
X1879639Y617850D01*
X1880014Y617808D01*
X1880389Y617892D01*
X1880639Y618017D01*
X1880889Y618267D01*
X1881056Y618558D01*
X1881139Y618850D01*
Y619142D01*
X1881056Y619433D01*
X1880931Y619683D01*
X1880764Y619892D01*
G01X1880639Y621033D02*
X1880931Y621283D01*
X1881097Y621617D01*
X1881139Y621992D01*
X1881097Y622325D01*
X1880889Y622658D01*
X1880639Y622867D01*
X1880389Y622908D01*
X1880097Y622825D01*
X1879889Y622533D01*
X1879806Y622242D01*
Y621867D01*
G01Y622242D02*
X1879681Y622492D01*
X1879472Y622700D01*
X1879222Y622783D01*
X1878972Y622700D01*
X1878764Y622492D01*
X1878639Y622117D01*
X1878681Y621742D01*
X1878847Y621367D01*
G01X1880639Y624133D02*
X1880931Y624383D01*
X1881097Y624717D01*
X1881139Y625092D01*
X1881097Y625425D01*
X1880889Y625758D01*
X1880639Y625967D01*
X1880389Y626008D01*
X1880097Y625925D01*
X1879889Y625633D01*
X1879806Y625342D01*
Y624967D01*
G01Y625342D02*
X1879681Y625592D01*
X1879472Y625800D01*
X1879222Y625883D01*
X1878972Y625800D01*
X1878764Y625592D01*
X1878639Y625217D01*
X1878681Y624842D01*
X1878847Y624467D01*
G01X1881139Y628650D02*
X1878639D01*
X1880431Y627108D01*
Y629192D01*
G01X1856467Y722000D02*
Y719500D01*
X1858133D01*
G01X1861233D02*
X1859567D01*
Y722000D01*
X1861233D01*
G01X1860567Y720792D02*
X1859567D01*
G01X1862583Y719500D02*
Y722000D01*
X1863417D01*
X1863750Y721875D01*
X1864000Y721708D01*
X1864208Y721458D01*
X1864375Y721167D01*
X1864417Y720750D01*
X1864375Y720333D01*
X1864208Y720042D01*
X1864000Y719792D01*
X1863750Y719625D01*
X1863417Y719500D01*
X1862583D01*
G01X1866600D02*
Y722000D01*
X1866100Y721500D01*
G01Y719500D02*
X1867100D01*
G01X1868908Y721583D02*
X1869158Y721833D01*
X1869450Y721958D01*
X1869783Y722000D01*
X1870200Y721917D01*
X1870492Y721708D01*
X1870575Y721458D01*
X1870533Y721208D01*
X1870367Y721000D01*
X1869533Y720583D01*
X1869158Y720292D01*
X1868908Y719875D01*
X1868825Y719500D01*
X1870575D01*
G01X1857411Y704636D02*
Y715836D01*
X1866211D01*
Y704636D01*
X1857411D01*
G01X1820517Y834500D02*
Y837000D01*
X1821558D01*
X1821892Y836875D01*
X1822100Y836708D01*
X1822183Y836375D01*
X1822100Y836042D01*
X1821850Y835833D01*
X1821558Y835708D01*
X1820517D01*
G01X1821558D02*
X1822183Y834500D01*
G01X1823533Y835000D02*
X1823783Y834708D01*
X1824117Y834542D01*
X1824492Y834500D01*
X1824825Y834542D01*
X1825158Y834750D01*
X1825367Y835000D01*
X1825408Y835250D01*
X1825325Y835542D01*
X1825033Y835750D01*
X1824742Y835833D01*
X1824367D01*
G01X1824742D02*
X1824992Y835958D01*
X1825200Y836167D01*
X1825283Y836417D01*
X1825200Y836667D01*
X1824992Y836875D01*
X1824617Y837000D01*
X1824242Y836958D01*
X1823867Y836792D01*
G01X1826758Y836583D02*
X1827008Y836833D01*
X1827300Y836958D01*
X1827633Y837000D01*
X1828050Y836917D01*
X1828342Y836708D01*
X1828425Y836458D01*
X1828383Y836208D01*
X1828217Y836000D01*
X1827383Y835583D01*
X1827008Y835292D01*
X1826758Y834875D01*
X1826675Y834500D01*
X1828425D01*
G01X1829733Y834875D02*
X1829983Y834667D01*
X1830275Y834542D01*
X1830650Y834500D01*
X1831025Y834583D01*
X1831317Y834750D01*
X1831525Y835042D01*
X1831567Y835375D01*
X1831483Y835708D01*
X1831275Y835917D01*
X1830983Y836083D01*
X1830692Y836125D01*
X1830400Y836083D01*
X1830025Y835917D01*
X1830150Y837000D01*
X1831275D01*
G01X1840124Y834182D02*
Y838182D01*
X1832724D01*
G01X1854857Y853959D02*
Y857959D01*
X1847457D01*
G01X1860700Y852817D02*
X1858200D01*
Y853858D01*
X1858325Y854192D01*
X1858492Y854400D01*
X1858825Y854483D01*
X1859158Y854400D01*
X1859367Y854150D01*
X1859492Y853858D01*
Y852817D01*
G01Y853858D02*
X1860700Y854483D01*
G01X1860200Y855833D02*
X1860492Y856083D01*
X1860658Y856417D01*
X1860700Y856792D01*
X1860658Y857125D01*
X1860450Y857458D01*
X1860200Y857667D01*
X1859950Y857708D01*
X1859658Y857625D01*
X1859450Y857333D01*
X1859367Y857042D01*
Y856667D01*
G01Y857042D02*
X1859242Y857292D01*
X1859033Y857500D01*
X1858783Y857583D01*
X1858533Y857500D01*
X1858325Y857292D01*
X1858200Y856917D01*
X1858242Y856542D01*
X1858408Y856167D01*
G01X1860700Y859767D02*
X1860158Y859850D01*
X1859700Y859975D01*
X1859283Y860142D01*
X1858825Y860350D01*
X1858200Y860683D01*
Y859017D01*
G01X1860325Y862033D02*
X1860533Y862283D01*
X1860658Y862575D01*
X1860700Y862950D01*
X1860617Y863325D01*
X1860450Y863617D01*
X1860158Y863825D01*
X1859825Y863867D01*
X1859492Y863783D01*
X1859283Y863575D01*
X1859117Y863283D01*
X1859075Y862992D01*
X1859117Y862700D01*
X1859283Y862325D01*
X1858200Y862450D01*
Y863575D01*
G01X1864700Y852817D02*
X1862200D01*
Y853858D01*
X1862325Y854192D01*
X1862492Y854400D01*
X1862825Y854483D01*
X1863158Y854400D01*
X1863367Y854150D01*
X1863492Y853858D01*
Y852817D01*
G01Y853858D02*
X1864700Y854483D01*
G01X1864200Y855833D02*
X1864492Y856083D01*
X1864658Y856417D01*
X1864700Y856792D01*
X1864658Y857125D01*
X1864450Y857458D01*
X1864200Y857667D01*
X1863950Y857708D01*
X1863658Y857625D01*
X1863450Y857333D01*
X1863367Y857042D01*
Y856667D01*
G01Y857042D02*
X1863242Y857292D01*
X1863033Y857500D01*
X1862783Y857583D01*
X1862533Y857500D01*
X1862325Y857292D01*
X1862200Y856917D01*
X1862242Y856542D01*
X1862408Y856167D01*
G01X1864700Y859850D02*
X1864658Y860142D01*
X1864533Y860475D01*
X1864325Y860683D01*
X1864033Y860767D01*
X1863742Y860683D01*
X1863492Y860433D01*
X1863367Y860058D01*
Y859642D01*
X1863283Y859392D01*
X1863075Y859183D01*
X1862783Y859100D01*
X1862492Y859225D01*
X1862283Y859517D01*
X1862200Y859850D01*
X1862283Y860183D01*
X1862492Y860475D01*
X1862783Y860600D01*
X1863075Y860517D01*
X1863283Y860308D01*
X1863367Y860058D01*
Y859642D01*
X1863492Y859267D01*
X1863742Y859017D01*
X1864033Y858933D01*
X1864325Y859017D01*
X1864533Y859225D01*
X1864658Y859558D01*
X1864700Y859850D01*
G01X1862200Y862950D02*
X1862283Y862617D01*
X1862492Y862367D01*
X1862742Y862200D01*
X1863075Y862075D01*
X1863450Y862033D01*
X1863825Y862075D01*
X1864158Y862200D01*
X1864408Y862367D01*
X1864617Y862617D01*
X1864700Y862950D01*
X1864617Y863283D01*
X1864408Y863533D01*
X1864158Y863700D01*
X1863825Y863825D01*
X1863450Y863867D01*
X1863075Y863825D01*
X1862742Y863700D01*
X1862492Y863533D01*
X1862283Y863283D01*
X1862200Y862950D01*
G01X1845850Y834500D02*
X1845517Y834542D01*
X1845225Y834708D01*
X1844975Y834958D01*
X1844808Y835250D01*
X1844725Y835583D01*
Y835917D01*
X1844808Y836250D01*
X1844975Y836542D01*
X1845225Y836792D01*
X1845517Y836958D01*
X1845850Y837000D01*
X1846183Y836958D01*
X1846475Y836792D01*
X1846725Y836542D01*
X1846892Y836250D01*
X1846975Y835917D01*
Y835583D01*
X1846892Y835250D01*
X1846725Y834958D01*
X1846475Y834708D01*
X1846183Y834542D01*
X1845850Y834500D01*
G01X1846183Y835167D02*
X1846683Y834500D01*
G01X1848158Y836583D02*
X1848408Y836833D01*
X1848700Y836958D01*
X1849033Y837000D01*
X1849450Y836917D01*
X1849742Y836708D01*
X1849825Y836458D01*
X1849783Y836208D01*
X1849617Y836000D01*
X1848783Y835583D01*
X1848408Y835292D01*
X1848158Y834875D01*
X1848075Y834500D01*
X1849825D01*
G01X1851133Y835000D02*
X1851383Y834708D01*
X1851717Y834542D01*
X1852092Y834500D01*
X1852425Y834542D01*
X1852758Y834750D01*
X1852967Y835000D01*
X1853008Y835250D01*
X1852925Y835542D01*
X1852633Y835750D01*
X1852342Y835833D01*
X1851967D01*
G01X1852342D02*
X1852592Y835958D01*
X1852800Y836167D01*
X1852883Y836417D01*
X1852800Y836667D01*
X1852592Y836875D01*
X1852217Y837000D01*
X1851842Y836958D01*
X1851467Y836792D01*
G01X1855150Y837000D02*
X1854817Y836917D01*
X1854567Y836708D01*
X1854400Y836458D01*
X1854275Y836125D01*
X1854233Y835750D01*
X1854275Y835375D01*
X1854400Y835042D01*
X1854567Y834792D01*
X1854817Y834583D01*
X1855150Y834500D01*
X1855483Y834583D01*
X1855733Y834792D01*
X1855900Y835042D01*
X1856025Y835375D01*
X1856067Y835750D01*
X1856025Y836125D01*
X1855900Y836458D01*
X1855733Y836708D01*
X1855483Y836917D01*
X1855150Y837000D01*
G01X1855532Y838500D02*
Y852500D01*
G01X1842532Y838500D02*
X1855532D01*
G01X1842532Y852500D02*
Y838500D01*
G01X1855532Y852500D02*
X1842532D01*
G01X1829450Y855500D02*
X1829117Y855542D01*
X1828825Y855708D01*
X1828575Y855958D01*
X1828408Y856250D01*
X1828325Y856583D01*
Y856917D01*
X1828408Y857250D01*
X1828575Y857542D01*
X1828825Y857792D01*
X1829117Y857958D01*
X1829450Y858000D01*
X1829783Y857958D01*
X1830075Y857792D01*
X1830325Y857542D01*
X1830492Y857250D01*
X1830575Y856917D01*
Y856583D01*
X1830492Y856250D01*
X1830325Y855958D01*
X1830075Y855708D01*
X1829783Y855542D01*
X1829450Y855500D01*
G01X1829783Y856167D02*
X1830283Y855500D01*
G01X1831758Y857583D02*
X1832008Y857833D01*
X1832300Y857958D01*
X1832633Y858000D01*
X1833050Y857917D01*
X1833342Y857708D01*
X1833425Y857458D01*
X1833383Y857208D01*
X1833217Y857000D01*
X1832383Y856583D01*
X1832008Y856292D01*
X1831758Y855875D01*
X1831675Y855500D01*
X1833425D01*
G01X1834733Y855875D02*
X1834983Y855667D01*
X1835275Y855542D01*
X1835650Y855500D01*
X1836025Y855583D01*
X1836317Y855750D01*
X1836525Y856042D01*
X1836567Y856375D01*
X1836483Y856708D01*
X1836275Y856917D01*
X1835983Y857083D01*
X1835692Y857125D01*
X1835400Y857083D01*
X1835025Y856917D01*
X1835150Y858000D01*
X1836275D01*
G01X1839250Y855500D02*
Y858000D01*
X1837708Y856208D01*
X1839792D01*
G01X1827424Y839407D02*
X1841424D01*
G01X1827424Y852407D02*
Y839407D01*
G01X1841424Y852407D02*
X1827424D01*
G01X1841424Y839407D02*
Y852407D01*
G01X1885856Y1012831D02*
X1890906D01*
Y1111531D01*
X1915556D01*
Y927131D01*
X1890906D01*
Y985831D01*
X1885856D01*
Y1012831D01*
G01X1879267Y950792D02*
X1879017Y950917D01*
X1878725Y951000D01*
X1878392D01*
X1878017Y950875D01*
X1877725Y950667D01*
X1877517Y950417D01*
X1877350Y950000D01*
X1877308Y949625D01*
X1877392Y949250D01*
X1877517Y949000D01*
X1877767Y948750D01*
X1878058Y948583D01*
X1878350Y948500D01*
X1878642D01*
X1878933Y948583D01*
X1879183Y948708D01*
X1879392Y948875D01*
G01X1881450Y948500D02*
Y951000D01*
X1880950Y950500D01*
G01Y948500D02*
X1881950D01*
G01X1884467D02*
X1884550Y949042D01*
X1884675Y949500D01*
X1884842Y949917D01*
X1885050Y950375D01*
X1885383Y951000D01*
X1883717D01*
G01X1886858Y950583D02*
X1887108Y950833D01*
X1887400Y950958D01*
X1887733Y951000D01*
X1888150Y950917D01*
X1888442Y950708D01*
X1888525Y950458D01*
X1888483Y950208D01*
X1888317Y950000D01*
X1887483Y949583D01*
X1887108Y949292D01*
X1886858Y948875D01*
X1886775Y948500D01*
X1888525D01*
G01X1879267Y954792D02*
X1879017Y954917D01*
X1878725Y955000D01*
X1878392D01*
X1878017Y954875D01*
X1877725Y954667D01*
X1877517Y954417D01*
X1877350Y954000D01*
X1877308Y953625D01*
X1877392Y953250D01*
X1877517Y953000D01*
X1877767Y952750D01*
X1878058Y952583D01*
X1878350Y952500D01*
X1878642D01*
X1878933Y952583D01*
X1879183Y952708D01*
X1879392Y952875D01*
G01X1881450Y952500D02*
Y955000D01*
X1880950Y954500D01*
G01Y952500D02*
X1881950D01*
G01X1884467D02*
X1884550Y953042D01*
X1884675Y953500D01*
X1884842Y953917D01*
X1885050Y954375D01*
X1885383Y955000D01*
X1883717D01*
G01X1887650Y952500D02*
Y955000D01*
X1887150Y954500D01*
G01Y952500D02*
X1888150D01*
G01X1831223Y879015D02*
X1830973Y879140D01*
X1830681Y879223D01*
X1830348D01*
X1829973Y879098D01*
X1829681Y878890D01*
X1829473Y878640D01*
X1829306Y878223D01*
X1829264Y877848D01*
X1829348Y877473D01*
X1829473Y877223D01*
X1829723Y876973D01*
X1830014Y876806D01*
X1830306Y876723D01*
X1830598D01*
X1830889Y876806D01*
X1831139Y876931D01*
X1831348Y877098D01*
G01X1832614Y877765D02*
X1832906Y878056D01*
X1833156Y878223D01*
X1833489Y878306D01*
X1833781Y878223D01*
X1833989Y878056D01*
X1834156Y877806D01*
X1834198Y877515D01*
X1834156Y877265D01*
X1833989Y877015D01*
X1833739Y876806D01*
X1833448Y876723D01*
X1833114Y876806D01*
X1832823Y877056D01*
X1832656Y877431D01*
X1832614Y877848D01*
X1832698Y878390D01*
X1832823Y878681D01*
X1833031Y878973D01*
X1833323Y879181D01*
X1833614Y879223D01*
X1833906Y879140D01*
X1834114Y878931D01*
G01X1835714Y877765D02*
X1836006Y878056D01*
X1836256Y878223D01*
X1836589Y878306D01*
X1836881Y878223D01*
X1837089Y878056D01*
X1837256Y877806D01*
X1837298Y877515D01*
X1837256Y877265D01*
X1837089Y877015D01*
X1836839Y876806D01*
X1836548Y876723D01*
X1836214Y876806D01*
X1835923Y877056D01*
X1835756Y877431D01*
X1835714Y877848D01*
X1835798Y878390D01*
X1835923Y878681D01*
X1836131Y878973D01*
X1836423Y879181D01*
X1836714Y879223D01*
X1837006Y879140D01*
X1837214Y878931D01*
G01X1839606Y876723D02*
Y879223D01*
X1839106Y878723D01*
G01Y876723D02*
X1840106D01*
G01X1831195Y873988D02*
X1830945Y874113D01*
X1830653Y874196D01*
X1830320D01*
X1829945Y874071D01*
X1829653Y873863D01*
X1829445Y873613D01*
X1829278Y873196D01*
X1829236Y872821D01*
X1829320Y872446D01*
X1829445Y872196D01*
X1829695Y871946D01*
X1829986Y871779D01*
X1830278Y871696D01*
X1830570D01*
X1830861Y871779D01*
X1831111Y871904D01*
X1831320Y872071D01*
G01X1832586Y872738D02*
X1832878Y873029D01*
X1833128Y873196D01*
X1833461Y873279D01*
X1833753Y873196D01*
X1833961Y873029D01*
X1834128Y872779D01*
X1834170Y872488D01*
X1834128Y872238D01*
X1833961Y871988D01*
X1833711Y871779D01*
X1833420Y871696D01*
X1833086Y871779D01*
X1832795Y872029D01*
X1832628Y872404D01*
X1832586Y872821D01*
X1832670Y873363D01*
X1832795Y873654D01*
X1833003Y873946D01*
X1833295Y874154D01*
X1833586Y874196D01*
X1833878Y874113D01*
X1834086Y873904D01*
G01X1835686Y872738D02*
X1835978Y873029D01*
X1836228Y873196D01*
X1836561Y873279D01*
X1836853Y873196D01*
X1837061Y873029D01*
X1837228Y872779D01*
X1837270Y872488D01*
X1837228Y872238D01*
X1837061Y871988D01*
X1836811Y871779D01*
X1836520Y871696D01*
X1836186Y871779D01*
X1835895Y872029D01*
X1835728Y872404D01*
X1835686Y872821D01*
X1835770Y873363D01*
X1835895Y873654D01*
X1836103Y873946D01*
X1836395Y874154D01*
X1836686Y874196D01*
X1836978Y874113D01*
X1837186Y873904D01*
G01X1838786Y873779D02*
X1839036Y874029D01*
X1839328Y874154D01*
X1839661Y874196D01*
X1840078Y874113D01*
X1840370Y873904D01*
X1840453Y873654D01*
X1840411Y873404D01*
X1840245Y873196D01*
X1839411Y872779D01*
X1839036Y872488D01*
X1838786Y872071D01*
X1838703Y871696D01*
X1840453D01*
G01X1861500Y945517D02*
X1859000D01*
Y946558D01*
X1859125Y946892D01*
X1859292Y947100D01*
X1859625Y947183D01*
X1859958Y947100D01*
X1860167Y946850D01*
X1860292Y946558D01*
Y945517D01*
G01Y946558D02*
X1861500Y947183D01*
G01X1861000Y948533D02*
X1861292Y948783D01*
X1861458Y949117D01*
X1861500Y949492D01*
X1861458Y949825D01*
X1861250Y950158D01*
X1861000Y950367D01*
X1860750Y950408D01*
X1860458Y950325D01*
X1860250Y950033D01*
X1860167Y949742D01*
Y949367D01*
G01Y949742D02*
X1860042Y949992D01*
X1859833Y950200D01*
X1859583Y950283D01*
X1859333Y950200D01*
X1859125Y949992D01*
X1859000Y949617D01*
X1859042Y949242D01*
X1859208Y948867D01*
G01X1861500Y953050D02*
X1859000D01*
X1860792Y951508D01*
Y953592D01*
G01X1861000Y954733D02*
X1861292Y954983D01*
X1861458Y955317D01*
X1861500Y955692D01*
X1861458Y956025D01*
X1861250Y956358D01*
X1861000Y956567D01*
X1860750Y956608D01*
X1860458Y956525D01*
X1860250Y956233D01*
X1860167Y955942D01*
Y955567D01*
G01Y955942D02*
X1860042Y956192D01*
X1859833Y956400D01*
X1859583Y956483D01*
X1859333Y956400D01*
X1859125Y956192D01*
X1859000Y955817D01*
X1859042Y955442D01*
X1859208Y955067D01*
G01X1822967Y916000D02*
Y918500D01*
X1824008D01*
X1824342Y918375D01*
X1824550Y918208D01*
X1824633Y917875D01*
X1824550Y917542D01*
X1824300Y917333D01*
X1824008Y917208D01*
X1822967D01*
G01X1824008D02*
X1824633Y916000D01*
G01X1826900D02*
Y918500D01*
X1826400Y918000D01*
G01Y916000D02*
X1827400D01*
G01X1830000D02*
Y918500D01*
X1829500Y918000D01*
G01Y916000D02*
X1830500D01*
G01X1832183Y916500D02*
X1832433Y916208D01*
X1832767Y916042D01*
X1833142Y916000D01*
X1833475Y916042D01*
X1833808Y916250D01*
X1834017Y916500D01*
X1834058Y916750D01*
X1833975Y917042D01*
X1833683Y917250D01*
X1833392Y917333D01*
X1833017D01*
G01X1833392D02*
X1833642Y917458D01*
X1833850Y917667D01*
X1833933Y917917D01*
X1833850Y918167D01*
X1833642Y918375D01*
X1833267Y918500D01*
X1832892Y918458D01*
X1832517Y918292D01*
G01X1835408Y917042D02*
X1835700Y917333D01*
X1835950Y917500D01*
X1836283Y917583D01*
X1836575Y917500D01*
X1836783Y917333D01*
X1836950Y917083D01*
X1836992Y916792D01*
X1836950Y916542D01*
X1836783Y916292D01*
X1836533Y916083D01*
X1836242Y916000D01*
X1835908Y916083D01*
X1835617Y916333D01*
X1835450Y916708D01*
X1835408Y917125D01*
X1835492Y917667D01*
X1835617Y917958D01*
X1835825Y918250D01*
X1836117Y918458D01*
X1836408Y918500D01*
X1836700Y918417D01*
X1836908Y918208D01*
G01X1826763Y909925D02*
Y913925D01*
X1819363D01*
G01X1832467Y902500D02*
Y905000D01*
X1833508D01*
X1833842Y904875D01*
X1834050Y904708D01*
X1834133Y904375D01*
X1834050Y904042D01*
X1833800Y903833D01*
X1833508Y903708D01*
X1832467D01*
G01X1833508D02*
X1834133Y902500D01*
G01X1836400D02*
Y905000D01*
X1835900Y904500D01*
G01Y902500D02*
X1836900D01*
G01X1839500D02*
Y905000D01*
X1839000Y904500D01*
G01Y902500D02*
X1840000D01*
G01X1843100D02*
Y905000D01*
X1841558Y903208D01*
X1843642D01*
G01X1845700Y905000D02*
X1845367Y904917D01*
X1845117Y904708D01*
X1844950Y904458D01*
X1844825Y904125D01*
X1844783Y903750D01*
X1844825Y903375D01*
X1844950Y903042D01*
X1845117Y902792D01*
X1845367Y902583D01*
X1845700Y902500D01*
X1846033Y902583D01*
X1846283Y902792D01*
X1846450Y903042D01*
X1846575Y903375D01*
X1846617Y903750D01*
X1846575Y904125D01*
X1846450Y904458D01*
X1846283Y904708D01*
X1846033Y904917D01*
X1845700Y905000D01*
G01X1826722Y901550D02*
Y905550D01*
X1819322D01*
G01X1845017Y859000D02*
Y861500D01*
X1846058D01*
X1846392Y861375D01*
X1846600Y861208D01*
X1846683Y860875D01*
X1846600Y860542D01*
X1846350Y860333D01*
X1846058Y860208D01*
X1845017D01*
G01X1846058D02*
X1846683Y859000D01*
G01X1848033Y859500D02*
X1848283Y859208D01*
X1848617Y859042D01*
X1848992Y859000D01*
X1849325Y859042D01*
X1849658Y859250D01*
X1849867Y859500D01*
X1849908Y859750D01*
X1849825Y860042D01*
X1849533Y860250D01*
X1849242Y860333D01*
X1848867D01*
G01X1849242D02*
X1849492Y860458D01*
X1849700Y860667D01*
X1849783Y860917D01*
X1849700Y861167D01*
X1849492Y861375D01*
X1849117Y861500D01*
X1848742Y861458D01*
X1848367Y861292D01*
G01X1851258Y861083D02*
X1851508Y861333D01*
X1851800Y861458D01*
X1852133Y861500D01*
X1852550Y861417D01*
X1852842Y861208D01*
X1852925Y860958D01*
X1852883Y860708D01*
X1852717Y860500D01*
X1851883Y860083D01*
X1851508Y859792D01*
X1851258Y859375D01*
X1851175Y859000D01*
X1852925D01*
G01X1854358Y861083D02*
X1854608Y861333D01*
X1854900Y861458D01*
X1855233Y861500D01*
X1855650Y861417D01*
X1855942Y861208D01*
X1856025Y860958D01*
X1855983Y860708D01*
X1855817Y860500D01*
X1854983Y860083D01*
X1854608Y859792D01*
X1854358Y859375D01*
X1854275Y859000D01*
X1856025D01*
G01X1835800Y913000D02*
Y910500D01*
G01X1834842Y913000D02*
X1836758D01*
G01X1838067Y910500D02*
Y913000D01*
X1839067D01*
X1839400Y912875D01*
X1839650Y912583D01*
X1839733Y912250D01*
X1839650Y911917D01*
X1839442Y911667D01*
X1839067Y911542D01*
X1838067D01*
G01X1841208Y912583D02*
X1841458Y912833D01*
X1841750Y912958D01*
X1842083Y913000D01*
X1842500Y912917D01*
X1842792Y912708D01*
X1842875Y912458D01*
X1842833Y912208D01*
X1842667Y912000D01*
X1841833Y911583D01*
X1841458Y911292D01*
X1841208Y910875D01*
X1841125Y910500D01*
X1842875D01*
G01X1845100Y913000D02*
X1844767Y912917D01*
X1844517Y912708D01*
X1844350Y912458D01*
X1844225Y912125D01*
X1844183Y911750D01*
X1844225Y911375D01*
X1844350Y911042D01*
X1844517Y910792D01*
X1844767Y910583D01*
X1845100Y910500D01*
X1845433Y910583D01*
X1845683Y910792D01*
X1845850Y911042D01*
X1845975Y911375D01*
X1846017Y911750D01*
X1845975Y912125D01*
X1845850Y912458D01*
X1845683Y912708D01*
X1845433Y912917D01*
X1845100Y913000D01*
G01X1848700Y910500D02*
Y913000D01*
X1847158Y911208D01*
X1849242D01*
G01X1885708Y972967D02*
X1885583Y972717D01*
X1885500Y972425D01*
Y972092D01*
X1885625Y971717D01*
X1885833Y971425D01*
X1886083Y971217D01*
X1886500Y971050D01*
X1886875Y971008D01*
X1887250Y971092D01*
X1887500Y971217D01*
X1887750Y971467D01*
X1887917Y971758D01*
X1888000Y972050D01*
Y972342D01*
X1887917Y972633D01*
X1887792Y972883D01*
X1887625Y973092D01*
G01X1888000Y975150D02*
X1885500D01*
X1886000Y974650D01*
G01X1888000D02*
Y975650D01*
G01Y978167D02*
X1887458Y978250D01*
X1887000Y978375D01*
X1886583Y978542D01*
X1886125Y978750D01*
X1885500Y979083D01*
Y977417D01*
G01X1886958Y980558D02*
X1886667Y980850D01*
X1886500Y981100D01*
X1886417Y981433D01*
X1886500Y981725D01*
X1886667Y981933D01*
X1886917Y982100D01*
X1887208Y982142D01*
X1887458Y982100D01*
X1887708Y981933D01*
X1887917Y981683D01*
X1888000Y981392D01*
X1887917Y981058D01*
X1887667Y980767D01*
X1887292Y980600D01*
X1886875Y980558D01*
X1886333Y980642D01*
X1886042Y980767D01*
X1885750Y980975D01*
X1885542Y981267D01*
X1885500Y981558D01*
X1885583Y981850D01*
X1885792Y982058D01*
G01X1855767Y991292D02*
X1855517Y991417D01*
X1855225Y991500D01*
X1854892D01*
X1854517Y991375D01*
X1854225Y991167D01*
X1854017Y990917D01*
X1853850Y990500D01*
X1853808Y990125D01*
X1853892Y989750D01*
X1854017Y989500D01*
X1854267Y989250D01*
X1854558Y989083D01*
X1854850Y989000D01*
X1855142D01*
X1855433Y989083D01*
X1855683Y989208D01*
X1855892Y989375D01*
G01X1857950Y989000D02*
Y991500D01*
X1857450Y991000D01*
G01Y989000D02*
X1858450D01*
G01X1861050D02*
X1861342Y989042D01*
X1861675Y989167D01*
X1861883Y989375D01*
X1861967Y989667D01*
X1861883Y989958D01*
X1861633Y990208D01*
X1861258Y990333D01*
X1860842D01*
X1860592Y990417D01*
X1860383Y990625D01*
X1860300Y990917D01*
X1860425Y991208D01*
X1860717Y991417D01*
X1861050Y991500D01*
X1861383Y991417D01*
X1861675Y991208D01*
X1861800Y990917D01*
X1861717Y990625D01*
X1861508Y990417D01*
X1861258Y990333D01*
X1860842D01*
X1860467Y990208D01*
X1860217Y989958D01*
X1860133Y989667D01*
X1860217Y989375D01*
X1860425Y989167D01*
X1860758Y989042D01*
X1861050Y989000D01*
G01X1864150D02*
Y991500D01*
X1863650Y991000D01*
G01Y989000D02*
X1864650D01*
G01X1835267Y1008792D02*
X1835017Y1008917D01*
X1834725Y1009000D01*
X1834392D01*
X1834017Y1008875D01*
X1833725Y1008667D01*
X1833517Y1008417D01*
X1833350Y1008000D01*
X1833308Y1007625D01*
X1833392Y1007250D01*
X1833517Y1007000D01*
X1833767Y1006750D01*
X1834058Y1006583D01*
X1834350Y1006500D01*
X1834642D01*
X1834933Y1006583D01*
X1835183Y1006708D01*
X1835392Y1006875D01*
G01X1837450Y1006500D02*
Y1009000D01*
X1836950Y1008500D01*
G01Y1006500D02*
X1837950D01*
G01X1840550D02*
X1840842Y1006542D01*
X1841175Y1006667D01*
X1841383Y1006875D01*
X1841467Y1007167D01*
X1841383Y1007458D01*
X1841133Y1007708D01*
X1840758Y1007833D01*
X1840342D01*
X1840092Y1007917D01*
X1839883Y1008125D01*
X1839800Y1008417D01*
X1839925Y1008708D01*
X1840217Y1008917D01*
X1840550Y1009000D01*
X1840883Y1008917D01*
X1841175Y1008708D01*
X1841300Y1008417D01*
X1841217Y1008125D01*
X1841008Y1007917D01*
X1840758Y1007833D01*
X1840342D01*
X1839967Y1007708D01*
X1839717Y1007458D01*
X1839633Y1007167D01*
X1839717Y1006875D01*
X1839925Y1006667D01*
X1840258Y1006542D01*
X1840550Y1006500D01*
G01X1842858Y1008583D02*
X1843108Y1008833D01*
X1843400Y1008958D01*
X1843733Y1009000D01*
X1844150Y1008917D01*
X1844442Y1008708D01*
X1844525Y1008458D01*
X1844483Y1008208D01*
X1844317Y1008000D01*
X1843483Y1007583D01*
X1843108Y1007292D01*
X1842858Y1006875D01*
X1842775Y1006500D01*
X1844525D01*
G01X1836000Y964017D02*
X1833500D01*
Y965058D01*
X1833625Y965392D01*
X1833792Y965600D01*
X1834125Y965683D01*
X1834458Y965600D01*
X1834667Y965350D01*
X1834792Y965058D01*
Y964017D01*
G01Y965058D02*
X1836000Y965683D01*
G01X1835500Y967033D02*
X1835792Y967283D01*
X1835958Y967617D01*
X1836000Y967992D01*
X1835958Y968325D01*
X1835750Y968658D01*
X1835500Y968867D01*
X1835250Y968908D01*
X1834958Y968825D01*
X1834750Y968533D01*
X1834667Y968242D01*
Y967867D01*
G01Y968242D02*
X1834542Y968492D01*
X1834333Y968700D01*
X1834083Y968783D01*
X1833833Y968700D01*
X1833625Y968492D01*
X1833500Y968117D01*
X1833542Y967742D01*
X1833708Y967367D01*
G01X1833917Y970258D02*
X1833667Y970508D01*
X1833542Y970800D01*
X1833500Y971133D01*
X1833583Y971550D01*
X1833792Y971842D01*
X1834042Y971925D01*
X1834292Y971883D01*
X1834500Y971717D01*
X1834917Y970883D01*
X1835208Y970508D01*
X1835625Y970258D01*
X1836000Y970175D01*
Y971925D01*
G01Y974150D02*
X1835958Y974442D01*
X1835833Y974775D01*
X1835625Y974983D01*
X1835333Y975067D01*
X1835042Y974983D01*
X1834792Y974733D01*
X1834667Y974358D01*
Y973942D01*
X1834583Y973692D01*
X1834375Y973483D01*
X1834083Y973400D01*
X1833792Y973525D01*
X1833583Y973817D01*
X1833500Y974150D01*
X1833583Y974483D01*
X1833792Y974775D01*
X1834083Y974900D01*
X1834375Y974817D01*
X1834583Y974608D01*
X1834667Y974358D01*
Y973942D01*
X1834792Y973567D01*
X1835042Y973317D01*
X1835333Y973233D01*
X1835625Y973317D01*
X1835833Y973525D01*
X1835958Y973858D01*
X1836000Y974150D01*
G01X1821000Y967800D02*
X1825000D01*
Y975200D01*
G01X1833700Y1013000D02*
Y1017000D01*
X1826300D01*
G01X1823800Y988000D02*
Y984000D01*
X1831200D01*
G01X1832000Y964017D02*
X1829500D01*
Y965058D01*
X1829625Y965392D01*
X1829792Y965600D01*
X1830125Y965683D01*
X1830458Y965600D01*
X1830667Y965350D01*
X1830792Y965058D01*
Y964017D01*
G01Y965058D02*
X1832000Y965683D01*
G01X1831500Y967033D02*
X1831792Y967283D01*
X1831958Y967617D01*
X1832000Y967992D01*
X1831958Y968325D01*
X1831750Y968658D01*
X1831500Y968867D01*
X1831250Y968908D01*
X1830958Y968825D01*
X1830750Y968533D01*
X1830667Y968242D01*
Y967867D01*
G01Y968242D02*
X1830542Y968492D01*
X1830333Y968700D01*
X1830083Y968783D01*
X1829833Y968700D01*
X1829625Y968492D01*
X1829500Y968117D01*
X1829542Y967742D01*
X1829708Y967367D01*
G01X1831500Y970133D02*
X1831792Y970383D01*
X1831958Y970717D01*
X1832000Y971092D01*
X1831958Y971425D01*
X1831750Y971758D01*
X1831500Y971967D01*
X1831250Y972008D01*
X1830958Y971925D01*
X1830750Y971633D01*
X1830667Y971342D01*
Y970967D01*
G01Y971342D02*
X1830542Y971592D01*
X1830333Y971800D01*
X1830083Y971883D01*
X1829833Y971800D01*
X1829625Y971592D01*
X1829500Y971217D01*
X1829542Y970842D01*
X1829708Y970467D01*
G01X1832000Y974150D02*
X1829500D01*
X1830000Y973650D01*
G01X1832000D02*
Y974650D01*
G01X1884000Y971217D02*
X1881500D01*
Y972258D01*
X1881625Y972592D01*
X1881792Y972800D01*
X1882125Y972883D01*
X1882458Y972800D01*
X1882667Y972550D01*
X1882792Y972258D01*
Y971217D01*
G01Y972258D02*
X1884000Y972883D01*
G01X1883500Y974233D02*
X1883792Y974483D01*
X1883958Y974817D01*
X1884000Y975192D01*
X1883958Y975525D01*
X1883750Y975858D01*
X1883500Y976067D01*
X1883250Y976108D01*
X1882958Y976025D01*
X1882750Y975733D01*
X1882667Y975442D01*
Y975067D01*
G01Y975442D02*
X1882542Y975692D01*
X1882333Y975900D01*
X1882083Y975983D01*
X1881833Y975900D01*
X1881625Y975692D01*
X1881500Y975317D01*
X1881542Y974942D01*
X1881708Y974567D01*
G01X1883500Y977333D02*
X1883792Y977583D01*
X1883958Y977917D01*
X1884000Y978292D01*
X1883958Y978625D01*
X1883750Y978958D01*
X1883500Y979167D01*
X1883250Y979208D01*
X1882958Y979125D01*
X1882750Y978833D01*
X1882667Y978542D01*
Y978167D01*
G01Y978542D02*
X1882542Y978792D01*
X1882333Y979000D01*
X1882083Y979083D01*
X1881833Y979000D01*
X1881625Y978792D01*
X1881500Y978417D01*
X1881542Y978042D01*
X1881708Y977667D01*
G01X1883625Y980433D02*
X1883833Y980683D01*
X1883958Y980975D01*
X1884000Y981350D01*
X1883917Y981725D01*
X1883750Y982017D01*
X1883458Y982225D01*
X1883125Y982267D01*
X1882792Y982183D01*
X1882583Y981975D01*
X1882417Y981683D01*
X1882375Y981392D01*
X1882417Y981100D01*
X1882583Y980725D01*
X1881500Y980850D01*
Y981975D01*
G01X1873800Y982800D02*
X1877800D01*
Y990200D01*
G01X1853917Y985100D02*
Y987600D01*
X1854958D01*
X1855292Y987475D01*
X1855500Y987308D01*
X1855583Y986975D01*
X1855500Y986642D01*
X1855250Y986433D01*
X1854958Y986308D01*
X1853917D01*
G01X1854958D02*
X1855583Y985100D01*
G01X1856933Y985600D02*
X1857183Y985308D01*
X1857517Y985142D01*
X1857892Y985100D01*
X1858225Y985142D01*
X1858558Y985350D01*
X1858767Y985600D01*
X1858808Y985850D01*
X1858725Y986142D01*
X1858433Y986350D01*
X1858142Y986433D01*
X1857767D01*
G01X1858142D02*
X1858392Y986558D01*
X1858600Y986767D01*
X1858683Y987017D01*
X1858600Y987267D01*
X1858392Y987475D01*
X1858017Y987600D01*
X1857642Y987558D01*
X1857267Y987392D01*
G01X1860033Y985600D02*
X1860283Y985308D01*
X1860617Y985142D01*
X1860992Y985100D01*
X1861325Y985142D01*
X1861658Y985350D01*
X1861867Y985600D01*
X1861908Y985850D01*
X1861825Y986142D01*
X1861533Y986350D01*
X1861242Y986433D01*
X1860867D01*
G01X1861242D02*
X1861492Y986558D01*
X1861700Y986767D01*
X1861783Y987017D01*
X1861700Y987267D01*
X1861492Y987475D01*
X1861117Y987600D01*
X1860742Y987558D01*
X1860367Y987392D01*
G01X1863342Y985392D02*
X1863633Y985183D01*
X1863967Y985100D01*
X1864300Y985183D01*
X1864592Y985433D01*
X1864800Y985808D01*
X1864883Y986183D01*
Y986642D01*
X1864800Y987017D01*
X1864592Y987350D01*
X1864342Y987517D01*
X1864050Y987600D01*
X1863717Y987517D01*
X1863467Y987350D01*
X1863300Y987100D01*
X1863217Y986767D01*
X1863300Y986475D01*
X1863508Y986183D01*
X1863758Y986017D01*
X1864050Y985975D01*
X1864383Y986058D01*
X1864633Y986267D01*
X1864883Y986642D01*
G01X1853800Y998500D02*
Y994500D01*
X1861200D01*
G01X1845500Y954017D02*
X1843000D01*
Y955058D01*
X1843125Y955392D01*
X1843292Y955600D01*
X1843625Y955683D01*
X1843958Y955600D01*
X1844167Y955350D01*
X1844292Y955058D01*
Y954017D01*
G01Y955058D02*
X1845500Y955683D01*
G01X1845000Y957033D02*
X1845292Y957283D01*
X1845458Y957617D01*
X1845500Y957992D01*
X1845458Y958325D01*
X1845250Y958658D01*
X1845000Y958867D01*
X1844750Y958908D01*
X1844458Y958825D01*
X1844250Y958533D01*
X1844167Y958242D01*
Y957867D01*
G01Y958242D02*
X1844042Y958492D01*
X1843833Y958700D01*
X1843583Y958783D01*
X1843333Y958700D01*
X1843125Y958492D01*
X1843000Y958117D01*
X1843042Y957742D01*
X1843208Y957367D01*
G01X1845500Y961550D02*
X1843000D01*
X1844792Y960008D01*
Y962092D01*
G01X1843000Y964150D02*
X1843083Y963817D01*
X1843292Y963567D01*
X1843542Y963400D01*
X1843875Y963275D01*
X1844250Y963233D01*
X1844625Y963275D01*
X1844958Y963400D01*
X1845208Y963567D01*
X1845417Y963817D01*
X1845500Y964150D01*
X1845417Y964483D01*
X1845208Y964733D01*
X1844958Y964900D01*
X1844625Y965025D01*
X1844250Y965067D01*
X1843875Y965025D01*
X1843542Y964900D01*
X1843292Y964733D01*
X1843083Y964483D01*
X1843000Y964150D01*
G01X1851000Y958300D02*
X1855000D01*
Y965700D01*
G01X1841500Y954017D02*
X1839000D01*
Y955058D01*
X1839125Y955392D01*
X1839292Y955600D01*
X1839625Y955683D01*
X1839958Y955600D01*
X1840167Y955350D01*
X1840292Y955058D01*
Y954017D01*
G01Y955058D02*
X1841500Y955683D01*
G01X1841000Y957033D02*
X1841292Y957283D01*
X1841458Y957617D01*
X1841500Y957992D01*
X1841458Y958325D01*
X1841250Y958658D01*
X1841000Y958867D01*
X1840750Y958908D01*
X1840458Y958825D01*
X1840250Y958533D01*
X1840167Y958242D01*
Y957867D01*
G01Y958242D02*
X1840042Y958492D01*
X1839833Y958700D01*
X1839583Y958783D01*
X1839333Y958700D01*
X1839125Y958492D01*
X1839000Y958117D01*
X1839042Y957742D01*
X1839208Y957367D01*
G01X1841500Y961550D02*
X1839000D01*
X1840792Y960008D01*
Y962092D01*
G01X1839417Y963358D02*
X1839167Y963608D01*
X1839042Y963900D01*
X1839000Y964233D01*
X1839083Y964650D01*
X1839292Y964942D01*
X1839542Y965025D01*
X1839792Y964983D01*
X1840000Y964817D01*
X1840417Y963983D01*
X1840708Y963608D01*
X1841125Y963358D01*
X1841500Y963275D01*
Y965025D01*
G01X1846500Y958300D02*
X1850500D01*
Y965700D01*
G01X1865000D02*
X1861000D01*
Y958300D01*
G01X1835017Y978500D02*
Y981000D01*
X1836058D01*
X1836392Y980875D01*
X1836600Y980708D01*
X1836683Y980375D01*
X1836600Y980042D01*
X1836350Y979833D01*
X1836058Y979708D01*
X1835017D01*
G01X1836058D02*
X1836683Y978500D01*
G01X1838033Y979000D02*
X1838283Y978708D01*
X1838617Y978542D01*
X1838992Y978500D01*
X1839325Y978542D01*
X1839658Y978750D01*
X1839867Y979000D01*
X1839908Y979250D01*
X1839825Y979542D01*
X1839533Y979750D01*
X1839242Y979833D01*
X1838867D01*
G01X1839242D02*
X1839492Y979958D01*
X1839700Y980167D01*
X1839783Y980417D01*
X1839700Y980667D01*
X1839492Y980875D01*
X1839117Y981000D01*
X1838742Y980958D01*
X1838367Y980792D01*
G01X1842550Y978500D02*
Y981000D01*
X1841008Y979208D01*
X1843092D01*
G01X1845650Y978500D02*
Y981000D01*
X1844108Y979208D01*
X1846192D01*
G01X1837800Y988500D02*
Y984500D01*
X1845200D01*
G01X1833517Y1002500D02*
Y1005000D01*
X1834558D01*
X1834892Y1004875D01*
X1835100Y1004708D01*
X1835183Y1004375D01*
X1835100Y1004042D01*
X1834850Y1003833D01*
X1834558Y1003708D01*
X1833517D01*
G01X1834558D02*
X1835183Y1002500D01*
G01X1836533Y1003000D02*
X1836783Y1002708D01*
X1837117Y1002542D01*
X1837492Y1002500D01*
X1837825Y1002542D01*
X1838158Y1002750D01*
X1838367Y1003000D01*
X1838408Y1003250D01*
X1838325Y1003542D01*
X1838033Y1003750D01*
X1837742Y1003833D01*
X1837367D01*
G01X1837742D02*
X1837992Y1003958D01*
X1838200Y1004167D01*
X1838283Y1004417D01*
X1838200Y1004667D01*
X1837992Y1004875D01*
X1837617Y1005000D01*
X1837242Y1004958D01*
X1836867Y1004792D01*
G01X1841050Y1002500D02*
Y1005000D01*
X1839508Y1003208D01*
X1841592D01*
G01X1842733Y1002875D02*
X1842983Y1002667D01*
X1843275Y1002542D01*
X1843650Y1002500D01*
X1844025Y1002583D01*
X1844317Y1002750D01*
X1844525Y1003042D01*
X1844567Y1003375D01*
X1844483Y1003708D01*
X1844275Y1003917D01*
X1843983Y1004083D01*
X1843692Y1004125D01*
X1843400Y1004083D01*
X1843025Y1003917D01*
X1843150Y1005000D01*
X1844275D01*
G01X1853700Y1000000D02*
Y1004000D01*
X1846300D01*
G01X1835500Y989517D02*
X1833000D01*
Y990558D01*
X1833125Y990892D01*
X1833292Y991100D01*
X1833625Y991183D01*
X1833958Y991100D01*
X1834167Y990850D01*
X1834292Y990558D01*
Y989517D01*
G01Y990558D02*
X1835500Y991183D01*
G01X1835000Y992533D02*
X1835292Y992783D01*
X1835458Y993117D01*
X1835500Y993492D01*
X1835458Y993825D01*
X1835250Y994158D01*
X1835000Y994367D01*
X1834750Y994408D01*
X1834458Y994325D01*
X1834250Y994033D01*
X1834167Y993742D01*
Y993367D01*
G01Y993742D02*
X1834042Y993992D01*
X1833833Y994200D01*
X1833583Y994283D01*
X1833333Y994200D01*
X1833125Y993992D01*
X1833000Y993617D01*
X1833042Y993242D01*
X1833208Y992867D01*
G01X1835500Y997050D02*
X1833000D01*
X1834792Y995508D01*
Y997592D01*
G01X1834458Y998858D02*
X1834167Y999150D01*
X1834000Y999400D01*
X1833917Y999733D01*
X1834000Y1000025D01*
X1834167Y1000233D01*
X1834417Y1000400D01*
X1834708Y1000442D01*
X1834958Y1000400D01*
X1835208Y1000233D01*
X1835417Y999983D01*
X1835500Y999692D01*
X1835417Y999358D01*
X1835167Y999067D01*
X1834792Y998900D01*
X1834375Y998858D01*
X1833833Y998942D01*
X1833542Y999067D01*
X1833250Y999275D01*
X1833042Y999567D01*
X1833000Y999858D01*
X1833083Y1000150D01*
X1833292Y1000358D01*
G01X1841000Y988800D02*
X1845000D01*
Y996200D01*
G01X1839017Y974000D02*
Y976500D01*
X1840058D01*
X1840392Y976375D01*
X1840600Y976208D01*
X1840683Y975875D01*
X1840600Y975542D01*
X1840350Y975333D01*
X1840058Y975208D01*
X1839017D01*
G01X1840058D02*
X1840683Y974000D01*
G01X1842033Y974500D02*
X1842283Y974208D01*
X1842617Y974042D01*
X1842992Y974000D01*
X1843325Y974042D01*
X1843658Y974250D01*
X1843867Y974500D01*
X1843908Y974750D01*
X1843825Y975042D01*
X1843533Y975250D01*
X1843242Y975333D01*
X1842867D01*
G01X1843242D02*
X1843492Y975458D01*
X1843700Y975667D01*
X1843783Y975917D01*
X1843700Y976167D01*
X1843492Y976375D01*
X1843117Y976500D01*
X1842742Y976458D01*
X1842367Y976292D01*
G01X1846550Y974000D02*
Y976500D01*
X1845008Y974708D01*
X1847092D01*
G01X1849067Y974000D02*
X1849150Y974542D01*
X1849275Y975000D01*
X1849442Y975417D01*
X1849650Y975875D01*
X1849983Y976500D01*
X1848317D01*
G01X1855200Y978000D02*
Y982000D01*
X1847800D01*
G01X1870700Y1024100D02*
X1870367Y1024142D01*
X1870075Y1024308D01*
X1869825Y1024558D01*
X1869658Y1024850D01*
X1869575Y1025183D01*
Y1025517D01*
X1869658Y1025850D01*
X1869825Y1026142D01*
X1870075Y1026392D01*
X1870367Y1026558D01*
X1870700Y1026600D01*
X1871033Y1026558D01*
X1871325Y1026392D01*
X1871575Y1026142D01*
X1871742Y1025850D01*
X1871825Y1025517D01*
Y1025183D01*
X1871742Y1024850D01*
X1871575Y1024558D01*
X1871325Y1024308D01*
X1871033Y1024142D01*
X1870700Y1024100D01*
G01X1871033Y1024767D02*
X1871533Y1024100D01*
G01X1874300D02*
Y1026600D01*
X1872758Y1024808D01*
X1874842D01*
G01X1876108Y1026183D02*
X1876358Y1026433D01*
X1876650Y1026558D01*
X1876983Y1026600D01*
X1877400Y1026517D01*
X1877692Y1026308D01*
X1877775Y1026058D01*
X1877733Y1025808D01*
X1877567Y1025600D01*
X1876733Y1025183D01*
X1876358Y1024892D01*
X1876108Y1024475D01*
X1876025Y1024100D01*
X1877775D01*
G01X1883700Y1007000D02*
X1881600Y1008800D01*
X1883700Y1011000D01*
G01X1883800Y1014600D02*
X1864600D01*
Y1003400D01*
X1883800D01*
Y1014600D01*
X1883400D01*
G01X1838000Y1034100D02*
X1837958Y1033767D01*
X1837792Y1033475D01*
X1837542Y1033225D01*
X1837250Y1033058D01*
X1836917Y1032975D01*
X1836583D01*
X1836250Y1033058D01*
X1835958Y1033225D01*
X1835708Y1033475D01*
X1835542Y1033767D01*
X1835500Y1034100D01*
X1835542Y1034433D01*
X1835708Y1034725D01*
X1835958Y1034975D01*
X1836250Y1035142D01*
X1836583Y1035225D01*
X1836917D01*
X1837250Y1035142D01*
X1837542Y1034975D01*
X1837792Y1034725D01*
X1837958Y1034433D01*
X1838000Y1034100D01*
G01X1837333Y1034433D02*
X1838000Y1034933D01*
G01Y1037700D02*
X1835500D01*
X1837292Y1036158D01*
Y1038242D01*
G01X1838000Y1040800D02*
X1835500D01*
X1837292Y1039258D01*
Y1041342D01*
G01X1839300Y1029000D02*
X1841400Y1027200D01*
X1839300Y1025000D01*
G01X1839200Y1021400D02*
X1858400D01*
Y1032600D01*
X1839200D01*
Y1021400D01*
X1839600D01*
G01X1873000Y975017D02*
X1870500D01*
Y976058D01*
X1870625Y976392D01*
X1870792Y976600D01*
X1871125Y976683D01*
X1871458Y976600D01*
X1871667Y976350D01*
X1871792Y976058D01*
Y975017D01*
G01Y976058D02*
X1873000Y976683D01*
G01X1872500Y978033D02*
X1872792Y978283D01*
X1872958Y978617D01*
X1873000Y978992D01*
X1872958Y979325D01*
X1872750Y979658D01*
X1872500Y979867D01*
X1872250Y979908D01*
X1871958Y979825D01*
X1871750Y979533D01*
X1871667Y979242D01*
Y978867D01*
G01Y979242D02*
X1871542Y979492D01*
X1871333Y979700D01*
X1871083Y979783D01*
X1870833Y979700D01*
X1870625Y979492D01*
X1870500Y979117D01*
X1870542Y978742D01*
X1870708Y978367D01*
G01X1872500Y981133D02*
X1872792Y981383D01*
X1872958Y981717D01*
X1873000Y982092D01*
X1872958Y982425D01*
X1872750Y982758D01*
X1872500Y982967D01*
X1872250Y983008D01*
X1871958Y982925D01*
X1871750Y982633D01*
X1871667Y982342D01*
Y981967D01*
G01Y982342D02*
X1871542Y982592D01*
X1871333Y982800D01*
X1871083Y982883D01*
X1870833Y982800D01*
X1870625Y982592D01*
X1870500Y982217D01*
X1870542Y981842D01*
X1870708Y981467D01*
G01X1873000Y985067D02*
X1872458Y985150D01*
X1872000Y985275D01*
X1871583Y985442D01*
X1871125Y985650D01*
X1870500Y985983D01*
Y984317D01*
G01X1879300Y1027500D02*
X1873800D01*
G01X1879300Y1035500D02*
Y1027500D01*
G01X1873800Y1035500D02*
X1879300D01*
G01X1861700D02*
X1867200D01*
G01X1861700Y1027500D02*
Y1035500D01*
G01X1867200Y1027500D02*
X1861700D01*
G01X1833000Y983000D02*
Y976000D01*
G01X1840000Y990983D02*
X1837500D01*
Y991817D01*
X1837625Y992150D01*
X1837792Y992400D01*
X1838042Y992608D01*
X1838333Y992775D01*
X1838750Y992817D01*
X1839167Y992775D01*
X1839458Y992608D01*
X1839708Y992400D01*
X1839875Y992150D01*
X1840000Y991817D01*
Y990983D01*
G01Y995000D02*
X1837500D01*
X1838000Y994500D01*
G01X1840000D02*
Y995500D01*
G01Y998100D02*
X1837500D01*
X1838000Y997600D01*
G01X1840000D02*
Y998600D01*
G01X1853000Y999000D02*
Y982900D01*
G01X1846000Y999000D02*
X1853000D01*
G01X1846000Y982900D02*
Y999000D01*
G01X1853000Y982900D02*
X1846000D01*
G01X1857400Y979000D02*
X1857067Y979042D01*
X1856775Y979208D01*
X1856525Y979458D01*
X1856358Y979750D01*
X1856275Y980083D01*
Y980417D01*
X1856358Y980750D01*
X1856525Y981042D01*
X1856775Y981292D01*
X1857067Y981458D01*
X1857400Y981500D01*
X1857733Y981458D01*
X1858025Y981292D01*
X1858275Y981042D01*
X1858442Y980750D01*
X1858525Y980417D01*
Y980083D01*
X1858442Y979750D01*
X1858275Y979458D01*
X1858025Y979208D01*
X1857733Y979042D01*
X1857400Y979000D01*
G01X1857733Y979667D02*
X1858233Y979000D01*
G01X1861000D02*
Y981500D01*
X1859458Y979708D01*
X1861542D01*
G01X1862683Y979500D02*
X1862933Y979208D01*
X1863267Y979042D01*
X1863642Y979000D01*
X1863975Y979042D01*
X1864308Y979250D01*
X1864517Y979500D01*
X1864558Y979750D01*
X1864475Y980042D01*
X1864183Y980250D01*
X1863892Y980333D01*
X1863517D01*
G01X1863892D02*
X1864142Y980458D01*
X1864350Y980667D01*
X1864433Y980917D01*
X1864350Y981167D01*
X1864142Y981375D01*
X1863767Y981500D01*
X1863392Y981458D01*
X1863017Y981292D01*
G01X1869700Y966300D02*
Y977700D01*
G01X1856300Y966300D02*
X1869700D01*
G01X1856300Y977700D02*
Y966300D01*
G01X1869700Y977700D02*
X1856300D01*
G01X1889000Y1014517D02*
X1886500D01*
Y1015558D01*
X1886625Y1015892D01*
X1886792Y1016100D01*
X1887125Y1016183D01*
X1887458Y1016100D01*
X1887667Y1015850D01*
X1887792Y1015558D01*
Y1014517D01*
G01Y1015558D02*
X1889000Y1016183D01*
G01X1888500Y1017533D02*
X1888792Y1017783D01*
X1888958Y1018117D01*
X1889000Y1018492D01*
X1888958Y1018825D01*
X1888750Y1019158D01*
X1888500Y1019367D01*
X1888250Y1019408D01*
X1887958Y1019325D01*
X1887750Y1019033D01*
X1887667Y1018742D01*
Y1018367D01*
G01Y1018742D02*
X1887542Y1018992D01*
X1887333Y1019200D01*
X1887083Y1019283D01*
X1886833Y1019200D01*
X1886625Y1018992D01*
X1886500Y1018617D01*
X1886542Y1018242D01*
X1886708Y1017867D01*
G01X1888500Y1020633D02*
X1888792Y1020883D01*
X1888958Y1021217D01*
X1889000Y1021592D01*
X1888958Y1021925D01*
X1888750Y1022258D01*
X1888500Y1022467D01*
X1888250Y1022508D01*
X1887958Y1022425D01*
X1887750Y1022133D01*
X1887667Y1021842D01*
Y1021467D01*
G01Y1021842D02*
X1887542Y1022092D01*
X1887333Y1022300D01*
X1887083Y1022383D01*
X1886833Y1022300D01*
X1886625Y1022092D01*
X1886500Y1021717D01*
X1886542Y1021342D01*
X1886708Y1020967D01*
G01X1889000Y1025150D02*
X1886500D01*
X1888292Y1023608D01*
Y1025692D01*
G01X1881000Y1045300D02*
X1889000D01*
Y1027700D01*
X1881000D01*
Y1045300D01*
G01X1857200Y1042000D02*
Y1050000D01*
X1874800D01*
Y1042000D01*
X1857200D01*
G01X1890775Y1115000D02*
Y1117500D01*
G01X1892525D02*
Y1115000D01*
G01Y1116250D02*
X1890775D01*
G01X1893833Y1115000D02*
Y1117500D01*
X1894667D01*
X1895000Y1117375D01*
X1895250Y1117208D01*
X1895458Y1116958D01*
X1895625Y1116667D01*
X1895667Y1116250D01*
X1895625Y1115833D01*
X1895458Y1115542D01*
X1895250Y1115292D01*
X1895000Y1115125D01*
X1894667Y1115000D01*
X1893833D01*
G01X1896933D02*
Y1117500D01*
X1897767D01*
X1898100Y1117375D01*
X1898350Y1117208D01*
X1898558Y1116958D01*
X1898725Y1116667D01*
X1898767Y1116250D01*
X1898725Y1115833D01*
X1898558Y1115542D01*
X1898350Y1115292D01*
X1898100Y1115125D01*
X1897767Y1115000D01*
X1896933D01*
G01X1900075Y1115333D02*
X1900408Y1115125D01*
X1900783Y1115000D01*
X1901117D01*
X1901450Y1115125D01*
X1901700Y1115333D01*
X1901825Y1115625D01*
X1901742Y1115917D01*
X1901533Y1116167D01*
X1901158Y1116333D01*
X1900658Y1116417D01*
X1900367Y1116583D01*
X1900242Y1116875D01*
X1900325Y1117167D01*
X1900533Y1117375D01*
X1900825Y1117500D01*
X1901117D01*
X1901408Y1117417D01*
X1901658Y1117208D01*
G01X1903008Y1115000D02*
X1904050Y1117500D01*
X1905092Y1115000D01*
G01X1904717Y1115875D02*
X1903383D01*
G01X1906275Y1115333D02*
X1906608Y1115125D01*
X1906983Y1115000D01*
X1907317D01*
X1907650Y1115125D01*
X1907900Y1115333D01*
X1908025Y1115625D01*
X1907942Y1115917D01*
X1907733Y1116167D01*
X1907358Y1116333D01*
X1906858Y1116417D01*
X1906567Y1116583D01*
X1906442Y1116875D01*
X1906525Y1117167D01*
X1906733Y1117375D01*
X1907025Y1117500D01*
X1907317D01*
X1907608Y1117417D01*
X1907858Y1117208D01*
G01X1910250Y1115000D02*
Y1117500D01*
X1909750Y1117000D01*
G01Y1115000D02*
X1910750D01*
G01X1913350D02*
Y1117500D01*
X1912850Y1117000D01*
G01Y1115000D02*
X1913850D01*
G01X1862967Y1062292D02*
X1862717Y1062417D01*
X1862425Y1062500D01*
X1862092D01*
X1861717Y1062375D01*
X1861425Y1062167D01*
X1861217Y1061917D01*
X1861050Y1061500D01*
X1861008Y1061125D01*
X1861092Y1060750D01*
X1861217Y1060500D01*
X1861467Y1060250D01*
X1861758Y1060083D01*
X1862050Y1060000D01*
X1862342D01*
X1862633Y1060083D01*
X1862883Y1060208D01*
X1863092Y1060375D01*
G01X1865150Y1060000D02*
Y1062500D01*
X1864650Y1062000D01*
G01Y1060000D02*
X1865650D01*
G01X1868167D02*
X1868250Y1060542D01*
X1868375Y1061000D01*
X1868542Y1061417D01*
X1868750Y1061875D01*
X1869083Y1062500D01*
X1867417D01*
G01X1870433Y1060500D02*
X1870683Y1060208D01*
X1871017Y1060042D01*
X1871392Y1060000D01*
X1871725Y1060042D01*
X1872058Y1060250D01*
X1872267Y1060500D01*
X1872308Y1060750D01*
X1872225Y1061042D01*
X1871933Y1061250D01*
X1871642Y1061333D01*
X1871267D01*
G01X1871642D02*
X1871892Y1061458D01*
X1872100Y1061667D01*
X1872183Y1061917D01*
X1872100Y1062167D01*
X1871892Y1062375D01*
X1871517Y1062500D01*
X1871142Y1062458D01*
X1870767Y1062292D01*
G01X1878208Y1085767D02*
X1878083Y1085517D01*
X1878000Y1085225D01*
Y1084892D01*
X1878125Y1084517D01*
X1878333Y1084225D01*
X1878583Y1084017D01*
X1879000Y1083850D01*
X1879375Y1083808D01*
X1879750Y1083892D01*
X1880000Y1084017D01*
X1880250Y1084267D01*
X1880417Y1084558D01*
X1880500Y1084850D01*
Y1085142D01*
X1880417Y1085433D01*
X1880292Y1085683D01*
X1880125Y1085892D01*
G01X1880500Y1087950D02*
X1878000D01*
X1878500Y1087450D01*
G01X1880500D02*
Y1088450D01*
G01Y1091050D02*
X1880458Y1091342D01*
X1880333Y1091675D01*
X1880125Y1091883D01*
X1879833Y1091967D01*
X1879542Y1091883D01*
X1879292Y1091633D01*
X1879167Y1091258D01*
Y1090842D01*
X1879083Y1090592D01*
X1878875Y1090383D01*
X1878583Y1090300D01*
X1878292Y1090425D01*
X1878083Y1090717D01*
X1878000Y1091050D01*
X1878083Y1091383D01*
X1878292Y1091675D01*
X1878583Y1091800D01*
X1878875Y1091717D01*
X1879083Y1091508D01*
X1879167Y1091258D01*
Y1090842D01*
X1879292Y1090467D01*
X1879542Y1090217D01*
X1879833Y1090133D01*
X1880125Y1090217D01*
X1880333Y1090425D01*
X1880458Y1090758D01*
X1880500Y1091050D01*
G01X1878000Y1094150D02*
X1878083Y1093817D01*
X1878292Y1093567D01*
X1878542Y1093400D01*
X1878875Y1093275D01*
X1879250Y1093233D01*
X1879625Y1093275D01*
X1879958Y1093400D01*
X1880208Y1093567D01*
X1880417Y1093817D01*
X1880500Y1094150D01*
X1880417Y1094483D01*
X1880208Y1094733D01*
X1879958Y1094900D01*
X1879625Y1095025D01*
X1879250Y1095067D01*
X1878875Y1095025D01*
X1878542Y1094900D01*
X1878292Y1094733D01*
X1878083Y1094483D01*
X1878000Y1094150D01*
G01X1876850Y1062500D02*
Y1060000D01*
G01X1875892Y1062500D02*
X1877808D01*
G01X1879117Y1060000D02*
Y1062500D01*
X1880117D01*
X1880450Y1062375D01*
X1880700Y1062083D01*
X1880783Y1061750D01*
X1880700Y1061417D01*
X1880492Y1061167D01*
X1880117Y1061042D01*
X1879117D01*
G01X1882967Y1060000D02*
X1883050Y1060542D01*
X1883175Y1061000D01*
X1883342Y1061417D01*
X1883550Y1061875D01*
X1883883Y1062500D01*
X1882217D01*
G01X1885358Y1061042D02*
X1885650Y1061333D01*
X1885900Y1061500D01*
X1886233Y1061583D01*
X1886525Y1061500D01*
X1886733Y1061333D01*
X1886900Y1061083D01*
X1886942Y1060792D01*
X1886900Y1060542D01*
X1886733Y1060292D01*
X1886483Y1060083D01*
X1886192Y1060000D01*
X1885858Y1060083D01*
X1885567Y1060333D01*
X1885400Y1060708D01*
X1885358Y1061125D01*
X1885442Y1061667D01*
X1885567Y1061958D01*
X1885775Y1062250D01*
X1886067Y1062458D01*
X1886358Y1062500D01*
X1886650Y1062417D01*
X1886858Y1062208D01*
G01X1826900Y1050500D02*
X1826567Y1050542D01*
X1826275Y1050708D01*
X1826025Y1050958D01*
X1825858Y1051250D01*
X1825775Y1051583D01*
Y1051917D01*
X1825858Y1052250D01*
X1826025Y1052542D01*
X1826275Y1052792D01*
X1826567Y1052958D01*
X1826900Y1053000D01*
X1827233Y1052958D01*
X1827525Y1052792D01*
X1827775Y1052542D01*
X1827942Y1052250D01*
X1828025Y1051917D01*
Y1051583D01*
X1827942Y1051250D01*
X1827775Y1050958D01*
X1827525Y1050708D01*
X1827233Y1050542D01*
X1826900Y1050500D01*
G01X1827233Y1051167D02*
X1827733Y1050500D01*
G01X1830500D02*
Y1053000D01*
X1828958Y1051208D01*
X1831042D01*
G01X1833100Y1053000D02*
X1832767Y1052917D01*
X1832517Y1052708D01*
X1832350Y1052458D01*
X1832225Y1052125D01*
X1832183Y1051750D01*
X1832225Y1051375D01*
X1832350Y1051042D01*
X1832517Y1050792D01*
X1832767Y1050583D01*
X1833100Y1050500D01*
X1833433Y1050583D01*
X1833683Y1050792D01*
X1833850Y1051042D01*
X1833975Y1051375D01*
X1834017Y1051750D01*
X1833975Y1052125D01*
X1833850Y1052458D01*
X1833683Y1052708D01*
X1833433Y1052917D01*
X1833100Y1053000D01*
G01X1863767Y1057953D02*
X1863517Y1058078D01*
X1863225Y1058161D01*
X1862892D01*
X1862517Y1058036D01*
X1862225Y1057828D01*
X1862017Y1057578D01*
X1861850Y1057161D01*
X1861808Y1056786D01*
X1861892Y1056411D01*
X1862017Y1056161D01*
X1862267Y1055911D01*
X1862558Y1055744D01*
X1862850Y1055661D01*
X1863142D01*
X1863433Y1055744D01*
X1863683Y1055869D01*
X1863892Y1056036D01*
G01X1865950Y1055661D02*
Y1058161D01*
X1865450Y1057661D01*
G01Y1055661D02*
X1866450D01*
G01X1868967D02*
X1869050Y1056203D01*
X1869175Y1056661D01*
X1869342Y1057078D01*
X1869550Y1057536D01*
X1869883Y1058161D01*
X1868217D01*
G01X1872650Y1055661D02*
Y1058161D01*
X1871108Y1056369D01*
X1873192D01*
G01X1859517Y1064000D02*
Y1066500D01*
X1860558D01*
X1860892Y1066375D01*
X1861100Y1066208D01*
X1861183Y1065875D01*
X1861100Y1065542D01*
X1860850Y1065333D01*
X1860558Y1065208D01*
X1859517D01*
G01X1860558D02*
X1861183Y1064000D01*
G01X1862533Y1064500D02*
X1862783Y1064208D01*
X1863117Y1064042D01*
X1863492Y1064000D01*
X1863825Y1064042D01*
X1864158Y1064250D01*
X1864367Y1064500D01*
X1864408Y1064750D01*
X1864325Y1065042D01*
X1864033Y1065250D01*
X1863742Y1065333D01*
X1863367D01*
G01X1863742D02*
X1863992Y1065458D01*
X1864200Y1065667D01*
X1864283Y1065917D01*
X1864200Y1066167D01*
X1863992Y1066375D01*
X1863617Y1066500D01*
X1863242Y1066458D01*
X1862867Y1066292D01*
G01X1865633Y1064500D02*
X1865883Y1064208D01*
X1866217Y1064042D01*
X1866592Y1064000D01*
X1866925Y1064042D01*
X1867258Y1064250D01*
X1867467Y1064500D01*
X1867508Y1064750D01*
X1867425Y1065042D01*
X1867133Y1065250D01*
X1866842Y1065333D01*
X1866467D01*
G01X1866842D02*
X1867092Y1065458D01*
X1867300Y1065667D01*
X1867383Y1065917D01*
X1867300Y1066167D01*
X1867092Y1066375D01*
X1866717Y1066500D01*
X1866342Y1066458D01*
X1865967Y1066292D01*
G01X1868858Y1065042D02*
X1869150Y1065333D01*
X1869400Y1065500D01*
X1869733Y1065583D01*
X1870025Y1065500D01*
X1870233Y1065333D01*
X1870400Y1065083D01*
X1870442Y1064792D01*
X1870400Y1064542D01*
X1870233Y1064292D01*
X1869983Y1064083D01*
X1869692Y1064000D01*
X1869358Y1064083D01*
X1869067Y1064333D01*
X1868900Y1064708D01*
X1868858Y1065125D01*
X1868942Y1065667D01*
X1869067Y1065958D01*
X1869275Y1066250D01*
X1869567Y1066458D01*
X1869858Y1066500D01*
X1870150Y1066417D01*
X1870358Y1066208D01*
G01X1845309Y1054946D02*
X1845059Y1055071D01*
X1844767Y1055154D01*
X1844434D01*
X1844059Y1055029D01*
X1843767Y1054821D01*
X1843559Y1054571D01*
X1843392Y1054154D01*
X1843350Y1053779D01*
X1843434Y1053404D01*
X1843559Y1053154D01*
X1843809Y1052904D01*
X1844100Y1052737D01*
X1844392Y1052654D01*
X1844684D01*
X1844975Y1052737D01*
X1845225Y1052862D01*
X1845434Y1053029D01*
G01X1847492Y1052654D02*
Y1055154D01*
X1846992Y1054654D01*
G01Y1052654D02*
X1847992D01*
G01X1850509D02*
X1850592Y1053196D01*
X1850717Y1053654D01*
X1850884Y1054071D01*
X1851092Y1054529D01*
X1851425Y1055154D01*
X1849759D01*
G01X1853692Y1052654D02*
X1853984Y1052696D01*
X1854317Y1052821D01*
X1854525Y1053029D01*
X1854609Y1053321D01*
X1854525Y1053612D01*
X1854275Y1053862D01*
X1853900Y1053987D01*
X1853484D01*
X1853234Y1054071D01*
X1853025Y1054279D01*
X1852942Y1054571D01*
X1853067Y1054862D01*
X1853359Y1055071D01*
X1853692Y1055154D01*
X1854025Y1055071D01*
X1854317Y1054862D01*
X1854442Y1054571D01*
X1854359Y1054279D01*
X1854150Y1054071D01*
X1853900Y1053987D01*
X1853484D01*
X1853109Y1053862D01*
X1852859Y1053612D01*
X1852775Y1053321D01*
X1852859Y1053029D01*
X1853067Y1052821D01*
X1853400Y1052696D01*
X1853692Y1052654D01*
G01X1879010Y1072353D02*
X1878885Y1072103D01*
X1878802Y1071811D01*
Y1071478D01*
X1878927Y1071103D01*
X1879135Y1070811D01*
X1879385Y1070603D01*
X1879802Y1070436D01*
X1880177Y1070394D01*
X1880552Y1070478D01*
X1880802Y1070603D01*
X1881052Y1070853D01*
X1881219Y1071144D01*
X1881302Y1071436D01*
Y1071728D01*
X1881219Y1072019D01*
X1881094Y1072269D01*
X1880927Y1072478D01*
G01X1881302Y1074536D02*
X1878802D01*
X1879302Y1074036D01*
G01X1881302D02*
Y1075036D01*
G01Y1077553D02*
X1880760Y1077636D01*
X1880302Y1077761D01*
X1879885Y1077928D01*
X1879427Y1078136D01*
X1878802Y1078469D01*
Y1076803D01*
G01X1881010Y1080028D02*
X1881219Y1080319D01*
X1881302Y1080653D01*
X1881219Y1080986D01*
X1880969Y1081278D01*
X1880594Y1081486D01*
X1880219Y1081569D01*
X1879760D01*
X1879385Y1081486D01*
X1879052Y1081278D01*
X1878885Y1081028D01*
X1878802Y1080736D01*
X1878885Y1080403D01*
X1879052Y1080153D01*
X1879302Y1079986D01*
X1879635Y1079903D01*
X1879927Y1079986D01*
X1880219Y1080194D01*
X1880385Y1080444D01*
X1880427Y1080736D01*
X1880344Y1081069D01*
X1880135Y1081319D01*
X1879760Y1081569D01*
G01X1822026Y1453167D02*
X1819526D01*
Y1454208D01*
X1819651Y1454542D01*
X1819818Y1454750D01*
X1820151Y1454833D01*
X1820484Y1454750D01*
X1820693Y1454500D01*
X1820818Y1454208D01*
Y1453167D01*
G01Y1454208D02*
X1822026Y1454833D01*
G01Y1457100D02*
X1819526D01*
X1820026Y1456600D01*
G01X1822026D02*
Y1457600D01*
G01X1821526Y1459283D02*
X1821818Y1459533D01*
X1821984Y1459867D01*
X1822026Y1460242D01*
X1821984Y1460575D01*
X1821776Y1460908D01*
X1821526Y1461117D01*
X1821276Y1461158D01*
X1820984Y1461075D01*
X1820776Y1460783D01*
X1820693Y1460492D01*
Y1460117D01*
G01Y1460492D02*
X1820568Y1460742D01*
X1820359Y1460950D01*
X1820109Y1461033D01*
X1819859Y1460950D01*
X1819651Y1460742D01*
X1819526Y1460367D01*
X1819568Y1459992D01*
X1819734Y1459617D01*
G01X1819526Y1463300D02*
X1819609Y1462967D01*
X1819818Y1462717D01*
X1820068Y1462550D01*
X1820401Y1462425D01*
X1820776Y1462383D01*
X1821151Y1462425D01*
X1821484Y1462550D01*
X1821734Y1462717D01*
X1821943Y1462967D01*
X1822026Y1463300D01*
X1821943Y1463633D01*
X1821734Y1463883D01*
X1821484Y1464050D01*
X1821151Y1464175D01*
X1820776Y1464217D01*
X1820401Y1464175D01*
X1820068Y1464050D01*
X1819818Y1463883D01*
X1819609Y1463633D01*
X1819526Y1463300D01*
G01Y1466400D02*
X1819609Y1466067D01*
X1819818Y1465817D01*
X1820068Y1465650D01*
X1820401Y1465525D01*
X1820776Y1465483D01*
X1821151Y1465525D01*
X1821484Y1465650D01*
X1821734Y1465817D01*
X1821943Y1466067D01*
X1822026Y1466400D01*
X1821943Y1466733D01*
X1821734Y1466983D01*
X1821484Y1467150D01*
X1821151Y1467275D01*
X1820776Y1467317D01*
X1820401Y1467275D01*
X1820068Y1467150D01*
X1819818Y1466983D01*
X1819609Y1466733D01*
X1819526Y1466400D01*
G01X1846543Y1471900D02*
Y1474400D01*
X1847584D01*
X1847918Y1474275D01*
X1848126Y1474108D01*
X1848209Y1473775D01*
X1848126Y1473442D01*
X1847876Y1473233D01*
X1847584Y1473108D01*
X1846543D01*
G01X1847584D02*
X1848209Y1471900D01*
G01X1849768Y1472192D02*
X1850059Y1471983D01*
X1850393Y1471900D01*
X1850726Y1471983D01*
X1851018Y1472233D01*
X1851226Y1472608D01*
X1851309Y1472983D01*
Y1473442D01*
X1851226Y1473817D01*
X1851018Y1474150D01*
X1850768Y1474317D01*
X1850476Y1474400D01*
X1850143Y1474317D01*
X1849893Y1474150D01*
X1849726Y1473900D01*
X1849643Y1473567D01*
X1849726Y1473275D01*
X1849934Y1472983D01*
X1850184Y1472817D01*
X1850476Y1472775D01*
X1850809Y1472858D01*
X1851059Y1473067D01*
X1851309Y1473442D01*
G01X1853493Y1471900D02*
X1853576Y1472442D01*
X1853701Y1472900D01*
X1853868Y1473317D01*
X1854076Y1473775D01*
X1854409Y1474400D01*
X1852743D01*
G01X1856593Y1471900D02*
X1856676Y1472442D01*
X1856801Y1472900D01*
X1856968Y1473317D01*
X1857176Y1473775D01*
X1857509Y1474400D01*
X1855843D01*
G01X1831526Y1476850D02*
X1836726D01*
G01X1831526Y1469850D02*
X1839326D01*
G01X1831526Y1476850D02*
Y1469850D01*
G01X1844926Y1476850D02*
X1836226D01*
G01X1844926Y1469850D02*
Y1476850D01*
G01X1838526Y1469850D02*
X1844926D01*
G01X1832743Y1457800D02*
Y1460300D01*
X1833784D01*
X1834118Y1460175D01*
X1834326Y1460008D01*
X1834409Y1459675D01*
X1834326Y1459342D01*
X1834076Y1459133D01*
X1833784Y1459008D01*
X1832743D01*
G01X1833784D02*
X1834409Y1457800D01*
G01X1835968Y1458092D02*
X1836259Y1457883D01*
X1836593Y1457800D01*
X1836926Y1457883D01*
X1837218Y1458133D01*
X1837426Y1458508D01*
X1837509Y1458883D01*
Y1459342D01*
X1837426Y1459717D01*
X1837218Y1460050D01*
X1836968Y1460217D01*
X1836676Y1460300D01*
X1836343Y1460217D01*
X1836093Y1460050D01*
X1835926Y1459800D01*
X1835843Y1459467D01*
X1835926Y1459175D01*
X1836134Y1458883D01*
X1836384Y1458717D01*
X1836676Y1458675D01*
X1837009Y1458758D01*
X1837259Y1458967D01*
X1837509Y1459342D01*
G01X1839776Y1457800D02*
X1840068Y1457842D01*
X1840401Y1457967D01*
X1840609Y1458175D01*
X1840693Y1458467D01*
X1840609Y1458758D01*
X1840359Y1459008D01*
X1839984Y1459133D01*
X1839568D01*
X1839318Y1459217D01*
X1839109Y1459425D01*
X1839026Y1459717D01*
X1839151Y1460008D01*
X1839443Y1460217D01*
X1839776Y1460300D01*
X1840109Y1460217D01*
X1840401Y1460008D01*
X1840526Y1459717D01*
X1840443Y1459425D01*
X1840234Y1459217D01*
X1839984Y1459133D01*
X1839568D01*
X1839193Y1459008D01*
X1838943Y1458758D01*
X1838859Y1458467D01*
X1838943Y1458175D01*
X1839151Y1457967D01*
X1839484Y1457842D01*
X1839776Y1457800D01*
G01X1842876Y1460300D02*
X1842543Y1460217D01*
X1842293Y1460008D01*
X1842126Y1459758D01*
X1842001Y1459425D01*
X1841959Y1459050D01*
X1842001Y1458675D01*
X1842126Y1458342D01*
X1842293Y1458092D01*
X1842543Y1457883D01*
X1842876Y1457800D01*
X1843209Y1457883D01*
X1843459Y1458092D01*
X1843626Y1458342D01*
X1843751Y1458675D01*
X1843793Y1459050D01*
X1843751Y1459425D01*
X1843626Y1459758D01*
X1843459Y1460008D01*
X1843209Y1460217D01*
X1842876Y1460300D01*
G01X1845026Y1462100D02*
X1839826D01*
G01X1845026Y1469100D02*
X1837226D01*
G01X1845026Y1462100D02*
Y1469100D01*
G01X1831626Y1462100D02*
X1840326D01*
G01X1831626Y1469100D02*
Y1462100D01*
G01X1838026Y1469100D02*
X1831626D01*
G01X1866534Y1487200D02*
Y1489700D01*
X1868118D01*
G01X1867534Y1488492D02*
X1866534D01*
G01X1869593Y1489700D02*
Y1487200D01*
X1871259D01*
G01X1874359D02*
X1872693D01*
Y1489700D01*
X1874359D01*
G01X1873693Y1488492D02*
X1872693D01*
G01X1875709Y1487200D02*
Y1489700D01*
X1876543D01*
X1876876Y1489575D01*
X1877126Y1489408D01*
X1877334Y1489158D01*
X1877501Y1488867D01*
X1877543Y1488450D01*
X1877501Y1488033D01*
X1877334Y1487742D01*
X1877126Y1487492D01*
X1876876Y1487325D01*
X1876543Y1487200D01*
X1875709D01*
G01X1880226D02*
Y1489700D01*
X1878684Y1487908D01*
X1880768D01*
G01X1863225Y1479118D02*
X1833625D01*
Y1516718D01*
X1863225D01*
Y1479118D01*
G01X1855330Y1494328D02*
X1862030D01*
G01X1850230D02*
X1846130D01*
G01X1855330Y1499428D02*
X1850230Y1494328D01*
G01X1855330Y1489228D02*
Y1499428D01*
G01X1850230Y1494328D02*
X1855330Y1489228D01*
G01X1841030Y1499428D02*
X1846130Y1494328D01*
G01X1841030Y1489228D02*
Y1499428D01*
G01X1846130Y1494328D02*
X1841030Y1489228D01*
G01Y1494328D02*
X1837330D01*
G01X1850230Y1497128D02*
Y1490728D01*
G01X1846130Y1497128D02*
Y1490728D01*
G01X1821126Y1479265D02*
Y1482135D01*
G54D12*
G01X63500Y77600D02*
X69500D01*
G01X58000Y138000D02*
Y143000D01*
G01X96500Y166500D02*
X91500D01*
G01X64979Y256480D02*
Y251180D01*
X75179D01*
Y256480D01*
G01X63500Y530100D02*
X69500D01*
G01X58000Y590500D02*
Y595500D01*
G01X96500Y619000D02*
X91500D01*
G01X64979Y709236D02*
Y703936D01*
X75179D01*
Y709236D01*
G01X76290Y884367D02*
Y879367D01*
G01Y876706D02*
Y871706D01*
G01X63500Y983100D02*
X69500D01*
G01X58000Y1043500D02*
Y1048500D01*
G01X96500Y1072000D02*
X91500D01*
G01X140661Y37096D02*
Y44796D01*
G01X182000Y138000D02*
Y143000D01*
G01X189191Y256480D02*
Y251180D01*
X199391D01*
Y256480D01*
G01X174117Y446631D02*
Y441631D01*
G01Y438970D02*
Y433970D01*
G01X187500Y530100D02*
X193500D01*
G01X182000Y590500D02*
Y595500D01*
G01X189191Y709236D02*
Y703936D01*
X199391D01*
Y709236D01*
G01X188000Y983100D02*
X194000D01*
G01X182500Y1043500D02*
Y1048500D01*
G01X177374Y1398300D02*
X171374D01*
G01X135374Y1460500D02*
Y1467500D01*
G01Y1442000D02*
Y1449000D01*
G01X116109Y1482600D02*
X121849D01*
G01X204900Y48200D02*
Y54200D01*
G01X221000Y166500D02*
X216000D01*
G01X221000Y619000D02*
X216000D01*
G01X221000Y1072000D02*
X216000D01*
G01X312000Y77600D02*
X318000D01*
G01X306500Y138000D02*
Y143000D01*
G01X345000Y166500D02*
X340000D01*
G01X313404Y256480D02*
Y251180D01*
X323604D01*
Y256480D01*
G01X312000Y530100D02*
X318000D01*
G01X306500Y590500D02*
Y595500D01*
G01X345000Y619000D02*
X340000D01*
G01X313404Y709236D02*
Y703936D01*
X323604D01*
Y709236D01*
G01X312000Y983100D02*
X318000D01*
G01X306500Y1043500D02*
Y1048500D01*
G01X345000Y1072000D02*
X340000D01*
G01X466941Y-145664D02*
Y-225664D01*
G01D02*
X1593241D01*
G01X462941Y-129664D02*
G02I-12000J0D01*
G01X457791D02*
G02I-6850J0D01*
G01X450941Y-145664D02*
Y-113664D01*
G01X466941Y-129664D02*
X434941D01*
G01X466941Y-145664D02*
X1593241D01*
G01X466941Y-181164D02*
X1593241D01*
G01X453400Y48500D02*
Y54500D01*
G01X430500Y138000D02*
Y143000D01*
G01X469500Y166500D02*
X464500D01*
G01X437617Y256480D02*
Y251180D01*
X447817D01*
Y256480D01*
G01X436000Y530100D02*
X442000D01*
G01X430500Y590500D02*
Y595500D01*
G01X469500Y619000D02*
X464500D01*
G01X437617Y709236D02*
Y703936D01*
X447817D01*
Y709236D01*
G01X436000Y983100D02*
X442000D01*
G01X430500Y1043500D02*
Y1048500D01*
G01X469500Y1072000D02*
X464500D01*
G01X424213Y1435948D02*
Y1410748D01*
G01X560500Y77600D02*
X566500D01*
G01X555000Y138000D02*
Y143000D01*
G01X561829Y256480D02*
Y251180D01*
X572029D01*
Y256480D01*
G01X560500Y530100D02*
X566500D01*
G01X555000Y590500D02*
Y595500D01*
G01X561829Y709236D02*
Y703936D01*
X572029D01*
Y709236D01*
G01X560500Y983100D02*
X566500D01*
G01X555000Y1043500D02*
Y1048500D01*
G01X521000Y1453774D02*
X514000D01*
G01X531700Y1466100D02*
X538700D01*
G01X593500Y166500D02*
X588500D01*
G01X593500Y619000D02*
X588500D01*
G01X593500Y1072000D02*
X588500D01*
G01X701900Y48300D02*
Y54300D01*
G01X679000Y138000D02*
Y143000D01*
G01X717800Y166500D02*
X712800D01*
G01X686042Y256480D02*
Y251180D01*
X696242D01*
Y256480D01*
G01X684500Y530100D02*
X690500D01*
G01X679000Y590500D02*
Y595500D01*
G01X717800Y619000D02*
X712800D01*
G01X686042Y709236D02*
Y703936D01*
X696242D01*
Y709236D01*
G01X684500Y983100D02*
X690500D01*
G01X679000Y1043500D02*
Y1048500D01*
G01X717800Y1072000D02*
X712800D01*
G01X742067Y1468534D02*
X747807D01*
G01X805741Y-145664D02*
Y-225664D01*
G01X863490Y647550D02*
X853990Y647540D01*
G01X829300Y775640D02*
X838800Y775650D01*
G01X865000Y807360D02*
X855500Y807350D01*
G01X834500Y887640D02*
X844000Y887650D01*
G01X830110Y966430D02*
X830120Y956930D01*
G01X943241Y-145664D02*
Y-225664D01*
G01X951500Y767160D02*
X942000Y767150D01*
G01X943770Y857130D02*
Y865130D01*
G01X920180Y906464D02*
X920190Y896964D01*
G01X925500Y1193500D02*
X916500D01*
G01X947100Y1362250D02*
X921900D01*
G01X1000400Y852230D02*
Y860230D01*
G01X1053100Y1413500D02*
Y1407500D01*
G01X1005118Y1468865D02*
X1010118D01*
G01X1058241Y-145664D02*
Y-225664D01*
G01X1073047Y370790D02*
Y387390D01*
G01X1089950Y1310700D02*
X1098300D01*
G01X1109600Y1493189D02*
Y1498189D01*
X1089700D01*
Y1493189D01*
G01X1225741Y-145664D02*
Y-225664D01*
G01X1235648Y256480D02*
Y251180D01*
X1245848D01*
Y256480D01*
G01X1235648Y709236D02*
Y703936D01*
X1245848D01*
Y709236D01*
G01X1217450Y1302483D02*
Y1310683D01*
G01X1184244Y1302483D02*
Y1310683D01*
G01X1173812Y1402473D02*
X1182812D01*
G01X1314900Y72500D02*
X1320900D01*
G01X1302500Y177000D02*
X1307500D01*
G01X1310500D02*
X1315500D01*
G01X1336100Y530000D02*
Y524000D01*
G01X1302500Y630000D02*
X1307500D01*
G01X1310500D02*
X1315500D01*
G01X1336100Y982500D02*
Y976500D01*
G01X1302500Y1082500D02*
X1307500D01*
G01X1310500D02*
X1315500D01*
G01X1316500Y1398300D02*
X1310500D01*
G01X1282374Y1460500D02*
Y1467500D01*
G01Y1442000D02*
Y1449000D01*
G01X1262409Y1487400D02*
X1268149D01*
G01X1395741Y-145664D02*
Y-225664D01*
G01X1426500Y177000D02*
X1431500D01*
G01X1434500D02*
X1439500D01*
G01X1359861Y256480D02*
Y251180D01*
X1370061D01*
Y256480D01*
G01X1426500Y630000D02*
X1431500D01*
G01X1434500D02*
X1439500D01*
G01X1359861Y709236D02*
Y703936D01*
X1370061D01*
Y709236D01*
G01X1426500Y1082500D02*
X1431500D01*
G01X1434500D02*
X1439500D01*
G01X1460100Y77000D02*
Y71000D01*
G01X1484073Y256480D02*
Y251180D01*
X1494273D01*
Y256480D01*
G01X1460100Y530000D02*
Y524000D01*
G01X1484073Y709236D02*
Y703936D01*
X1494273D01*
Y709236D01*
G01X1460100Y982500D02*
Y976500D01*
G01X1476400Y1389700D02*
X1682300D01*
Y1316100D01*
X1473400D01*
Y1389700D01*
X1476400D01*
G01X1593241Y-145664D02*
Y-225664D01*
G01X1621241Y-129664D02*
G02I-12000J0D01*
G01X1616091D02*
G02I-6850J0D01*
G01X1609241Y-145664D02*
Y-113664D01*
G01X1625241Y-129664D02*
X1593241D01*
G01X1567000Y72600D02*
X1573000D01*
G01X1551000Y177000D02*
X1556000D01*
G01X1559000D02*
X1564000D01*
G01X1608286Y256480D02*
Y251180D01*
X1618486D01*
Y256480D01*
G01X1584600Y530000D02*
Y524000D01*
G01X1551000Y630000D02*
X1556000D01*
G01X1559000D02*
X1564000D01*
G01X1608286Y709236D02*
Y703936D01*
X1618486D01*
Y709236D01*
G01X1584600Y982500D02*
Y976500D01*
G01X1551000Y1082500D02*
X1556000D01*
G01X1559000D02*
X1564000D01*
G01X1708600Y77000D02*
Y71000D01*
G01X1675000Y177000D02*
X1680000D01*
G01X1683000D02*
X1688000D01*
G01X1716886Y450049D02*
Y445049D01*
G01Y442388D02*
Y437388D01*
G01X1708600Y530000D02*
Y524000D01*
G01X1675000Y630000D02*
X1680000D01*
G01X1683000D02*
X1688000D01*
G01X1708600Y982500D02*
Y976500D01*
G01X1675000Y1082500D02*
X1680000D01*
G01X1683000D02*
X1688000D01*
G01X1704626Y1398300D02*
X1698626D01*
G01X1662626Y1460500D02*
Y1467500D01*
G01Y1442000D02*
Y1449000D01*
G01X1808181Y35796D02*
Y43496D01*
G01X1799000Y177000D02*
X1804000D01*
G01X1807000D02*
X1812000D01*
G01X1732498Y256480D02*
Y251180D01*
X1742698D01*
Y256480D01*
G01X1799000Y630000D02*
X1804000D01*
G01X1807000D02*
X1812000D01*
G01X1732498Y709236D02*
Y703936D01*
X1742698D01*
Y709236D01*
G01X1791290Y884367D02*
Y879367D01*
G01Y876706D02*
Y871706D01*
G01X1799000Y1082500D02*
X1804000D01*
G01X1807000D02*
X1812000D01*
G01X1810126Y1479265D02*
Y1473525D01*
G01X1831500Y97400D02*
Y91400D01*
G01X1865800Y34900D02*
X1871800D01*
G01X1849500Y137500D02*
Y142500D01*
G01X1888500Y166000D02*
X1883500D01*
G01X1856711Y256480D02*
Y251180D01*
X1866911D01*
Y256480D01*
G01X1832600Y530000D02*
Y524000D01*
G01X1846500Y545600D02*
X1852500D01*
G01X1849500Y590500D02*
Y595500D01*
G01X1888300Y619000D02*
X1883300D01*
G01X1856711Y709236D02*
Y703936D01*
X1866911D01*
Y709236D01*
G01X1832600Y982500D02*
Y976500D01*
G01X1846500Y998600D02*
X1852500D01*
G01X1849500Y1043500D02*
Y1048500D01*
G01X1888463Y1072086D02*
X1883463D01*
G54D22*
G01X79500Y131000D02*
Y135000D01*
G01X93500Y179000D02*
X97500D01*
G01X80367Y391346D02*
X81467D01*
G01X77667D02*
X78767D01*
G01X85367D02*
X86467D01*
G01X82667D02*
X83767D01*
G01X79400Y583500D02*
Y587500D01*
G01X93500Y631500D02*
X97500D01*
G01X74300Y843500D02*
X75400D01*
G01X71600D02*
X72700D01*
G01X69300D02*
X70400D01*
G01X66600D02*
X67700D01*
G01X97263Y901525D02*
Y905525D01*
G01X96063Y883125D02*
X97163D01*
G01X93363D02*
X94463D01*
G01X79300Y1036400D02*
Y1040400D01*
G01X93500Y1084500D02*
X97500D01*
G01X147700Y31300D02*
Y27300D01*
G01X139700Y129100D02*
X138600D01*
G01X142400D02*
X141300D01*
G01X193890Y445389D02*
X194990D01*
G01X191190D02*
X192290D01*
G01X140500Y595300D02*
Y596400D01*
G01Y592600D02*
Y593700D01*
G01X191800Y843500D02*
X192900D01*
G01X189100D02*
X190200D01*
G01X194100D02*
X195200D01*
G01X140500Y1045600D02*
Y1046700D01*
G01Y1048300D02*
Y1049400D01*
G01X141874Y1457800D02*
Y1458900D01*
G01Y1455100D02*
Y1456200D01*
G01Y1437700D02*
Y1436600D01*
G01Y1440400D02*
Y1439300D01*
G01X203800Y131000D02*
Y135000D01*
G01X217500Y179000D02*
X221500D01*
G01X264200Y129200D02*
X263100D01*
G01X266900D02*
X265800D01*
G01X195090Y463789D02*
Y467789D01*
G01X214000Y391000D02*
X215100D01*
G01X211300D02*
X212400D01*
G01X219000D02*
X220100D01*
G01X216300D02*
X217400D01*
G01X203800Y583500D02*
Y587500D01*
G01X217500Y631500D02*
X221500D01*
G01X264500Y595300D02*
Y596400D01*
G01Y592600D02*
Y593700D01*
G01X196800Y843500D02*
X197900D01*
G01X203900Y1036500D02*
Y1040500D01*
G01X264200Y1045600D02*
Y1046700D01*
G01X218000Y1084500D02*
X222000D01*
G01X264200Y1048300D02*
Y1049400D01*
G01X225374Y1432000D02*
Y1428000D01*
G01X328100Y131000D02*
Y135000D01*
G01X342000Y179000D02*
X346000D01*
G01X316300Y391000D02*
X317400D01*
G01X313600D02*
X314700D01*
G01X321300D02*
X322400D01*
G01X318600D02*
X319700D01*
G01X328100Y583500D02*
Y587500D01*
G01X342000Y631500D02*
X346000D01*
G01X316300Y843500D02*
X317400D01*
G01X313600D02*
X314700D01*
G01X321300D02*
X322400D01*
G01X318600D02*
X319700D01*
G01X327900Y1036500D02*
Y1040500D01*
G01X342000Y1084500D02*
X346000D01*
G01X452100Y131000D02*
Y135000D01*
G01X466000Y179000D02*
X470000D01*
G01X388200Y129400D02*
X387100D01*
G01X390900D02*
X389800D01*
G01X440800Y391000D02*
X441900D01*
G01X438100D02*
X439200D01*
G01X445800D02*
X446900D01*
G01X443100D02*
X444200D01*
G01X452400Y583500D02*
Y587500D01*
G01X466000Y631500D02*
X470000D01*
G01X389000Y595300D02*
Y596400D01*
G01Y592600D02*
Y593700D01*
G01X445800Y843500D02*
X446900D01*
G01X443100D02*
X444200D01*
G01X440800D02*
X441900D01*
G01X438100D02*
X439200D01*
G01X451900Y1036500D02*
Y1040500D01*
G01X389000Y1045600D02*
Y1046700D01*
G01X466000Y1084500D02*
X470000D01*
G01X389000Y1048300D02*
Y1049400D01*
G01X576600Y131000D02*
Y135000D01*
G01X512800Y129300D02*
X511700D01*
G01X515500D02*
X514400D01*
G01X564800Y391000D02*
X565900D01*
G01X562100D02*
X563200D01*
G01X569800D02*
X570900D01*
G01X567100D02*
X568200D01*
G01X576500Y583500D02*
Y587500D01*
G01X513000Y595300D02*
Y596400D01*
G01Y592600D02*
Y593700D01*
G01X564800Y843500D02*
X565900D01*
G01X562100D02*
X563200D01*
G01X569800D02*
X570900D01*
G01X567100D02*
X568200D01*
G01X576500Y1036500D02*
Y1040500D01*
G01X513000Y1045600D02*
Y1046700D01*
G01Y1048300D02*
Y1049400D01*
G01X526334Y1430729D02*
X530334D01*
G01X507500Y1466300D02*
Y1467400D01*
G01Y1463600D02*
Y1464700D01*
G01X527400Y1459600D02*
X526300D01*
G01X530100D02*
X529000D01*
G01X590500Y179000D02*
X594500D01*
G01X636500Y129300D02*
X635400D01*
G01X639200D02*
X638100D01*
G01X590500Y631500D02*
X594500D01*
G01X637500Y595300D02*
Y596400D01*
G01Y592600D02*
Y593700D01*
G01Y1045600D02*
Y1046700D01*
G01X590500Y1084500D02*
X594500D01*
G01X637500Y1048300D02*
Y1049400D01*
G01X649295Y1427919D02*
X653295D01*
G01X665000Y1446500D02*
Y1450500D01*
G01X653295Y1438419D02*
X649295D01*
G01X700800Y131000D02*
Y135000D01*
G01X714500Y179000D02*
X718500D01*
G01X747600Y140100D02*
X746500D01*
G01X750300D02*
X749200D01*
G01X681300Y391000D02*
X682400D01*
G01X678600D02*
X679700D01*
G01X686300D02*
X687400D01*
G01X683600D02*
X684700D01*
G01X700800Y583500D02*
Y587500D01*
G01X714500Y631500D02*
X718500D01*
G01X751700Y591000D02*
X750600D01*
G01X754400D02*
X753300D01*
G01X681300Y843500D02*
X682400D01*
G01X678600D02*
X679700D01*
G01X686300D02*
X687400D01*
G01X683600D02*
X684700D01*
G01X700700Y1036500D02*
Y1040500D01*
G01X714500Y1084500D02*
X718500D01*
G01X751700Y1051500D02*
X750600D01*
G01X754400D02*
X753300D01*
G01X678500Y1426500D02*
X674500D01*
G01X839490Y643690D02*
Y639690D01*
G01X837200Y802500D02*
Y798500D01*
G01X836470Y939430D02*
X840470D01*
G01X859858Y1394892D02*
Y1390892D01*
G01X930000Y761320D02*
Y757320D01*
G01X864600Y777100D02*
Y781100D01*
G01X869500Y894000D02*
Y890000D01*
G01X931500Y882000D02*
Y878000D01*
G01X942000Y892000D02*
Y896000D01*
G01X904000Y1193500D02*
X925500D01*
G01X909500Y1197000D02*
X906000Y1193500D01*
G01X909500Y1197000D02*
X913000Y1193500D01*
G01X915000Y1220000D02*
Y1193500D01*
X916500D01*
G01X904000Y1220000D02*
X915000D01*
G01X904000Y1193500D02*
Y1220000D01*
G01X956738Y1415818D02*
X960738D01*
G01Y1426318D02*
X956738D01*
G01X969118Y532117D02*
Y536117D01*
G01X981341Y565811D02*
Y561811D01*
G01X1012950Y840360D02*
Y844360D01*
G01X1000000Y1117000D02*
X996000D01*
G01X1007400Y1130100D02*
Y1131200D01*
G01Y1127400D02*
Y1128500D01*
G01X985943Y1414399D02*
X981943D01*
G01X1029734Y1389632D02*
Y1393632D01*
G01X1047700Y1417800D02*
Y1418900D01*
G01Y1415100D02*
Y1416200D01*
G01X972443Y1434399D02*
Y1438399D01*
G01X1042127Y1429500D02*
X1038127D01*
G01X1040550Y1481114D02*
Y1482214D01*
G01Y1478414D02*
Y1479514D01*
G01X1129215Y1313070D02*
X1133215D01*
G01X1110000Y1325500D02*
Y1329500D01*
G01X1112000Y1352000D02*
Y1356000D01*
G01X1244300Y386500D02*
X1245400D01*
G01X1241600D02*
X1242700D01*
G01X1239262Y839188D02*
X1240362D01*
G01X1236562D02*
X1237662D01*
G01X1244262D02*
X1245362D01*
G01X1241562D02*
X1242662D01*
G01X1211033Y1310944D02*
X1215033D01*
G01X1178009Y1311153D02*
X1182009D01*
G01X1195312Y1402473D02*
X1173812D01*
G01X1189812Y1398973D02*
X1193312Y1402473D01*
G01X1189812Y1398973D02*
X1186312Y1402473D01*
G01X1184312Y1375973D02*
Y1402473D01*
X1182812D01*
G01X1195312Y1375973D02*
X1184312D01*
G01X1195312Y1402473D02*
Y1375973D01*
G01X1296500Y149000D02*
X1300500D01*
G01X1296500Y178500D02*
X1300500D01*
G01X1252200Y129400D02*
X1251100D01*
G01X1254900D02*
X1253800D01*
G01X1249300Y386500D02*
X1250400D01*
G01X1246600D02*
X1247700D01*
G01X1296500Y602000D02*
X1300500D01*
G01X1296500Y631500D02*
X1300500D01*
G01X1252000Y582100D02*
X1250900D01*
G01X1254700D02*
X1253600D01*
G01X1252000Y1034700D02*
X1250900D01*
G01X1254700D02*
X1253600D01*
G01X1296500Y1054500D02*
X1300500D01*
G01X1296500Y1084000D02*
X1300500D01*
G01X1288874Y1457800D02*
Y1458900D01*
G01Y1455100D02*
Y1456200D01*
G01Y1437700D02*
Y1436600D01*
G01Y1440400D02*
Y1439300D01*
G01X1420500Y149000D02*
X1424500D01*
G01X1420500Y178500D02*
X1424500D01*
G01X1375900Y129400D02*
X1374800D01*
G01X1378600D02*
X1377500D01*
G01X1363300Y390500D02*
X1364400D01*
G01X1360600D02*
X1361700D01*
G01X1368300D02*
X1369400D01*
G01X1365600D02*
X1366700D01*
G01X1420500Y602000D02*
X1424500D01*
G01X1420500Y631500D02*
X1424500D01*
G01X1377900Y576200D02*
X1379000D01*
G01X1375200D02*
X1376300D01*
G01X1363300Y844000D02*
X1364400D01*
G01X1360600D02*
X1361700D01*
G01X1368300D02*
X1369400D01*
G01X1365600D02*
X1366700D01*
G01X1377700Y1028800D02*
X1378800D01*
G01X1375000D02*
X1376100D01*
G01X1420500Y1054500D02*
X1424500D01*
G01X1420500Y1084000D02*
X1424500D01*
G01X1372374Y1432000D02*
Y1428000D01*
G01X1500500Y129400D02*
X1499400D01*
G01X1503200D02*
X1502100D01*
G01X1487800Y390500D02*
X1488900D01*
G01X1485100D02*
X1486200D01*
G01X1492800D02*
X1493900D01*
G01X1490100D02*
X1491200D01*
G01X1501600Y575800D02*
X1502700D01*
G01X1498900D02*
X1500000D01*
G01X1487800Y843500D02*
X1488900D01*
G01X1485100D02*
X1486200D01*
G01X1492800D02*
X1493900D01*
G01X1490100D02*
X1491200D01*
G01X1501500Y1028800D02*
X1502600D01*
G01X1498800D02*
X1499900D01*
G01X1545000Y149000D02*
X1549000D01*
G01X1545000Y178500D02*
X1549000D01*
G01X1624500Y129400D02*
X1623400D01*
G01X1627200D02*
X1626100D01*
G01X1611800Y390500D02*
X1612900D01*
G01X1609100D02*
X1610200D01*
G01X1616800D02*
X1617900D01*
G01X1614100D02*
X1615200D01*
G01X1545000Y602000D02*
X1549000D01*
G01X1545000Y631500D02*
X1549000D01*
G01X1623600Y576000D02*
X1624700D01*
G01X1611800Y843500D02*
X1612900D01*
G01X1609100D02*
X1610200D01*
G01X1616800D02*
X1617900D01*
G01X1614100D02*
X1615200D01*
G01X1626200Y1028900D02*
X1627300D01*
G01X1623500D02*
X1624600D01*
G01X1545000Y1054500D02*
X1549000D01*
G01X1545000Y1084000D02*
X1549000D01*
G01X1669000Y149000D02*
X1673000D01*
G01X1669000Y178500D02*
X1673000D01*
G01X1669000Y602000D02*
X1673000D01*
G01X1669000Y631500D02*
X1673000D01*
G01X1626300Y576000D02*
X1627400D01*
G01X1669000Y1054500D02*
X1673000D01*
G01X1669000Y1084000D02*
X1673000D01*
G01X1669126Y1457800D02*
Y1458900D01*
G01Y1455100D02*
Y1456200D01*
G01Y1437700D02*
Y1436600D01*
G01Y1440400D02*
Y1439300D01*
G01X1814500Y30900D02*
Y26900D01*
G01X1793000Y149000D02*
X1797000D01*
G01X1793000Y178500D02*
X1797000D01*
G01X1748900Y128900D02*
X1747800D01*
G01X1751600D02*
X1750500D01*
G01X1737859Y467207D02*
Y471207D01*
G01X1736659Y448807D02*
X1737759D01*
G01X1733959D02*
X1735059D01*
G01X1735800Y390500D02*
X1736900D01*
G01X1733100D02*
X1734200D01*
G01X1740800D02*
X1741900D01*
G01X1738100D02*
X1739200D01*
G01X1793000Y602000D02*
X1797000D01*
G01X1793000Y631500D02*
X1797000D01*
G01X1760000Y594200D02*
Y593100D01*
G01Y596900D02*
Y595800D01*
G01X1735800Y843500D02*
X1736900D01*
G01X1733100D02*
X1734200D01*
G01X1740800D02*
X1741900D01*
G01X1738100D02*
X1739200D01*
G01X1812263Y901525D02*
Y905525D01*
G01X1811063Y883125D02*
X1812163D01*
G01X1808363D02*
X1809463D01*
G01X1750100Y1028900D02*
X1751200D01*
G01X1747400D02*
X1748500D01*
G01X1793000Y1054500D02*
X1797000D01*
G01X1793000Y1084000D02*
X1797000D01*
G01X1752626Y1432000D02*
Y1428000D01*
G01X1875298Y68122D02*
Y67022D01*
G01Y70822D02*
Y69722D01*
G01X1871400Y130500D02*
Y134500D01*
G01X1885000Y178500D02*
X1889000D01*
G01X1832900Y391300D02*
X1834000D01*
G01X1830200D02*
X1831300D01*
G01X1827900D02*
X1829000D01*
G01X1825200D02*
X1826300D01*
G01X1876900Y518200D02*
X1878000D01*
G01X1874200D02*
X1875300D01*
G01X1871500Y583500D02*
Y587500D01*
G01X1885000Y631500D02*
X1889000D01*
G01X1860300Y843500D02*
X1861400D01*
G01X1857600D02*
X1858700D01*
G01X1865300D02*
X1866400D01*
G01X1862600D02*
X1863700D01*
G01X1871200Y1036500D02*
Y1040500D01*
G01X1868300Y985200D02*
X1869400D01*
G01X1865600D02*
X1866700D01*
G01X1885000Y1084500D02*
X1889000D01*
G54D13*
G01X1143500Y729616D02*
X1149500D01*
G01X1143500Y683454D02*
X1149500D01*
Y686954D01*
G01X1076000Y729616D02*
X1082000D01*
G01Y683454D02*
X1076000D01*
Y686954D01*
G01Y772136D02*
X1082000D01*
G01X1143500Y828829D02*
X1149500D01*
G01X1143500Y772136D02*
X1149500D01*
G01X1076000Y828829D02*
X1082000D01*
G01X1076000Y885522D02*
X1082000D01*
G01X1143500Y945954D02*
X1149500D01*
Y942454D01*
G01X1143500Y885522D02*
X1149500D01*
G01X1082000Y945954D02*
X1076000D01*
Y942454D01*
G54D14*
G01X74609Y1485118D02*
G02I-3900J0D01*
G01X84609D02*
G02I-3900J0D01*
G01X94609D02*
G02I-3900J0D01*
G01X174166Y1445275D02*
G02I-6450J0D01*
G01X190702D02*
G02I-6450J0D01*
G01X207237D02*
G02I-6450J0D01*
G01X174166Y1466929D02*
G02I-6450J0D01*
G01X190702D02*
G02I-6450J0D01*
G01X207237D02*
G02I-6450J0D01*
G01X223772Y1445275D02*
G02I-6450J0D01*
G01X240308D02*
G02I-6450J0D01*
G01X223772Y1466929D02*
G02I-6450J0D01*
G01X240308D02*
G02I-6450J0D01*
G01X554481Y1445275D02*
G02I-6450J0D01*
G01X571017D02*
G02I-6450J0D01*
G01X587552D02*
G02I-6450J0D01*
G01X554481Y1466929D02*
G02I-6450J0D01*
G01X571017D02*
G02I-6450J0D01*
G01X587552D02*
G02I-6450J0D01*
G01X604087Y1445275D02*
G02I-6450J0D01*
G01X620623D02*
G02I-6450J0D01*
G01X604087Y1466929D02*
G02I-6450J0D01*
G01X620623D02*
G02I-6450J0D01*
G01X695081Y1485118D02*
G02I-3900J0D01*
G01X705081D02*
G02I-3900J0D01*
G01X715081D02*
G02I-3900J0D01*
G01X1221853D02*
G02I-3900J0D01*
G01X1231853D02*
G02I-3900J0D01*
G01X1241853D02*
G02I-3900J0D01*
G01X1321410Y1445275D02*
G02I-6450J0D01*
G01X1337946D02*
G02I-6450J0D01*
G01X1321410Y1466929D02*
G02I-6450J0D01*
G01X1337946D02*
G02I-6450J0D01*
G01X1354481Y1445275D02*
G02I-6450J0D01*
G01X1371016D02*
G02I-6450J0D01*
G01X1387552D02*
G02I-6450J0D01*
G01X1354481Y1466929D02*
G02I-6450J0D01*
G01X1371016D02*
G02I-6450J0D01*
G01X1387552D02*
G02I-6450J0D01*
G01X1701725Y1445275D02*
G02I-6450J0D01*
G01X1718261D02*
G02I-6450J0D01*
G01X1701725Y1466929D02*
G02I-6450J0D01*
G01X1718261D02*
G02I-6450J0D01*
G01X1734796Y1445275D02*
G02I-6450J0D01*
G01X1751331D02*
G02I-6450J0D01*
G01X1767867D02*
G02I-6450J0D01*
G01X1734796Y1466929D02*
G02I-6450J0D01*
G01X1751331D02*
G02I-6450J0D01*
G01X1767867D02*
G02I-6450J0D01*
G01X1842325Y1485118D02*
G02I-3900J0D01*
G01X1852325D02*
G02I-3900J0D01*
G01X1862325D02*
G02I-3900J0D01*
G54D15*
G01X124174Y52769D02*
Y49769D01*
G01Y505525D02*
Y502525D01*
G01Y958281D02*
Y955281D01*
G01X141595Y1425800D02*
Y1428650D01*
X144295D01*
G01X113274Y1448600D02*
X110424D01*
Y1451300D01*
G01X248386Y52769D02*
Y49769D01*
G01Y505525D02*
Y502525D01*
G01Y958281D02*
Y955281D01*
G01X372599Y52769D02*
Y49769D01*
G01Y505525D02*
Y502525D01*
G01Y958281D02*
Y955281D01*
G01X496811Y52769D02*
Y49769D01*
G01Y505525D02*
Y502525D01*
G01Y958281D02*
Y955281D01*
G01X621024Y52769D02*
Y49769D01*
G01Y505525D02*
Y502525D01*
G01Y958281D02*
Y955281D01*
G01X666050Y1313050D02*
Y1319150D01*
X660000D01*
G01X621350Y1392650D02*
Y1386550D01*
X627400D01*
G01X745237Y52769D02*
Y49769D01*
G01Y505525D02*
Y502525D01*
G01Y958281D02*
Y955281D01*
G01X741532Y1434334D02*
X738682D01*
Y1437034D01*
G01X814031Y1304935D02*
Y1300635D01*
X810231D01*
G01X814501Y1347441D02*
Y1343141D01*
X810701D01*
G01X814280Y1385109D02*
Y1380809D01*
X810480D01*
G01X941950Y1334450D02*
Y1328350D01*
X948000D01*
G01X1032518Y1312339D02*
Y1308039D01*
X1028718D01*
G01X1032518Y1367939D02*
Y1363639D01*
X1028718D01*
G01X1032518Y1340139D02*
Y1335839D01*
X1028718D01*
G01X1030043Y1448499D02*
X1032893D01*
Y1445799D01*
G01X1111300Y1348115D02*
X1115300D01*
Y1342315D01*
G01X1294843Y52769D02*
Y49769D01*
G01Y505525D02*
Y502525D01*
G01Y958281D02*
Y955281D01*
G01X1259574Y1453700D02*
X1256724D01*
Y1456400D01*
G01X1419056Y52769D02*
Y49769D01*
G01Y505525D02*
Y502525D01*
G01Y958281D02*
Y955281D01*
G01X1543268Y52769D02*
Y49769D01*
G01Y505525D02*
Y502525D01*
G01Y958281D02*
Y955281D01*
G01X1667481Y52769D02*
Y49769D01*
G01Y505525D02*
Y502525D01*
G01Y958281D02*
Y955281D01*
G01X1791693Y52769D02*
Y49769D01*
G01Y505525D02*
Y502525D01*
G01Y958281D02*
Y955281D01*
G01X1796626Y1453100D02*
X1793776D01*
Y1455800D01*
G01X1915906Y52769D02*
Y49769D01*
G01Y505525D02*
Y502525D01*
G01Y958281D02*
Y955281D01*
G54D16*
G01X91850Y117050D02*
Y109300D01*
G01X48150Y107950D02*
Y115700D01*
G01X91850Y569550D02*
Y561800D01*
G01X48150Y560450D02*
Y568200D01*
G01X91850Y1022550D02*
Y1014800D01*
G01X48150Y1013450D02*
Y1021200D01*
G01X170650Y82450D02*
Y90200D01*
G01X172150Y560450D02*
Y568200D01*
G01X172650Y1013450D02*
Y1021200D01*
G01X191324Y1407250D02*
Y1415000D01*
G01X215850Y117050D02*
Y109300D01*
G01Y569550D02*
Y561800D01*
G01X216350Y1022550D02*
Y1014800D01*
G01X340350Y117050D02*
Y109300D01*
G01X296650Y107950D02*
Y115700D01*
G01X340350Y569550D02*
Y561800D01*
G01X296650Y560450D02*
Y568200D01*
G01X340350Y1022550D02*
Y1014800D01*
G01X296650Y1013450D02*
Y1021200D01*
G01X304331Y1496063D02*
X322441D01*
G01X422650Y43050D02*
Y50800D01*
G01X464750Y120650D02*
Y112900D01*
G01X464350Y569550D02*
Y561800D01*
G01X420650Y560450D02*
Y568200D01*
G01X464350Y1022550D02*
Y1014800D01*
G01X420650Y1013450D02*
Y1021200D01*
G01X459449Y1496063D02*
X477559D01*
G01X545150Y107950D02*
Y115700D01*
G01Y560450D02*
Y568200D01*
G01Y1013450D02*
Y1021200D01*
G01X520885Y1441681D02*
Y1433931D01*
G01X667650Y82450D02*
Y90200D01*
G01X588850Y117050D02*
Y109300D01*
G01Y569550D02*
Y561800D01*
G01X669150Y560450D02*
Y568200D01*
G01X588850Y1022550D02*
Y1014800D01*
G01X669150Y1013450D02*
Y1021200D01*
G01X712850Y117050D02*
Y109300D01*
G01Y569550D02*
Y561800D01*
G01Y1022550D02*
Y1014800D01*
G01X783465Y23622D02*
Y54331D01*
G01X799213Y1496063D02*
X817323D01*
G01X928098Y248031D02*
X953295D01*
G01X954331Y1496063D02*
X972441D01*
G01X991970Y868600D02*
Y860850D01*
G01X1133071Y189765D02*
X1102362D01*
G01X1224409Y54331D02*
Y23622D01*
G01X1317350Y105550D02*
Y97800D01*
G01X1315150Y116450D02*
Y124200D01*
G01X1304950Y557350D02*
X1312700D01*
G01X1315650Y569450D02*
Y577200D01*
G01X1304950Y1009850D02*
X1312700D01*
G01X1315650Y1021950D02*
Y1029700D01*
G01X1330250Y1407150D02*
Y1414900D01*
G01X1428950Y104350D02*
X1436700D01*
G01X1428950Y557350D02*
X1436700D01*
G01X1428950Y1009850D02*
X1436700D01*
G01X1439650Y116450D02*
Y124200D01*
G01Y569450D02*
Y577200D01*
G01Y1021950D02*
Y1029700D01*
G01X1451575Y1496063D02*
X1469685D01*
G01X1566850Y105550D02*
Y97800D01*
G01X1593950Y123150D02*
X1586200D01*
G01X1553450Y557350D02*
X1561200D01*
G01X1564150Y569450D02*
Y577200D01*
G01X1553450Y1009850D02*
X1561200D01*
G01X1564150Y1021950D02*
Y1029700D01*
G01X1606693Y1496063D02*
X1624803D01*
G01X1677450Y104350D02*
X1685200D01*
G01X1688150Y116450D02*
Y124200D01*
G01X1677450Y557350D02*
X1685200D01*
G01X1688150Y569450D02*
Y577200D01*
G01X1677450Y1009850D02*
X1685200D01*
G01X1688150Y1021950D02*
Y1029700D01*
G01X1718476Y1407050D02*
Y1414800D01*
G01X1814150Y114650D02*
Y106900D01*
G01X1811650Y116450D02*
Y124200D01*
G01X1801450Y557350D02*
X1809200D01*
G01X1812150Y569450D02*
Y577200D01*
G01X1801450Y1009850D02*
X1809200D01*
G01X1812150Y1021950D02*
Y1029700D01*
G01X1838150Y81950D02*
Y89700D01*
G01X1883350Y116550D02*
Y108800D01*
G01Y569550D02*
Y561800D01*
G01X1839650Y560450D02*
Y568200D01*
G01X1883350Y1022550D02*
Y1014800D01*
G01X1839650Y1013450D02*
Y1021200D01*
G54D17*
G01X966321Y556271D02*
X958721D01*
G01X963963Y530157D02*
X956363D01*
G54D18*
G01X1662709Y1297797D02*
G03I-10900J0D01*
G54D19*
G01X85500Y83000D02*
Y79600D01*
G01Y535500D02*
Y532100D01*
G01Y988500D02*
Y985100D01*
G01X108874Y1477000D02*
X112274D01*
G01X201000Y70500D02*
X204400D01*
G01X209500Y535500D02*
Y532100D01*
G01X210000Y988500D02*
Y985100D01*
G01X334000Y83000D02*
Y79600D01*
G01Y535500D02*
Y532100D01*
G01Y988500D02*
Y985100D01*
G01X448000Y70500D02*
X451400D01*
G01X458000Y535500D02*
Y532100D01*
G01Y988500D02*
Y985100D01*
G01X582500Y83000D02*
Y79600D01*
G01Y535500D02*
Y532100D01*
G01Y988500D02*
Y985100D01*
G01X698000Y70500D02*
X701400D01*
G01X706500Y535500D02*
Y532100D01*
G01Y988500D02*
Y985100D01*
G01X733632Y1462234D02*
X737032D01*
G01X1297500Y55500D02*
X1300900D01*
G01X1301500Y522000D02*
X1304900D01*
G01X1301500Y974500D02*
X1304900D01*
G01X1255074Y1481400D02*
X1258474D01*
G01X1425500Y69000D02*
X1428900D01*
G01X1425500Y522000D02*
X1428900D01*
G01X1425500Y974500D02*
X1428900D01*
G01X1547000Y55500D02*
X1550400D01*
G01X1550000Y522000D02*
X1553400D01*
G01X1550000Y974500D02*
X1553400D01*
G01X1674000Y69000D02*
X1677400D01*
G01X1674000Y522000D02*
X1677400D01*
G01X1674000Y974500D02*
X1677400D01*
G01X1806300Y77700D02*
X1809700D01*
G01X1798000Y522000D02*
X1801400D01*
G01X1798000Y974500D02*
X1801400D01*
G01X1804236Y1486690D02*
Y1483290D01*
G01X1888500Y39000D02*
Y35600D01*
G01X1869000Y514000D02*
X1865600D01*
G01X1869000Y967000D02*
X1865600D01*
M02*
